CONCISE NET LIST - 1  
AGND_HSC                 C1D9             2        CAP_A_0402V-0.1UF,16V,10%,X7R,A
AGND_HSC                 C1D11            2        CAP_A_0402V-0.1UF,16V,10%,X7R,A
AGND_HSC                 C1D19            2        CAP_0402-1.0UF,16V,10%,X6S,D97A
AGND_HSC                 C1D21            2        CAP_A_0402V-0.1UF,16V,10%,X7R,A
AGND_HSC                 C1D25            2        CAP_0402-1.0UF,16V,10%,X6S,D97A
AGND_HSC                 C1D26            2        CAP_A_0402V-0.1UF,16V,10%,X7R,A
AGND_HSC                 C1D27            2        CAP_A_0402V-0.1UF,16V,10%,X7R,A
AGND_HSC                 C9P6             2        CAP_A_0402V-0.1UF,16V,10%,X7R,A
AGND_HSC                 C9P12            2        CAP_A_0402V-0.1UF,16V,10%,EMPTA
AGND_HSC                 C9P14            2        CAP_0603LF-0.033UF,50V,10%,X7RA
AGND_HSC                 C9P15            2        CAP_A_0402V-0.1UF,16V,10%,X7R,A
AGND_HSC                 C9P16            2        CAP_A_0402V-0.1UF,16V,10%,EMPTA
AGND_HSC                 C9P17            2        CAP_A_0402V-0.1UF,16V,10%,EMPTA
AGND_HSC                 EU1D2            22       ADM1278_SM-IC,G99251-001
AGND_HSC                 EU1D2            33       ADM1278_SM-IC,G99251-001
AGND_HSC                 Q1D1             1        FET_N_DUAL_SMLF-2N7002DW,FET,DA
AGND_HSC                 Q1D1             4        FET_N_DUAL_SMLF-2N7002DW,FET,DA
AGND_HSC                 R1D11            2        RES_0402-100.0K,1%,1/16W,CHIP,A
AGND_HSC                 R1D12            2        RES_0402-10.0K,1%,1/16W,CHIP,GA
AGND_HSC                 R1D18            2        RES_0402-100.0K,1%,1/16W,CHIP,A
AGND_HSC                 R1D19            2        RES_0402-10.0K,1%,1/16W,CHIP,GA
AGND_HSC                 R1D28            2        RES_0402-100.0,1%,1/16W,EMPTY,A
AGND_HSC                 R1D34            2        RES_0402-16K,1.0%,1/16W,CHIP,GA
AGND_HSC                 R1D40            2        RES_0402-40.2K,1%,1/16W,CHIP,GA
AGND_HSC                 R1D41            2        RES_0805-0.0,5%,1/8W,CHIP,G221A
AGND_HSC                 R1D42            2        RES_0402-11K,1%,1/16W,CHIP,G21A
AGND_HSC                 R1D43            2        RES_0402-7.5K,1%,1/16W,CHIP,G2A
AGND_HSC                 R9P9             2        RES_0402-10.0K,1%,1/16W,CHIP,GA
AGND_HSC                 R9P11            2        RES_0402-10.0K,1%,1/16W,CHIP,GA
AGND_HSC                 R9P12            2        RES_0402-4.99K,1%,1/16W,CHIP,GA
AGND_HSC                 R9P16            2        RES_0402-0.0,5%,1/16W,CHIP,G21A
AGND_HSC                 R9P17            2        RES_0402-150.0K,1%,1/16W,CHIP,A
AGND_HSC                 R9P19            2        RES_0402-10.0K,1%,1/16W,EMPTY,A
AGND_HSC                 R9P24            2        RES_0402-12.1K,1%,1/16W,CHIP,GA
AGND_P3V3_STBY           C2R11            2        CAP_0603-4.7UF,6.3V,10%,X6S,E1A
AGND_P3V3_STBY           C8E17            2        CAP_0402LF-1000PF,50V,10%,EMPTA
AGND_P3V3_STBY           EU8F1            11       RT8240_QFN-IC,H66262-001
AGND_P3V3_STBY           EU8F1            12       RT8240_QFN-IC,H66262-001
AGND_P3V3_STBY           EU8F1            13       RT8240_QFN-IC,H66262-001
AGND_P3V3_STBY           R8E34            2        RES_0402-10.0K,1%,1/16W,CHIP,GA
AGND_P3V3_STBY           R8E38            2        RES_0402-0.0,5%,1/16W,CHIP,G21A
AGND_P3V3_STBY           R8F9             2        RES_0402-64.9K,1%,1/16W,CHIP,GA
AGND_P3V3_STBY           R8F11            2        RES_0402-0.0,5%,1/16W,CHIP,G21A
AGND_P5V_STBY            C8E13            2        CAP_0402LF-1000PF,50V,10%,EMPTA
AGND_P5V_STBY            C8E15            2        CAP_0402LF-0.022UF,16V,10%,X7RA
AGND_P5V_STBY            C8E16            2        CAP_0402LF-270PF,50V,10%,X7R,AA
AGND_P5V_STBY            C8F1             2        CAP_0402LF-2200PF,50V,10%,X7R,A
AGND_P5V_STBY            R7E13            2        RES_0402-0.0,5%,1/16W,CHIP,G21A
AGND_P5V_STBY            R7E14            2        RES_0402-75K,1%,1/16W,CHIP,G21A
AGND_P5V_STBY            R7E16            2        RES_0402-1.37K,1%,1/16W,CHIP,GA
AGND_PVPP_ABC            C3T11            2        CAP_0603-4.7UF,6.3V,10%,X6S,E1A
AGND_PVPP_ABC            C7F8             2        CAP_0402LF-1000PF,50V,10%,EMPTA
AGND_PVPP_ABC            C7F10            2        CAP_0402-0.027UF,16V,10%,X7R,AA
AGND_PVPP_ABC            EU7F1            5        NCP3232L_SM-IC,H86355-001
AGND_PVPP_ABC            EU7F1            6        NCP3232L_SM-IC,H86355-001
AGND_PVPP_ABC            R7F11            2        RES_0402-6.34K,1%,1/16W,CHIP,GA
AGND_PVPP_ABC            R7F15            2        RES_0402-7.87K,1.0%,1/16W,CHIPA
AGND_PVPP_ABC            R7F35            2        RES_0402-0.0,5%,1/16W,CHIP,G21A
AGND_PVPP_DEF            C3M10            2        CAP_0603-4.7UF,6.3V,10%,X6S,E1A
AGND_PVPP_DEF            C7B9             2        CAP_0402LF-1000PF,50V,10%,EMPTA
AGND_PVPP_DEF            C7B11            2        CAP_0402-0.027UF,16V,10%,X7R,AA
AGND_PVPP_DEF            EU7B1            5        NCP3232L_SM-IC,H86355-001
AGND_PVPP_DEF            EU7B1            6        NCP3232L_SM-IC,H86355-001
AGND_PVPP_DEF            R7B13            2        RES_0402-6.34K,1%,1/16W,CHIP,GA
AGND_PVPP_DEF            R7B14            2        RES_0402-7.87K,1.0%,1/16W,CHIPA
AGND_PVPP_DEF            R7B20            2        RES_0402-0.0,5%,1/16W,CHIP,G21A
AGND_PVPP_GHJ            C4G7             2        CAP_0402LF-1000PF,50V,10%,EMPTA
AGND_PVPP_GHJ            C4G8             2        CAP_0402-0.027UF,16V,10%,X7R,AA
AGND_PVPP_GHJ            C6U6             2        CAP_0603-4.7UF,6.3V,10%,X6S,E1A
AGND_PVPP_GHJ            EU4G1            5        NCP3232L_SM-IC,H86355-001
AGND_PVPP_GHJ            EU4G1            6        NCP3232L_SM-IC,H86355-001
AGND_PVPP_GHJ            R4G9             2        RES_0402-6.34K,1%,1/16W,CHIP,GA
AGND_PVPP_GHJ            R4G11            2        RES_0402-7.87K,1.0%,1/16W,CHIPA
AGND_PVPP_GHJ            R4G25            2        RES_0402-0.0,5%,1/16W,CHIP,G21A
AGND_PVPP_KLM            C4B5             2        CAP_0402LF-1000PF,50V,10%,EMPTA
AGND_PVPP_KLM            C4B6             2        CAP_0402-0.027UF,16V,10%,X7R,AA
AGND_PVPP_KLM            C6L12            2        CAP_0603-4.7UF,6.3V,10%,X6S,E1A
AGND_PVPP_KLM            EU4A3            5        NCP3232L_SM-IC,H86355-001
AGND_PVPP_KLM            EU4A3            6        NCP3232L_SM-IC,H86355-001
AGND_PVPP_KLM            R4B4             2        RES_0402-6.34K,1%,1/16W,CHIP,GA
AGND_PVPP_KLM            R4B6             2        RES_0402-7.87K,1.0%,1/16W,CHIPA
AGND_PVPP_KLM            R4B14            2        RES_0402-0.0,5%,1/16W,CHIP,G21A
A_1P8_3P3_RCOMP          R8C26            1        RES_0402-100.0,1%,1/16W,CHIP,GA
A_1P8_3P3_RCOMP          U7C1             AM4      LBG_CORE_QAT_EXT_D_BGA1-IC,H91A
A_ADM1085_CEXT           C3P45            1        CAP_0402-0.047UF,25V,10%,X7R,AA
A_ADM1085_CEXT           U7D3             5        ADM1085_SMT-IC,H46130-001
A_CBOT                   C9E7             2        CAP_0402LF-0.039UF,25V,10%,X7RA
A_CBOT                   EU9E1            37       SPRINGVILLE_SM1-IC,G47144-004
A_COMP_CKMNG             EU8F2            11       ICS9FGP204_MLFP-IC,E95226-001
A_COMP_CKMNG             R8F25            1        RES_0402-475.0,1%,1/16W,CHIP,GA
A_CPU0_ABC_RCOMP0        R4P8             1        RES_0402-90.9,1%,1/16W,CHIP,G2A
A_CPU0_ABC_RCOMP0        U5D1             Y43      SKX_EXT_B_BGA1-IC,TBD
A_CPU0_ABC_RCOMP1        R4P10            1        RES_0402-90.9,1%,1/16W,CHIP,G2A
A_CPU0_ABC_RCOMP1        U5D1             AB43     SKX_EXT_B_BGA1-IC,TBD
A_CPU0_ABC_RCOMP2        R4P11            1        RES_0402-100.0,1%,1/16W,CHIP,GA
A_CPU0_ABC_RCOMP2        U5D1             AC42     SKX_EXT_B_BGA1-IC,TBD
A_CPU0_DEF_RCOMP0        R5D1             1        RES_0402-90.9,1%,1/16W,CHIP,G2A
A_CPU0_DEF_RCOMP0        U5D1             DC48     SKX_EXT_B_BGA1-IC,TBD
A_CPU0_DEF_RCOMP1        R5D2             1        RES_0402-90.9,1%,1/16W,CHIP,G2A
A_CPU0_DEF_RCOMP1        U5D1             DD47     SKX_EXT_B_BGA1-IC,TBD
A_CPU0_DEF_RCOMP2        R6D1             1        RES_0402-100.0,1%,1/16W,CHIP,GA
A_CPU0_DEF_RCOMP2        U5D1             DD49     SKX_EXT_B_BGA1-IC,TBD
A_CPU0_MCP01_RBIAS       R6D2             1        RES_0402-49.9,1%,1/16W,CHIP,G2A
A_CPU0_MCP01_RBIAS       U5D1             CT31     SKX_EXT_B_BGA1-IC,TBD
A_CPU0_MCP01_RBIAS       U5D1             CU32     SKX_EXT_B_BGA1-IC,TBD
A_CPU0_PE012_RBIAS       R4P3             1        RES_0402-49.9,1%,1/16W,CHIP,G2A
A_CPU0_PE012_RBIAS       U5D1             CL30     SKX_EXT_B_BGA1-IC,TBD
A_CPU0_PE012_RBIAS       U5D1             CN30     SKX_EXT_B_BGA1-IC,TBD
A_CPU0_PE3_RBIAS         R4P2             1        RES_0402-49.9,1%,1/16W,CHIP,G2A
A_CPU0_PE3_RBIAS         U5D1             CP29     SKX_EXT_B_BGA1-IC,TBD
A_CPU0_PE3_RBIAS         U5D1             CR30     SKX_EXT_B_BGA1-IC,TBD
A_CPU0_UPI01_RBIAS       R6D11            1        RES_0402-49.9,1%,1/16W,CHIP,G2A
A_CPU0_UPI01_RBIAS       U5D1             AP29     SKX_EXT_B_BGA1-IC,TBD
A_CPU0_UPI01_RBIAS       U5D1             AT29     SKX_EXT_B_BGA1-IC,TBD
A_CPU0_UPI2_RBIAS        R4P4             1        RES_0402-49.9,1%,1/16W,CHIP,G2A
A_CPU0_UPI2_RBIAS        U5D1             CK29     SKX_EXT_B_BGA1-IC,TBD
A_CPU0_UPI2_RBIAS        U5D1             CL28     SKX_EXT_B_BGA1-IC,TBD
A_CPU1_GHJ_RCOMP0        R7P16            1        RES_0402-90.9,1%,1/16W,CHIP,G2A
A_CPU1_GHJ_RCOMP0        U2D1             Y43      SKX_EXT_B_BGA1-IC,TBD
A_CPU1_GHJ_RCOMP1        R7P17            1        RES_0402-90.9,1%,1/16W,CHIP,G2A
A_CPU1_GHJ_RCOMP1        U2D1             AB43     SKX_EXT_B_BGA1-IC,TBD
A_CPU1_GHJ_RCOMP2        R7P19            1        RES_0402-100.0,1%,1/16W,CHIP,GA
A_CPU1_GHJ_RCOMP2        U2D1             AC42     SKX_EXT_B_BGA1-IC,TBD
A_CPU1_KLM_RCOMP0        R3D1             1        RES_0402-90.9,1%,1/16W,CHIP,G2A
A_CPU1_KLM_RCOMP0        U2D1             DC48     SKX_EXT_B_BGA1-IC,TBD
A_CPU1_KLM_RCOMP1        R3D2             1        RES_0402-90.9,1%,1/16W,CHIP,G2A
A_CPU1_KLM_RCOMP1        U2D1             DD47     SKX_EXT_B_BGA1-IC,TBD
A_CPU1_KLM_RCOMP2        R3D3             1        RES_0402-100.0,1%,1/16W,CHIP,GA
A_CPU1_KLM_RCOMP2        U2D1             DD49     SKX_EXT_B_BGA1-IC,TBD
A_CPU1_MCP01_RBIAS       R3D4             1        RES_0402-49.9,1%,1/16W,CHIP,G2A
A_CPU1_MCP01_RBIAS       U2D1             CT31     SKX_EXT_B_BGA1-IC,TBD
A_CPU1_MCP01_RBIAS       U2D1             CU32     SKX_EXT_B_BGA1-IC,TBD
A_CPU1_PE012_RBIAS       R7P10            1        RES_0402-49.9,1%,1/16W,CHIP,G2A
A_CPU1_PE012_RBIAS       U2D1             CL30     SKX_EXT_B_BGA1-IC,TBD
A_CPU1_PE012_RBIAS       U2D1             CN30     SKX_EXT_B_BGA1-IC,TBD
A_CPU1_PE3_RBIAS         R7P8             1        RES_0402-49.9,1%,1/16W,CHIP,G2A
A_CPU1_PE3_RBIAS         U2D1             CP29     SKX_EXT_B_BGA1-IC,TBD
A_CPU1_PE3_RBIAS         U2D1             CR30     SKX_EXT_B_BGA1-IC,TBD
A_CPU1_UPI01_RBIAS       R3D19            1        RES_0402-49.9,1%,1/16W,CHIP,G2A
A_CPU1_UPI01_RBIAS       U2D1             AP29     SKX_EXT_B_BGA1-IC,TBD
A_CPU1_UPI01_RBIAS       U2D1             AT29     SKX_EXT_B_BGA1-IC,TBD
A_CPU1_UPI2_RBIAS        R7P11            1        RES_0402-49.9,1%,1/16W,CHIP,G2A
A_CPU1_UPI2_RBIAS        U2D1             CK29     SKX_EXT_B_BGA1-IC,TBD
A_CPU1_UPI2_RBIAS        U2D1             CL28     SKX_EXT_B_BGA1-IC,TBD
A_CTOP                   C9E7             1        CAP_0402LF-0.039UF,25V,10%,X7RA
A_CTOP                   EU9E1            40       SPRINGVILLE_SM1-IC,G47144-004
A_DACRSET                R9G8             1        RES_0402-2.7K,1%,1/16W,CHIP,G2A
A_DACRSET                U9F4             R1       AST1250_BGA-IC,G85138-002
A_EXTCLKN                R7B8             1        RES_0402-10.0K,1%,1/16W,EMPTY,A
A_EXTCLKN                U7C1             D66      LBG_CORE_QAT_EXT_D_BGA1-IC,H91A
A_EXTCLKP                R7B7             1        RES_0402-10.0K,1%,1/16W,EMPTY,A
A_EXTCLKP                U7C1             E67      LBG_CORE_QAT_EXT_D_BGA1-IC,H91A
A_HSC_C                  C1E2             1        CAP_1206-0.068UF,50V,20%,X7R,1A
A_HSC_C                  R1D51            1        RES_0402-10.0,1%,1/16W,CHIP,G2A
A_HSC_CSOUT              EU1D2            19       ADM1278_SM-IC,G99251-001
A_HSC_CSOUT              R1D14            1        RES_0402-105.0K,1%,1/16W,CHIP,A
A_HSC_CSOUT              R1D20            1        RES_0402-150.0K,1%,1/16W,CHIP,A
A_HSC_GATE               EU1D2            24       ADM1278_SM-IC,G99251-001
A_HSC_GATE               R1D48            1        RES_0402-10.0,1%,1/16W,CHIP,G2A
A_HSC_GATE               R1D51            2        RES_0402-10.0,1%,1/16W,CHIP,G2A
A_HSC_GATE               R1E1             1        RES_0402-10.0,1%,1/16W,CHIP,G2A
A_HSC_GATE               R9R4             1        RES_0402-10.0,1%,1/16W,CHIP,G2A
A_HSC_GATE1_R            EU1E3            4        MOSFETN_1D3S_SOT5-IC,G68777-001
A_HSC_GATE1_R            R1E1             2        RES_0402-10.0,1%,1/16W,CHIP,G2A
A_HSC_GATE2_R            EU9R1            4        MOSFETN_1D3S_SOT5-IC,G68777-001
A_HSC_GATE2_R            R9R4             2        RES_0402-10.0,1%,1/16W,CHIP,G2A
A_HSC_GATE3_R            EU1E1            4        MOSFETN_1D3S_SOT5-IC,G68777-001
A_HSC_GATE3_R            R1D48            2        RES_0402-10.0,1%,1/16W,CHIP,G2A
A_HSC_HIGH               R1D19            1        RES_0402-10.0K,1%,1/16W,CHIP,GA
A_HSC_HIGH               R1D20            2        RES_0402-150.0K,1%,1/16W,CHIP,A
A_HSC_HIGH               U1D2             3        TPS3700_SM-IC,H69492-001
A_HSC_HIGH_EN            J1B3             1        CONN3_C95678002_PIP-CONN,C9567A
A_HSC_HIGH_EN            J1B4             1        SCONN3_D53458001_SM-EMPTY,D534A
A_HSC_HIGH_EN            Q1D1             5        FET_N_DUAL_SMLF-2N7002DW,FET,DA
A_HSC_HIGH_EN            R1D18            1        RES_0402-100.0K,1%,1/16W,CHIP,A
A_HSC_HSN                EU1D2            27       ADM1278_SM-IC,G99251-001
A_HSC_HSN                R1D45            2        RES_0402-0.0,5%,1/16W,CHIP,G21A
A_HSC_HSN                R1D47            2        RES_0402-10.0,1%,1/16W,CHIP,G2A
A_HSC_HSN                R9P26            2        RES_0402-10.0,1%,1/16W,CHIP,G2A
A_HSC_HSP                EU1D2            28       ADM1278_SM-IC,G99251-001
A_HSC_HSP                R1D44            2        RES_0402-0.0,5%,1/16W,CHIP,G21A
A_HSC_HSP                R1D46            2        RES_0402-10.0,1%,1/16W,CHIP,G2A
A_HSC_HSP                R9P27            2        RES_0402-10.0,1%,1/16W,CHIP,G2A
A_HSC_INAP               R9P12            1        RES_0402-4.99K,1%,1/16W,CHIP,GA
A_HSC_INAP               R9P33            2        RES_0402-100.0K,1%,1/16W,CHIP,A
A_HSC_INAP               U9P2             4        TPS3700_SM-IC,H69492-001
A_HSC_ISET               C9P15            1        CAP_A_0402V-0.1UF,16V,10%,X7R,A
A_HSC_ISET               EU1D2            3        ADM1278_SM-IC,G99251-001
A_HSC_ISET               R1D13            2        RES_0402-90.9K,1%,1/16W,CHIP,GA
A_HSC_ISET               R1D16            1        RES_0402-69.8K,1%,1/16W,CHIP,GA
A_HSC_ISET               R1D37            2        RES_0402-100.0K,1%,1/16W,CHIP,A
A_HSC_ISET_S             Q1D1             3        FET_N_DUAL_SMLF-2N7002DW,FET,DA
A_HSC_ISET_S             R1D13            1        RES_0402-90.9K,1%,1/16W,CHIP,GA
A_HSC_ISET_S2            Q1D1             6        FET_N_DUAL_SMLF-2N7002DW,FET,DA
A_HSC_ISET_S2            R1D16            2        RES_0402-69.8K,1%,1/16W,CHIP,GA
A_HSC_ISTART             EU1D2            4        ADM1278_SM-IC,G99251-001
A_HSC_ISTART             R1D32            2        RES_0402-100.0K,1%,1/16W,CHIP,A
A_HSC_ISTART             R1D34            1        RES_0402-16K,1.0%,1/16W,CHIP,GA
A_HSC_LOW                R1D12            1        RES_0402-10.0K,1%,1/16W,CHIP,GA
A_HSC_LOW                R1D14            2        RES_0402-105.0K,1%,1/16W,CHIP,A
A_HSC_LOW                U1D2             4        TPS3700_SM-IC,H69492-001
A_HSC_LOW_DRAIN          Q9P1             6        FET_N_DUAL_SMLF-2N7002DW,FET,DA
A_HSC_LOW_DRAIN          R9P15            1        RES_0402-0.0,5%,1/16W,EMPTY,G2A
A_HSC_LOW_EN             J1B3             3        CONN3_C95678002_PIP-CONN,C9567A
A_HSC_LOW_EN             J1B4             3        SCONN3_D53458001_SM-EMPTY,D534A
A_HSC_LOW_EN             Q1D1             2        FET_N_DUAL_SMLF-2N7002DW,FET,DA
A_HSC_LOW_EN             R1D11            1        RES_0402-100.0K,1%,1/16W,CHIP,A
A_HSC_LOW_GATE           Q9P1             2        FET_N_DUAL_SMLF-2N7002DW,FET,DA
A_HSC_LOW_GATE           R1D10            2        RES_0402-10.0K,1%,1/16W,CHIP,GA
A_HSC_LOW_GATE           U1D2             6        TPS3700_SM-IC,H69492-001
A_HSC_MON                C1D22            1        CAP_A_0402V-0.1UF,16V,10%,EMPTA
A_HSC_MON                C9P17            1        CAP_A_0402V-0.1UF,16V,10%,EMPTA
A_HSC_MON                EU1D2            26       ADM1278_SM-IC,G99251-001
A_HSC_MON                R1D45            1        RES_0402-0.0,5%,1/16W,CHIP,G21A
A_HSC_MOP                C1D22            2        CAP_A_0402V-0.1UF,16V,10%,EMPTA
A_HSC_MOP                C9P16            1        CAP_A_0402V-0.1UF,16V,10%,EMPTA
A_HSC_MOP                EU1D2            29       ADM1278_SM-IC,G99251-001
A_HSC_MOP                R1D44            1        RES_0402-0.0,5%,1/16W,CHIP,G21A
A_HSC_OCP_SEL            J1B3             2        CONN3_C95678002_PIP-CONN,C9567A
A_HSC_OCP_SEL            J1B4             2        SCONN3_D53458001_SM-EMPTY,D534A
A_HSC_OCP_SEL            R1D15            2        RES_0402-100.0K,1%,1/16W,CHIP,A
A_HSC_OV                 C1D27            1        CAP_A_0402V-0.1UF,16V,10%,X7R,A
A_HSC_OV                 EU1D2            32       ADM1278_SM-IC,G99251-001
A_HSC_OV                 R1D43            1        RES_0402-7.5K,1%,1/16W,CHIP,G2A
A_HSC_OV                 R9P28            2        RES_0402-100.0K,1%,1/16W,CHIP,A
A_HSC_PSET               C1D21            1        CAP_A_0402V-0.1UF,16V,10%,X7R,A
A_HSC_PSET               EU1D2            1        ADM1278_SM-IC,G99251-001
A_HSC_PSET               R1D39            2        RES_0402-100.0K,1%,1/16W,CHIP,A
A_HSC_PSET               R1D40            1        RES_0402-40.2K,1%,1/16W,CHIP,GA
A_HSC_PWGIN              EU1D2            21       ADM1278_SM-IC,G99251-001
A_HSC_PWGIN              R9P23            2        RES_0402-100.0K,1%,1/16W,CHIP,A
A_HSC_PWGIN              R9P24            1        RES_0402-12.1K,1%,1/16W,CHIP,GA
A_HSC_TEMP               EU1D2            25       ADM1278_SM-IC,G99251-001
A_HSC_TEMP               Q1D3             1        NPN_SM-MMBT3904,IC,C52245-001
A_HSC_TEMP               Q1D3             3        NPN_SM-MMBT3904,IC,C52245-001
A_HSC_TIMER              C9P14            1        CAP_0603LF-0.033UF,50V,10%,X7RA
A_HSC_TIMER              EU1D2            5        ADM1278_SM-IC,G99251-001
A_HSC_TIMER              R9P21            1        RES_0402-0.0,5%,1/16W,CHIP,G21A
A_HSC_TIMER_R            R9P19            1        RES_0402-10.0K,1%,1/16W,EMPTY,A
A_HSC_TIMER_R            R9P21            2        RES_0402-0.0,5%,1/16W,CHIP,G21A
A_HSC_TIMER_R            U9P2             3        TPS3700_SM-IC,H69492-001
A_HSC_UV                 C1D26            1        CAP_A_0402V-0.1UF,16V,10%,X7R,A
A_HSC_UV                 EU1D2            31       ADM1278_SM-IC,G99251-001
A_HSC_UV                 R1D42            1        RES_0402-11K,1%,1/16W,CHIP,G21A
A_HSC_UV                 R9P29            2        RES_0402-100.0K,1%,1/16W,CHIP,A
A_HSC_VCAP               C1D19            1        CAP_0402-1.0UF,16V,10%,X6S,D97A
A_HSC_VCAP               EU1D2            2        ADM1278_SM-IC,G99251-001
A_HSC_VCAP               R1D27            1        RES_0402-4.75K,1%,1/16W,EMPTY,A
A_HSC_VCAP               R1D29            1        RES_0402-4.75K,1%,1/16W,EMPTY,A
A_HSC_VCAP               R1D32            1        RES_0402-100.0K,1%,1/16W,CHIP,A
A_HSC_VCAP               R1D37            1        RES_0402-100.0K,1%,1/16W,CHIP,A
A_HSC_VCAP               R1D39            1        RES_0402-100.0K,1%,1/16W,CHIP,A
A_HSC_VOUT               C9P12            1        CAP_A_0402V-0.1UF,16V,10%,EMPTA
A_HSC_VOUT               EU1D2            20       ADM1278_SM-IC,G99251-001
A_HSC_VOUT               R1D36            2        RES_0402-1.00K,1%,1/16W,CHIP,GA
A_KR0_RBIAS              R2N4             2        RES_0402-1.0K,0.1%,1/16W,CHIP,A
A_KR0_RBIAS              U7C1             BB29     LBG_CORE_QAT_EXT_D_BGA1-IC,H91A
A_KR1_RBIAS              R2M6             1        RES_0402-1.0K,0.1%,1/16W,CHIP,A
A_KR1_RBIAS              U7C1             BD42     LBG_CORE_QAT_EXT_D_BGA1-IC,H91A
A_M_BMC_ZQ               R1T27            1        RES_0402-240,1.0%,1/16W,CHIP,GA
A_M_BMC_ZQ               U9F5             L8       K4B1G16_BGA1-IC,G38649-001
A_P12V_STBY_ADR_TRIGGER  R9P7             2        RES_0402-249K,1.0%,1/16W,CHIP,A
A_P12V_STBY_ADR_TRIGGER  R9P9             1        RES_0402-10.0K,1%,1/16W,CHIP,GA
A_P12V_STBY_ADR_TRIGGER  U9P1             4        TPS3700_SM-IC,H69492-001
A_P12V_STBY_FPH_GATE     Q9P1             5        FET_N_DUAL_SMLF-2N7002DW,FET,DA
A_P12V_STBY_FPH_GATE     R9P10            2        RES_0402-10.0K,1%,1/16W,CHIP,GA
A_P12V_STBY_FPH_GATE     U9P1             1        TPS3700_SM-IC,H69492-001
A_P12V_STBY_FP_TRIGGER   R9P11            1        RES_0402-10.0K,1%,1/16W,CHIP,GA
A_P12V_STBY_FP_TRIGGER   R9P13            2        RES_0402-274K,1.0%,1/16W,CHIP,A
A_P12V_STBY_FP_TRIGGER   U9P1             3        TPS3700_SM-IC,H69492-001
A_P12V_STBY_SCALED       C9G17            1        CAP_0402LF-47.0PF,50V,5%,COG,AA
A_P12V_STBY_SCALED       EU9G1            14       ADC128D818_SM-IC,H63642-001
A_P12V_STBY_SCALED       R1U32            2        RES_0402-5.11K,1%,1/16W,CHIP,GA
A_P12V_STBY_SCALED       R1U33            1        RES_0402-1.00K,1%,1/16W,CHIP,GA
A_P12V_STBY_SCALED       U9F4             L3       AST1250_BGA-IC,G85138-002
A_P1V05_STBY_PCH_SENSOR  C1U21            1        CAP_0402LF-47.0PF,50V,5%,COG,AA
A_P1V05_STBY_PCH_SENSOR  EU9G1            13       ADC128D818_SM-IC,H63642-001
A_P1V05_STBY_PCH_SENSOR  FB1U3            1        FERRITE_SMLF-30,FB,693286-021
A_P1V05_STBY_PCH_SENSOR  U9F4             L2       AST1250_BGA-IC,G85138-002
A_P3V3_SCALED            C9G14            1        CAP_0402LF-47.0PF,50V,5%,COG,AA
A_P3V3_SCALED            EU9G1            16       ADC128D818_SM-IC,H63642-001
A_P3V3_SCALED            R1U26            2        RES_0402-5.11K,1%,1/16W,CHIP,GA
A_P3V3_SCALED            R1U27            1        RES_0402-8.2K,1%,1/16W,CHIP,G2A
A_P3V3_SCALED            U9F4             L5       AST1250_BGA-IC,G85138-002
A_P3V3_STBY_SCALED       C9G20            1        CAP_0402LF-47.0PF,50V,5%,COG,AA
A_P3V3_STBY_SCALED       EU9G1            11       ADC128D818_SM-IC,H63642-001
A_P3V3_STBY_SCALED       R1U38            1        RES_0402-8.2K,1%,1/16W,CHIP,G2A
A_P3V3_STBY_SCALED       R1U39            2        RES_0402-5.11K,1%,1/16W,CHIP,GA
A_P3V3_STBY_SCALED       U9F4             M5       AST1250_BGA-IC,G85138-002
A_P3V_BAT_R              CR2U1            2        DIODE2A_DUAL_SMLF-BAS70-05,DIOA
A_P3V_BAT_R              R1U50            1        RES_0402-200.0K,1%,1/16W,CHIP,A
A_P3V_BAT_R              R2U43            2        RES_0402-1.00K,1%,1/16W,CHIP,GA
A_P3V_BAT_SCALED         C9G22            1        CAP_0402LF-10.0PF,50V,5%,COG,AA
A_P3V_BAT_SCALED         EU9G1            9        ADC128D818_SM-IC,H63642-001
A_P3V_BAT_SCALED         Q9G1             4        FET_N_DUAL_SMLF-NTJD4001N,FET,A
A_P3V_BAT_SCALED         R9G26            1        RES_0402-100.0K,1%,1/16W,CHIP,A
A_P3V_BAT_SCALED         U9F4             M3       AST1250_BGA-IC,G85138-002
A_P5V_SCALED             C9G15            1        CAP_0402LF-47.0PF,50V,5%,COG,AA
A_P5V_SCALED             EU9G1            15       ADC128D818_SM-IC,H63642-001
A_P5V_SCALED             R1U28            1        RES_0402-3.48K,1.0%,1/16W,CHIPA
A_P5V_SCALED             R1U29            2        RES_0402-5.11K,1%,1/16W,CHIP,GA
A_P5V_SCALED             U9F4             L4       AST1250_BGA-IC,G85138-002
A_P5V_STBY_SCALED        C9G21            1        CAP_0402LF-47.0PF,50V,5%,COG,AA
A_P5V_STBY_SCALED        EU9G1            10       ADC128D818_SM-IC,H63642-001
A_P5V_STBY_SCALED        R1U44            1        RES_0402-3.48K,1.0%,1/16W,CHIPA
A_P5V_STBY_SCALED        R1U47            2        RES_0402-5.11K,1%,1/16W,CHIP,GA
A_P5V_STBY_SCALED        U9F4             M4       AST1250_BGA-IC,G85138-002
A_PCH_XCLK_BIASREF       R3N1             1        RES_0402-169,1.0%,1/16W,CHIP,GA
A_PCH_XCLK_BIASREF       U7C1             G44      LBG_CORE_QAT_EXT_D_BGA1-IC,H91A
A_PCIEUP_RCOMP_N         R3M12            2        RES_0402-100.0,1%,1/16W,CHIP,GA
A_PCIEUP_RCOMP_N         U7C1             AF58     LBG_CORE_QAT_EXT_D_BGA1-IC,H91A
A_PCIEUP_RCOMP_P         R3M12            1        RES_0402-100.0,1%,1/16W,CHIP,GA
A_PCIEUP_RCOMP_P         U7C1             AH58     LBG_CORE_QAT_EXT_D_BGA1-IC,H91A
A_PCIE_RCOMP_N           R3M11            2        RES_0402-100.0,1%,1/16W,CHIP,GA
A_PCIE_RCOMP_N           U7C1             BD58     LBG_CORE_QAT_EXT_D_BGA1-IC,H91A
A_PCIE_RCOMP_P           R3M11            1        RES_0402-100.0,1%,1/16W,CHIP,GA
A_PCIE_RCOMP_P           U7C1             BB56     LBG_CORE_QAT_EXT_D_BGA1-IC,H91A
A_PG_P12V_MAIN           R8D38            2        RES_0402-100.0K,1%,1/16W,CHIP,A
A_PG_P12V_MAIN           R8D40            1        RES_0402-3.74K,1%,1/16W,CHIP,GA
A_PG_P12V_MAIN           U8D8             4        TPS3700_SM-IC,H69492-001
A_PG_P5V                 R8D37            1        RES_0402-4.75K,1%,1/16W,CHIP,GA
A_PG_P5V                 R8D39            2        RES_0402-49.9K,1%,1/16W,CHIP,GA
A_PG_P5V                 U8D8             3        TPS3700_SM-IC,H69492-001
A_PVCCRTC_EXT_CAP        C3N29            1        CAP_A_0402V-0.1UF,16V,10%,X7R,A
A_PVCCRTC_EXT_CAP        U7C1             AG22     LBG_CORE_QAT_EXT_D_BGA1-IC,H91A
A_PVNN_STBY_PCH_SENSOR   C9G18            1        CAP_0402LF-47.0PF,50V,5%,COG,AA
A_PVNN_STBY_PCH_SENSOR   EU9G1            12       ADC128D818_SM-IC,H63642-001
A_PVNN_STBY_PCH_SENSOR   FB1U4            1        FERRITE_SMLF-30,FB,693286-021
A_PVNN_STBY_PCH_SENSOR   U9F4             L1       AST1250_BGA-IC,G85138-002
A_RCOMP_3P3              R8C21            1        RES_0402-100.0,1%,1/16W,CHIP,GA
A_RCOMP_3P3              U7C1             BY25     LBG_CORE_QAT_EXT_D_BGA1-IC,H91A
A_TSENSE_P1V05_PCH_STBY_TMON CTI69            1        CAP_0402LF-1000PF,50V,10%,X7R,A
A_TSENSE_P1V05_PCH_STBY_TMON EU7A2            36       IR354XX_SM-IR35412,IC,H73684-0A
A_TSENSE_P1V05_PCH_STBY_TMON EU8A1            34       PXE1110B_QFN-IC,H89187-001
A_TSENSE_PVCCIN_CPU0     C4D17            1        CAP_0402LF-220PF,50V,10%,X7R,AA
A_TSENSE_PVCCIN_CPU0     CTI2             1        CAP_0402LF-1000PF,50V,10%,X7R,A
A_TSENSE_PVCCIN_CPU0     CTI4             1        CAP_0402LF-1000PF,50V,10%,X7R,A
A_TSENSE_PVCCIN_CPU0     CTI34            1        CAP_0402LF-1000PF,50V,10%,X7R,A
A_TSENSE_PVCCIN_CPU0     CTI37            1        CAP_0402LF-1000PF,50V,10%,X7R,A
A_TSENSE_PVCCIN_CPU0     CTI42            1        CAP_0402LF-1000PF,50V,10%,X7R,A
A_TSENSE_PVCCIN_CPU0     EU4C2            36       IR354XX_SM-IR35411,IC,H73688-0A
A_TSENSE_PVCCIN_CPU0     EU4D1            36       IR354XX_SM-IR35411,IC,H73688-0A
A_TSENSE_PVCCIN_CPU0     EU4D3            36       IR354XX_SM-IR35411,IC,H73688-0A
A_TSENSE_PVCCIN_CPU0     EU4D4            43       PXE1610B_QFN-IC,H79206-001
A_TSENSE_PVCCIN_CPU0     EU4D6            36       IR354XX_SM-IR35411,IC,H73688-0A
A_TSENSE_PVCCIN_CPU0     EU4E1            36       IR354XX_SM-IR35411,IC,H73688-0A
A_TSENSE_PVCCIN_CPU1     C1C10            1        CAP_0402LF-220PF,50V,10%,X7R,AA
A_TSENSE_PVCCIN_CPU1     CTI15            1        CAP_0402LF-1000PF,50V,10%,X7R,A
A_TSENSE_PVCCIN_CPU1     CTI17            1        CAP_0402LF-1000PF,50V,10%,X7R,A
A_TSENSE_PVCCIN_CPU1     CTI19            1        CAP_0402LF-1000PF,50V,10%,X7R,A
A_TSENSE_PVCCIN_CPU1     CTI22            1        CAP_0402LF-1000PF,50V,10%,X7R,A
A_TSENSE_PVCCIN_CPU1     CTI26            1        CAP_0402LF-1000PF,50V,10%,X7R,A
A_TSENSE_PVCCIN_CPU1     EU1C2            43       PXE1610B_QFN-IC,H79206-001
A_TSENSE_PVCCIN_CPU1     EU1C3            36       IR354XX_SM-IR35411,IC,H73688-0A
A_TSENSE_PVCCIN_CPU1     EU1D1            36       IR354XX_SM-IR35411,IC,H73688-0A
A_TSENSE_PVCCIN_CPU1     EU1D3            36       IR354XX_SM-IR35411,IC,H73688-0A
A_TSENSE_PVCCIN_CPU1     EU1D4            36       IR354XX_SM-IR35411,IC,H73688-0A
A_TSENSE_PVCCIN_CPU1     EU1E2            36       IR354XX_SM-IR35411,IC,H73688-0A
A_TSENSE_PVCCIO_CPU0     CTI71            1        CAP_0402LF-1000PF,50V,10%,X7R,A
A_TSENSE_PVCCIO_CPU0     EU3P1            35       PXE1110B_QFN-IC,H89187-001
A_TSENSE_PVCCIO_CPU0     EU7C1            36       IR354XX_SM-IR35412,IC,H73684-0A
A_TSENSE_PVCCIO_CPU1     CTI61            1        CAP_0402LF-1000PF,50V,10%,X7R,A
A_TSENSE_PVCCIO_CPU1     EU4D5            35       PXE1110B_QFN-IC,H89187-001
A_TSENSE_PVCCIO_CPU1     EU4E2            36       IR354XX_SM-IR35412,IC,H73684-0A
A_TSENSE_PVDDQ_ABC       C7G3             1        CAP_0402LF-220PF,50V,10%,X7R,AA
A_TSENSE_PVDDQ_ABC       CTI49            1        CAP_0402LF-1000PF,50V,10%,X7R,A
A_TSENSE_PVDDQ_ABC       CTI54            1        CAP_0402LF-1000PF,50V,10%,X7R,A
A_TSENSE_PVDDQ_ABC       EU7G1            35       PXM1310B_QFN-IC,H89186-001
A_TSENSE_PVDDQ_ABC       EU7G2            36       IR354XX_SM-IR35411,IC,H73688-0A
A_TSENSE_PVDDQ_ABC       EU7G3            36       IR354XX_SM-IR35411,IC,H73688-0A
A_TSENSE_PVDDQ_DEF       C7A29            1        CAP_0402LF-220PF,50V,10%,X7R,AA
A_TSENSE_PVDDQ_DEF       CTI43            1        CAP_0402LF-1000PF,50V,10%,X7R,A
A_TSENSE_PVDDQ_DEF       CTI48            1        CAP_0402LF-1000PF,50V,10%,X7R,A
A_TSENSE_PVDDQ_DEF       EU7A1            36       IR354XX_SM-IR35411,IC,H73688-0A
A_TSENSE_PVDDQ_DEF       EU7A4            36       IR354XX_SM-IR35411,IC,H73688-0A
A_TSENSE_PVDDQ_DEF       EU7A5            35       PXM1310B_QFN-IC,H89186-001
A_TSENSE_PVDDQ_GHJ       C1G24            1        CAP_0402LF-220PF,50V,10%,X7R,AA
A_TSENSE_PVDDQ_GHJ       CTI28            1        CAP_0402LF-1000PF,50V,10%,X7R,A
A_TSENSE_PVDDQ_GHJ       CTI32            1        CAP_0402LF-1000PF,50V,10%,X7R,A
A_TSENSE_PVDDQ_GHJ       EU1F1            36       IR354XX_SM-IR35411,IC,H73688-0A
A_TSENSE_PVDDQ_GHJ       EU1G1            36       IR354XX_SM-IR35411,IC,H73688-0A
A_TSENSE_PVDDQ_GHJ       EU1G2            35       PXM1310B_QFN-IC,H89186-001
A_TSENSE_PVDDQ_KLM       C1B11            1        CAP_0402LF-220PF,50V,10%,X7R,AA
A_TSENSE_PVDDQ_KLM       CTI8             1        CAP_0402LF-1000PF,50V,10%,X7R,A
A_TSENSE_PVDDQ_KLM       CTI10            1        CAP_0402LF-1000PF,50V,10%,X7R,A
A_TSENSE_PVDDQ_KLM       EU1A1            36       IR354XX_SM-IR35411,IC,H73688-0A
A_TSENSE_PVDDQ_KLM       EU1A2            36       IR354XX_SM-IR35411,IC,H73688-0A
A_TSENSE_PVDDQ_KLM       EU1B1            35       PXM1310B_QFN-IC,H89186-001
A_TSENSE_PVNN_PCH_TMON   CTI64            1        CAP_0402LF-1000PF,50V,10%,X7R,A
A_TSENSE_PVNN_PCH_TMON   EU7A3            36       IR354XX_SM-IR35412,IC,H73684-0A
A_TSENSE_PVNN_PCH_TMON   EU8A1            35       PXE1110B_QFN-IC,H89187-001
A_TSENSE_PVSA_CPU0       C4D18            1        CAP_0402LF-220PF,50V,10%,X7R,AA
A_TSENSE_PVSA_CPU0       CTI58            1        CAP_0402LF-1000PF,50V,10%,X7R,A
A_TSENSE_PVSA_CPU0       EU4C1            36       IR354XX_SM-IR35412,IC,H73684-0A
A_TSENSE_PVSA_CPU0       EU4D4            42       PXE1610B_QFN-IC,H79206-001
A_TSENSE_PVSA_CPU1       C1C11            1        CAP_0402LF-220PF,50V,10%,X7R,AA
A_TSENSE_PVSA_CPU1       CTI55            1        CAP_0402LF-1000PF,50V,10%,X7R,A
A_TSENSE_PVSA_CPU1       EU1C1            36       IR354XX_SM-IR35412,IC,H73684-0A
A_TSENSE_PVSA_CPU1       EU1C2            42       PXE1610B_QFN-IC,H79206-001
A_USB2VRES               R1T25            1        RES_0402-8.2K,1%,1/16W,CHIP,G2A
A_USB2VRES               U9F4             AA20     AST1250_BGA-IC,G85138-002
A_USB2_COMP              R8B9             1        RES_0402-113,1%,1/16W,CHIP,G21A
A_USB2_COMP              U7C1             BN70     LBG_CORE_QAT_EXT_D_BGA1-IC,H91A
A_USB2_VBUS              R8B32            1        RES_0402-10.0K,1%,1/16W,CHIP,GA
A_USB2_VBUS              U7C1             BR67     LBG_CORE_QAT_EXT_D_BGA1-IC,H91A
CLK_100M_AIRMAX8_PE1_DN  J1F1             I4       CONN76_H22707001_THMT1-CONN,H2A
CLK_100M_AIRMAX8_PE1_DN  U7C1             K38      LBG_CORE_QAT_EXT_D_BGA1-IC,H91A
CLK_100M_AIRMAX8_PE1_DP  J1F1             H4       CONN76_H22707001_THMT1-CONN,H2A
CLK_100M_AIRMAX8_PE1_DP  U7C1             H38      LBG_CORE_QAT_EXT_D_BGA1-IC,H91A
CLK_100M_BMC_PE_DN       R7C2             2        RES_0402-0.0,5%,1/16W,EMPTY,G2A
CLK_100M_BMC_PE_DN       U7C1             B29      LBG_CORE_QAT_EXT_D_BGA1-IC,H91A
CLK_100M_BMC_PE_DP       R7C4             2        RES_0402-0.0,5%,1/16W,EMPTY,G2A
CLK_100M_BMC_PE_DP       U7C1             D29      LBG_CORE_QAT_EXT_D_BGA1-IC,H91A
CLK_100M_BMC_PE_R_DN     R7C2             1        RES_0402-0.0,5%,1/16W,EMPTY,G2A
CLK_100M_BMC_PE_R_DN     R9F44            1        RES_0402-100.0K,1%,1/16W,CHIP,A
CLK_100M_BMC_PE_R_DN     U9F4             G21      AST1250_BGA-IC,G85138-002
CLK_100M_BMC_PE_R_DP     R7C4             1        RES_0402-0.0,5%,1/16W,EMPTY,G2A
CLK_100M_BMC_PE_R_DP     R9F45            1        RES_0402-100.0K,1%,1/16W,CHIP,A
CLK_100M_BMC_PE_R_DP     U9F4             G22      AST1250_BGA-IC,G85138-002
CLK_100M_CPU0_BCLK0_DN   R4D25            2        RES_0402-27.4,1%,1/16W,CHIP,G2A
CLK_100M_CPU0_BCLK0_DN   R6P15            1        RES_0402-42.2,1.0%,1/16W,EMPTYA
CLK_100M_CPU0_BCLK0_DN   U5D1             AU24     SKX_EXT_B_BGA1-IC,TBD
CLK_100M_CPU0_BCLK0_DP   R4D29            2        RES_0402-27.4,1%,1/16W,CHIP,G2A
CLK_100M_CPU0_BCLK0_DP   R6P17            1        RES_0402-42.2,1.0%,1/16W,EMPTYA
CLK_100M_CPU0_BCLK0_DP   U5D1             AW24     SKX_EXT_B_BGA1-IC,TBD
CLK_100M_CPU0_BCLK0_R_DN EU4D2            18       NB3W1200L_LCC-IC,H13585-001
CLK_100M_CPU0_BCLK0_R_DN R4D25            1        RES_0402-27.4,1%,1/16W,CHIP,G2A
CLK_100M_CPU0_BCLK0_R_DP EU4D2            17       NB3W1200L_LCC-IC,H13585-001
CLK_100M_CPU0_BCLK0_R_DP R4D29            1        RES_0402-27.4,1%,1/16W,CHIP,G2A
CLK_100M_CPU0_BCLK1_DN   R4D18            1        RES_0402-42.2,1.0%,1/16W,EMPTYA
CLK_100M_CPU0_BCLK1_DN   R4D20            2        RES_0402-27.4,1%,1/16W,CHIP,G2A
CLK_100M_CPU0_BCLK1_DN   U5D1             CR26     SKX_EXT_B_BGA1-IC,TBD
CLK_100M_CPU0_BCLK1_DP   R4D22            2        RES_0402-27.4,1%,1/16W,CHIP,G2A
CLK_100M_CPU0_BCLK1_DP   R4D24            1        RES_0402-42.2,1.0%,1/16W,EMPTYA
CLK_100M_CPU0_BCLK1_DP   U5D1             CP27     SKX_EXT_B_BGA1-IC,TBD
CLK_100M_CPU0_BCLK1_R_DN EU4D2            22       NB3W1200L_LCC-IC,H13585-001
CLK_100M_CPU0_BCLK1_R_DN R4D20            1        RES_0402-27.4,1%,1/16W,CHIP,G2A
CLK_100M_CPU0_BCLK1_R_DP EU4D2            21       NB3W1200L_LCC-IC,H13585-001
CLK_100M_CPU0_BCLK1_R_DP R4D22            1        RES_0402-27.4,1%,1/16W,CHIP,G2A
CLK_100M_CPU0_BCLK2_DN   R4D14            2        RES_0402-27.4,1%,1/16W,CHIP,G2A
CLK_100M_CPU0_BCLK2_DN   R6P12            1        RES_0402-42.2,1.0%,1/16W,EMPTYA
CLK_100M_CPU0_BCLK2_DN   U5D1             CT25     SKX_EXT_B_BGA1-IC,TBD
CLK_100M_CPU0_BCLK2_DP   R4D17            2        RES_0402-27.4,1%,1/16W,CHIP,G2A
CLK_100M_CPU0_BCLK2_DP   R6P13            1        RES_0402-42.2,1.0%,1/16W,EMPTYA
CLK_100M_CPU0_BCLK2_DP   U5D1             CU26     SKX_EXT_B_BGA1-IC,TBD
CLK_100M_CPU0_BCLK2_R_DN EU4D2            27       NB3W1200L_LCC-IC,H13585-001
CLK_100M_CPU0_BCLK2_R_DN R4D14            1        RES_0402-27.4,1%,1/16W,CHIP,G2A
CLK_100M_CPU0_BCLK2_R_DP EU4D2            26       NB3W1200L_LCC-IC,H13585-001
CLK_100M_CPU0_BCLK2_R_DP R4D17            1        RES_0402-27.4,1%,1/16W,CHIP,G2A
CLK_100M_CPU0_PE_REFCLK_DN R4D10            2        RES_0402-27.4,1%,1/16W,CHIP,G2A
CLK_100M_CPU0_PE_REFCLK_DN R6P9             1        RES_0402-42.2,1.0%,1/16W,EMPTYA
CLK_100M_CPU0_PE_REFCLK_DN U5D1             BU24     SKX_EXT_B_BGA1-IC,TBD
CLK_100M_CPU0_PE_REFCLK_DP R4D12            2        RES_0402-27.4,1%,1/16W,CHIP,G2A
CLK_100M_CPU0_PE_REFCLK_DP R6P11            1        RES_0402-42.2,1.0%,1/16W,EMPTYA
CLK_100M_CPU0_PE_REFCLK_DP U5D1             BW24     SKX_EXT_B_BGA1-IC,TBD
CLK_100M_CPU0_PE_REFCLK_R_DN EU4D2            31       NB3W1200L_LCC-IC,H13585-001
CLK_100M_CPU0_PE_REFCLK_R_DN R4D10            1        RES_0402-27.4,1%,1/16W,CHIP,G2A
CLK_100M_CPU0_PE_REFCLK_R_DP EU4D2            30       NB3W1200L_LCC-IC,H13585-001
CLK_100M_CPU0_PE_REFCLK_R_DP R4D12            1        RES_0402-27.4,1%,1/16W,CHIP,G2A
CLK_100M_CPU0_RC_REFCLK0_DN R4D7             2        RES_0402-27.4,1%,1/16W,CHIP,G2A
CLK_100M_CPU0_RC_REFCLK0_DN R6P2             1        RES_0402-42.2,1.0%,1/16W,EMPTYA
CLK_100M_CPU0_RC_REFCLK0_DN U5D1             AP27     SKX_EXT_B_BGA1-IC,TBD
CLK_100M_CPU0_RC_REFCLK0_DP R4D8             2        RES_0402-27.4,1%,1/16W,CHIP,G2A
CLK_100M_CPU0_RC_REFCLK0_DP R6P1             1        RES_0402-42.2,1.0%,1/16W,EMPTYA
CLK_100M_CPU0_RC_REFCLK0_DP U5D1             AM27     SKX_EXT_B_BGA1-IC,TBD
CLK_100M_CPU0_RC_REFCLK0_R_DN EU4D2            35       NB3W1200L_LCC-IC,H13585-001
CLK_100M_CPU0_RC_REFCLK0_R_DN R4D7             1        RES_0402-27.4,1%,1/16W,CHIP,G2A
CLK_100M_CPU0_RC_REFCLK0_R_DP EU4D2            34       NB3W1200L_LCC-IC,H13585-001
CLK_100M_CPU0_RC_REFCLK0_R_DP R4D8             1        RES_0402-27.4,1%,1/16W,CHIP,G2A
CLK_100M_CPU0_RC_REFCLK1_DN R4D5             2        RES_0402-27.4,1%,1/16W,CHIP,G2A
CLK_100M_CPU0_RC_REFCLK1_DN R6P4             1        RES_0402-42.2,1.0%,1/16W,EMPTYA
CLK_100M_CPU0_RC_REFCLK1_DN U5D1             BB25     SKX_EXT_B_BGA1-IC,TBD
CLK_100M_CPU0_RC_REFCLK1_DP R4D6             2        RES_0402-27.4,1%,1/16W,CHIP,G2A
CLK_100M_CPU0_RC_REFCLK1_DP R6P3             1        RES_0402-42.2,1.0%,1/16W,EMPTYA
CLK_100M_CPU0_RC_REFCLK1_DP U5D1             BD25     SKX_EXT_B_BGA1-IC,TBD
CLK_100M_CPU0_RC_REFCLK1_R_DN EU4D2            39       NB3W1200L_LCC-IC,H13585-001
CLK_100M_CPU0_RC_REFCLK1_R_DN R4D5             1        RES_0402-27.4,1%,1/16W,CHIP,G2A
CLK_100M_CPU0_RC_REFCLK1_R_DP EU4D2            38       NB3W1200L_LCC-IC,H13585-001
CLK_100M_CPU0_RC_REFCLK1_R_DP R4D6             1        RES_0402-27.4,1%,1/16W,CHIP,G2A
CLK_100M_CPU1_BCLK0_DN   R4D3             2        RES_0402-27.4,1%,1/16W,CHIP,G2A
CLK_100M_CPU1_BCLK0_DN   R6P6             1        RES_0402-42.2,1.0%,1/16W,EMPTYA
CLK_100M_CPU1_BCLK0_DN   U2D1             AU24     SKX_EXT_B_BGA1-IC,TBD
CLK_100M_CPU1_BCLK0_DP   R4D4             2        RES_0402-27.4,1%,1/16W,CHIP,G2A
CLK_100M_CPU1_BCLK0_DP   R6P5             1        RES_0402-42.2,1.0%,1/16W,EMPTYA
CLK_100M_CPU1_BCLK0_DP   U2D1             AW24     SKX_EXT_B_BGA1-IC,TBD
CLK_100M_CPU1_BCLK0_R_DN EU4D2            43       NB3W1200L_LCC-IC,H13585-001
CLK_100M_CPU1_BCLK0_R_DN R4D3             1        RES_0402-27.4,1%,1/16W,CHIP,G2A
CLK_100M_CPU1_BCLK0_R_DP EU4D2            42       NB3W1200L_LCC-IC,H13585-001
CLK_100M_CPU1_BCLK0_R_DP R4D4             1        RES_0402-27.4,1%,1/16W,CHIP,G2A
CLK_100M_CPU1_BCLK1_DN   R4D1             2        RES_0402-27.4,1%,1/16W,CHIP,G2A
CLK_100M_CPU1_BCLK1_DN   R6P8             1        RES_0402-42.2,1.0%,1/16W,EMPTYA
CLK_100M_CPU1_BCLK1_DN   U2D1             CR26     SKX_EXT_B_BGA1-IC,TBD
CLK_100M_CPU1_BCLK1_DP   R4D2             2        RES_0402-27.4,1%,1/16W,CHIP,G2A
CLK_100M_CPU1_BCLK1_DP   R6P7             1        RES_0402-42.2,1.0%,1/16W,EMPTYA
CLK_100M_CPU1_BCLK1_DP   U2D1             CP27     SKX_EXT_B_BGA1-IC,TBD
CLK_100M_CPU1_BCLK1_R_DN EU4D2            47       NB3W1200L_LCC-IC,H13585-001
CLK_100M_CPU1_BCLK1_R_DN R4D1             1        RES_0402-27.4,1%,1/16W,CHIP,G2A
CLK_100M_CPU1_BCLK1_R_DP EU4D2            46       NB3W1200L_LCC-IC,H13585-001
CLK_100M_CPU1_BCLK1_R_DP R4D2             1        RES_0402-27.4,1%,1/16W,CHIP,G2A
CLK_100M_CPU1_BCLK2_DN   R4D11            2        RES_0402-27.4,1%,1/16W,CHIP,G2A
CLK_100M_CPU1_BCLK2_DN   R7P2             1        RES_0402-42.2,1.0%,1/16W,EMPTYA
CLK_100M_CPU1_BCLK2_DN   U2D1             CT25     SKX_EXT_B_BGA1-IC,TBD
CLK_100M_CPU1_BCLK2_DP   R4D9             2        RES_0402-27.4,1%,1/16W,CHIP,G2A
CLK_100M_CPU1_BCLK2_DP   R7P1             1        RES_0402-42.2,1.0%,1/16W,EMPTYA
CLK_100M_CPU1_BCLK2_DP   U2D1             CU26     SKX_EXT_B_BGA1-IC,TBD
CLK_100M_CPU1_BCLK2_R_DN EU4D2            51       NB3W1200L_LCC-IC,H13585-001
CLK_100M_CPU1_BCLK2_R_DN R4D11            1        RES_0402-27.4,1%,1/16W,CHIP,G2A
CLK_100M_CPU1_BCLK2_R_DP EU4D2            50       NB3W1200L_LCC-IC,H13585-001
CLK_100M_CPU1_BCLK2_R_DP R4D9             1        RES_0402-27.4,1%,1/16W,CHIP,G2A
CLK_100M_CPU1_PE_REFCLK_DN R4D16            2        RES_0402-27.4,1%,1/16W,CHIP,G2A
CLK_100M_CPU1_PE_REFCLK_DN R7P4             1        RES_0402-42.2,1.0%,1/16W,EMPTYA
CLK_100M_CPU1_PE_REFCLK_DN U2D1             BU24     SKX_EXT_B_BGA1-IC,TBD
CLK_100M_CPU1_PE_REFCLK_DP R4D13            2        RES_0402-27.4,1%,1/16W,CHIP,G2A
CLK_100M_CPU1_PE_REFCLK_DP R7P3             1        RES_0402-42.2,1.0%,1/16W,EMPTYA
CLK_100M_CPU1_PE_REFCLK_DP U2D1             BW24     SKX_EXT_B_BGA1-IC,TBD
CLK_100M_CPU1_PE_REFCLK_R_DN EU4D2            55       NB3W1200L_LCC-IC,H13585-001
CLK_100M_CPU1_PE_REFCLK_R_DN R4D16            1        RES_0402-27.4,1%,1/16W,CHIP,G2A
CLK_100M_CPU1_PE_REFCLK_R_DP EU4D2            54       NB3W1200L_LCC-IC,H13585-001
CLK_100M_CPU1_PE_REFCLK_R_DP R4D13            1        RES_0402-27.4,1%,1/16W,CHIP,G2A
CLK_100M_CPU1_RC_REFCLK0_DN R4D21            2        RES_0402-27.4,1%,1/16W,CHIP,G2A
CLK_100M_CPU1_RC_REFCLK0_DN R7P7             1        RES_0402-42.2,1.0%,1/16W,EMPTYA
CLK_100M_CPU1_RC_REFCLK0_DN U2D1             AP27     SKX_EXT_B_BGA1-IC,TBD
CLK_100M_CPU1_RC_REFCLK0_DP R4D19            2        RES_0402-27.4,1%,1/16W,CHIP,G2A
CLK_100M_CPU1_RC_REFCLK0_DP R7P6             1        RES_0402-42.2,1.0%,1/16W,EMPTYA
CLK_100M_CPU1_RC_REFCLK0_DP U2D1             AM27     SKX_EXT_B_BGA1-IC,TBD
CLK_100M_CPU1_RC_REFCLK0_R_DN EU4D2            60       NB3W1200L_LCC-IC,H13585-001
CLK_100M_CPU1_RC_REFCLK0_R_DN R4D21            1        RES_0402-27.4,1%,1/16W,CHIP,G2A
CLK_100M_CPU1_RC_REFCLK0_R_DP EU4D2            59       NB3W1200L_LCC-IC,H13585-001
CLK_100M_CPU1_RC_REFCLK0_R_DP R4D19            1        RES_0402-27.4,1%,1/16W,CHIP,G2A
CLK_100M_CPU1_RC_REFCLK1_DN R4D28            2        RES_0402-27.4,1%,1/16W,CHIP,G2A
CLK_100M_CPU1_RC_REFCLK1_DN R7P12            1        RES_0402-42.2,1.0%,1/16W,EMPTYA
CLK_100M_CPU1_RC_REFCLK1_DN U2D1             BB25     SKX_EXT_B_BGA1-IC,TBD
CLK_100M_CPU1_RC_REFCLK1_DP R4D23            2        RES_0402-27.4,1%,1/16W,CHIP,G2A
CLK_100M_CPU1_RC_REFCLK1_DP R7P9             1        RES_0402-42.2,1.0%,1/16W,EMPTYA
CLK_100M_CPU1_RC_REFCLK1_DP U2D1             BD25     SKX_EXT_B_BGA1-IC,TBD
CLK_100M_CPU1_RC_REFCLK1_R_DN EU4D2            64       NB3W1200L_LCC-IC,H13585-001
CLK_100M_CPU1_RC_REFCLK1_R_DN R4D28            1        RES_0402-27.4,1%,1/16W,CHIP,G2A
CLK_100M_CPU1_RC_REFCLK1_R_DP EU4D2            63       NB3W1200L_LCC-IC,H13585-001
CLK_100M_CPU1_RC_REFCLK1_R_DP R4D23            1        RES_0402-27.4,1%,1/16W,CHIP,G2A
CLK_100M_DB1200_DN       EU4D2            10       NB3W1200L_LCC-IC,H13585-001
CLK_100M_DB1200_DN       U7C1             K35      LBG_CORE_QAT_EXT_D_BGA1-IC,H91A
CLK_100M_DB1200_DP       EU4D2            9        NB3W1200L_LCC-IC,H13585-001
CLK_100M_DB1200_DP       U7C1             H35      LBG_CORE_QAT_EXT_D_BGA1-IC,H91A
CLK_100M_M2_DN           J8F1             53       SCONN75K_H17033002_SMT1-SCONN,A
CLK_100M_M2_DN           U7C1             K27      LBG_CORE_QAT_EXT_D_BGA1-IC,H91A
CLK_100M_M2_DP           J8F1             55       SCONN75K_H17033002_SMT1-SCONN,A
CLK_100M_M2_DP           U7C1             H27      LBG_CORE_QAT_EXT_D_BGA1-IC,H91A
CLK_100M_MEZZ1_DN        J9B3             50       SCONN120_A28699018_SM-SCONN,A2A
CLK_100M_MEZZ1_DN        U7C1             D31      LBG_CORE_QAT_EXT_D_BGA1-IC,H91A
CLK_100M_MEZZ1_DP        J9B3             48       SCONN120_A28699018_SM-SCONN,A2A
CLK_100M_MEZZ1_DP        U7C1             B31      LBG_CORE_QAT_EXT_D_BGA1-IC,H91A
CLK_100M_MEZZ2_DN        J9B3             53       SCONN120_A28699018_SM-SCONN,A2A
CLK_100M_MEZZ2_DN        U7C1             J26      LBG_CORE_QAT_EXT_D_BGA1-IC,H91A
CLK_100M_MEZZ2_DP        J9B3             51       SCONN120_A28699018_SM-SCONN,A2A
CLK_100M_MEZZ2_DP        U7C1             G26      LBG_CORE_QAT_EXT_D_BGA1-IC,H91A
CLK_100M_MEZZ3_DN        J8E3             71       SCONN80_E67482007_SM-CONN,E674A
CLK_100M_MEZZ3_DN        U7C1             B23      LBG_CORE_QAT_EXT_D_BGA1-IC,H91A
CLK_100M_MEZZ3_DP        J8E3             69       SCONN80_E67482007_SM-CONN,E674A
CLK_100M_MEZZ3_DP        U7C1             D23      LBG_CORE_QAT_EXT_D_BGA1-IC,H91A
CLK_100M_MEZZ4_DN        J8E3             76       SCONN80_E67482007_SM-CONN,E674A
CLK_100M_MEZZ4_DN        U7C1             B21      LBG_CORE_QAT_EXT_D_BGA1-IC,H91A
CLK_100M_MEZZ4_DP        J8E3             74       SCONN80_E67482007_SM-CONN,E674A
CLK_100M_MEZZ4_DP        U7C1             D21      LBG_CORE_QAT_EXT_D_BGA1-IC,H91A
CLK_100M_PCH_SLOTX24_S0_DN J8G1             35       SCONN200_H68296001_SM-CONN,H68A
CLK_100M_PCH_SLOTX24_S0_DN U7C1             J33      LBG_CORE_QAT_EXT_D_BGA1-IC,H91A
CLK_100M_PCH_SLOTX24_S0_DP J8G1             33       SCONN200_H68296001_SM-CONN,H68A
CLK_100M_PCH_SLOTX24_S0_DP U7C1             G33      LBG_CORE_QAT_EXT_D_BGA1-IC,H91A
CLK_100M_PCH_SLOTX24_S1_DN J8G1             38       SCONN200_H68296001_SM-CONN,H68A
CLK_100M_PCH_SLOTX24_S1_DN U7C1             K42      LBG_CORE_QAT_EXT_D_BGA1-IC,H91A
CLK_100M_PCH_SLOTX24_S1_DP J8G1             36       SCONN200_H68296001_SM-CONN,H68A
CLK_100M_PCH_SLOTX24_S1_DP U7C1             H42      LBG_CORE_QAT_EXT_D_BGA1-IC,H91A
CLK_100M_PCH_SLOTX24_S2_DN J8G1             41       SCONN200_H68296001_SM-CONN,H68A
CLK_100M_PCH_SLOTX24_S2_DN U7C1             A28      LBG_CORE_QAT_EXT_D_BGA1-IC,H91A
CLK_100M_PCH_SLOTX24_S2_DP J8G1             39       SCONN200_H68296001_SM-CONN,H68A
CLK_100M_PCH_SLOTX24_S2_DP U7C1             C28      LBG_CORE_QAT_EXT_D_BGA1-IC,H91A
CLK_100M_PCH_SLOTX24_S3_DN J8G1             44       SCONN200_H68296001_SM-CONN,H68A
CLK_100M_PCH_SLOTX24_S3_DN U7C1             J40      LBG_CORE_QAT_EXT_D_BGA1-IC,H91A
CLK_100M_PCH_SLOTX24_S3_DP J8G1             42       SCONN200_H68296001_SM-CONN,H68A
CLK_100M_PCH_SLOTX24_S3_DP U7C1             G40      LBG_CORE_QAT_EXT_D_BGA1-IC,H91A
CLK_100M_PCH_SLOTX24_S4_DN J8G1             47       SCONN200_H68296001_SM-CONN,H68A
CLK_100M_PCH_SLOTX24_S4_DN U7C1             D33      LBG_CORE_QAT_EXT_D_BGA1-IC,H91A
CLK_100M_PCH_SLOTX24_S4_DP J8G1             45       SCONN200_H68296001_SM-CONN,H68A
CLK_100M_PCH_SLOTX24_S4_DP U7C1             B33      LBG_CORE_QAT_EXT_D_BGA1-IC,H91A
CLK_100M_PCH_SLOTX24_S5_DN J8G1             50       SCONN200_H68296001_SM-CONN,H68A
CLK_100M_PCH_SLOTX24_S5_DN U7C1             H31      LBG_CORE_QAT_EXT_D_BGA1-IC,H91A
CLK_100M_PCH_SLOTX24_S5_DP J8G1             48       SCONN200_H68296001_SM-CONN,H68A
CLK_100M_PCH_SLOTX24_S5_DP U7C1             K31      LBG_CORE_QAT_EXT_D_BGA1-IC,H91A
CLK_100M_PCH_XDP_DN      J9A3             42       SCONN60_C21100002_SMLF-CONN,C2A
CLK_100M_PCH_XDP_DN      U7C1             A39      LBG_CORE_QAT_EXT_D_BGA1-IC,H91A
CLK_100M_PCH_XDP_DP      J9A3             40       SCONN60_C21100002_SMLF-CONN,C2A
CLK_100M_PCH_XDP_DP      U7C1             C39      LBG_CORE_QAT_EXT_D_BGA1-IC,H91A
CLK_100M_SPRV_DN         EU9E1            25       SPRINGVILLE_SM1-IC,G47144-004
CLK_100M_SPRV_DN         U7C1             C20      LBG_CORE_QAT_EXT_D_BGA1-IC,H91A
CLK_100M_SPRV_DP         EU9E1            26       SPRINGVILLE_SM1-IC,G47144-004
CLK_100M_SPRV_DP         U7C1             A20      LBG_CORE_QAT_EXT_D_BGA1-IC,H91A
CLK_156M_OSC_BRD_CPU0_DN R6F7             1        RES_0402-0.0,5%,1/16W,CHIP,G21A
CLK_156M_OSC_BRD_CPU0_DN Y6F1             5        OSC_C_6P10-156.25MHZ,OSC,G6383A
CLK_156M_OSC_BRD_CPU0_DP R6F9             1        RES_0402-0.0,5%,1/16W,CHIP,G21A
CLK_156M_OSC_BRD_CPU0_DP Y6F1             4        OSC_C_6P10-156.25MHZ,OSC,G6383A
CLK_156M_OSC_BRD_CPU1_DN R3F2             1        RES_0402-0.0,5%,1/16W,CHIP,G21A
CLK_156M_OSC_BRD_CPU1_DN Y3F1             5        OSC_C_6P10-156.25MHZ,OSC,G6383A
CLK_156M_OSC_BRD_CPU1_DP R3F4             1        RES_0402-0.0,5%,1/16W,CHIP,G21A
CLK_156M_OSC_BRD_CPU1_DP Y3F1             4        OSC_C_6P10-156.25MHZ,OSC,G6383A
CLK_156M_OSC_CPU0_HFI_DN R6F6             2        RES_0402-0.0,5%,1/16W,EMPTY,G2A
CLK_156M_OSC_CPU0_HFI_DN R6F7             2        RES_0402-0.0,5%,1/16W,CHIP,G21A
CLK_156M_OSC_CPU0_HFI_DN U5D1             BE16     SKX_EXT_B_BGA1-IC,TBD
CLK_156M_OSC_CPU0_HFI_DP R6F8             2        RES_0402-0.0,5%,1/16W,EMPTY,G2A
CLK_156M_OSC_CPU0_HFI_DP R6F9             2        RES_0402-0.0,5%,1/16W,CHIP,G21A
CLK_156M_OSC_CPU0_HFI_DP U5D1             BG16     SKX_EXT_B_BGA1-IC,TBD
CLK_156M_OSC_CPU1_HFI_DN R3F1             2        RES_0402-0.0,5%,1/16W,EMPTY,G2A
CLK_156M_OSC_CPU1_HFI_DN R3F2             2        RES_0402-0.0,5%,1/16W,CHIP,G21A
CLK_156M_OSC_CPU1_HFI_DN U2D1             BE16     SKX_EXT_B_BGA1-IC,TBD
CLK_156M_OSC_CPU1_HFI_DP R3F3             2        RES_0402-0.0,5%,1/16W,EMPTY,G2A
CLK_156M_OSC_CPU1_HFI_DP R3F4             2        RES_0402-0.0,5%,1/16W,CHIP,G21A
CLK_156M_OSC_CPU1_HFI_DP U2D1             BG16     SKX_EXT_B_BGA1-IC,TBD
CLK_24M_25M_BMC_CLKIN    R9F60            2        RES_0402-0.0,5%,1/16W,EMPTY,G2A
CLK_24M_25M_BMC_CLKIN    R9F62            2        RES_0402-0.0,5%,1/16W,CHIP,G21A
CLK_24M_25M_BMC_CLKIN    U9F4             AB22     AST1250_BGA-IC,G85138-002
CLK_24M_BMC_CLKIN_R      R9F62            1        RES_0402-0.0,5%,1/16W,CHIP,G21A
CLK_24M_BMC_CLKIN_R      Y9F2             3        OSC_C_SM4-24MHZ,OSC,D34520-021
CLK_24M_BMC_LPC          R2T15            1        RES_0402-100.0K,1%,1/16W,CHIP,A
CLK_24M_BMC_LPC          R7C26            1        RES_0402-33.2,1%,1/16W,CHIP,G2A
CLK_24M_BMC_LPC          U9F4             B20      AST1250_BGA-IC,G85138-002
CLK_24M_BMC_LPC_R        R7C26            2        RES_0402-33.2,1%,1/16W,CHIP,G2A
CLK_24M_BMC_LPC_R        U7C1             R3       LBG_CORE_QAT_EXT_D_BGA1-IC,H91A
CLK_25M_BMC              R8F29            2        RES_0402-33.2,1%,1/16W,CHIP,G2A
CLK_25M_BMC              R9F60            1        RES_0402-0.0,5%,1/16W,EMPTY,G2A
CLK_25M_BMC_R            EU8F2            16       ICS9FGP204_MLFP-IC,E95226-001
CLK_25M_BMC_R            R8F29            1        RES_0402-33.2,1%,1/16W,CHIP,G2A
CLK_25M_CPLD             R2T47            2        RES_0402-33.2,1%,1/16W,CHIP,G2A
CLK_25M_CPLD             U8D7             L2       LCMXO2_A_256BGA-IC,H63395-001
CLK_25M_CPLD_R           EU8F2            17       ICS9FGP204_MLFP-IC,E95226-001
CLK_25M_CPLD_R           R2T47            1        RES_0402-33.2,1%,1/16W,CHIP,G2A
CLK_322M_156M_CPU0_OSC_VRM_DN J6E1             F5       SCONN120_H61426002_SM-CONN,H61A
CLK_322M_156M_CPU0_OSC_VRM_DN R6F6             1        RES_0402-0.0,5%,1/16W,EMPTY,G2A
CLK_322M_156M_CPU0_OSC_VRM_DN R6F10            1        RES_0402-0.0,5%,1/16W,EMPTY,G2A
CLK_322M_156M_CPU0_OSC_VRM_DP J6E1             E5       SCONN120_H61426002_SM-CONN,H61A
CLK_322M_156M_CPU0_OSC_VRM_DP R6F8             1        RES_0402-0.0,5%,1/16W,EMPTY,G2A
CLK_322M_156M_CPU0_OSC_VRM_DP R6F11            1        RES_0402-0.0,5%,1/16W,EMPTY,G2A
CLK_322M_156M_CPU1_OSC_VRM_DN J4E1             F5       SCONN120_H61426002_SM-CONN,H61A
CLK_322M_156M_CPU1_OSC_VRM_DN R3F1             1        RES_0402-0.0,5%,1/16W,EMPTY,G2A
CLK_322M_156M_CPU1_OSC_VRM_DN R3F5             1        RES_0402-0.0,5%,1/16W,EMPTY,G2A
CLK_322M_156M_CPU1_OSC_VRM_DP J4E1             E5       SCONN120_H61426002_SM-CONN,H61A
CLK_322M_156M_CPU1_OSC_VRM_DP R3F3             1        RES_0402-0.0,5%,1/16W,EMPTY,G2A
CLK_322M_156M_CPU1_OSC_VRM_DP R3F6             1        RES_0402-0.0,5%,1/16W,EMPTY,G2A
CLK_322M_OSC_CPU0_RC_DN  R6F10            2        RES_0402-0.0,5%,1/16W,EMPTY,G2A
CLK_322M_OSC_CPU0_RC_DN  U5D1             AL26     SKX_EXT_B_BGA1-IC,TBD
CLK_322M_OSC_CPU0_RC_DP  R6F11            2        RES_0402-0.0,5%,1/16W,EMPTY,G2A
CLK_322M_OSC_CPU0_RC_DP  U5D1             AK27     SKX_EXT_B_BGA1-IC,TBD
CLK_322M_OSC_CPU1_RC_DN  R3F5             2        RES_0402-0.0,5%,1/16W,EMPTY,G2A
CLK_322M_OSC_CPU1_RC_DN  U2D1             AL26     SKX_EXT_B_BGA1-IC,TBD
CLK_322M_OSC_CPU1_RC_DP  R3F6             2        RES_0402-0.0,5%,1/16W,EMPTY,G2A
CLK_322M_OSC_CPU1_RC_DP  U2D1             AK27     SKX_EXT_B_BGA1-IC,TBD
CLK_32K_SUSCLK_PLD       R8F27            2        RES_0402-22.1,1.0%,1/16W,CHIP,A
CLK_32K_SUSCLK_PLD       U8D7             E1       LCMXO2_A_256BGA-IC,H63395-001
CLK_32K_SUSCLK_PLD_R     EU8F2            13       ICS9FGP204_MLFP-IC,E95226-001
CLK_32K_SUSCLK_PLD_R     R8F27            1        RES_0402-22.1,1.0%,1/16W,CHIP,A
CLK_48M_USB_BMC          U7C1             BW50     LBG_CORE_QAT_EXT_D_BGA1-IC,H91A
CLK_48M_USB_BMC          U9F4             Y21      AST1250_BGA-IC,G85138-002
CLK_50M_CKMNG_BMC_1      R2T46            2        RES_0402-22.1,1.0%,1/16W,CHIP,A
CLK_50M_CKMNG_BMC_1      U9F4             E11      AST1250_BGA-IC,G85138-002
CLK_50M_CKMNG_BMC_1_R    EU8F2            32       ICS9FGP204_MLFP-IC,E95226-001
CLK_50M_CKMNG_BMC_1_R    R2T46            1        RES_0402-22.1,1.0%,1/16W,CHIP,A
CLK_50M_CKMNG_BMC_2      R8G1             2        RES_0402-33.2,1%,1/16W,CHIP,G2A
CLK_50M_CKMNG_BMC_2      U9F4             C9       AST1250_BGA-IC,G85138-002
CLK_50M_CKMNG_BMC_2_R    EU8F2            29       ICS9FGP204_MLFP-IC,E95226-001
CLK_50M_CKMNG_BMC_2_R    R8G1             1        RES_0402-33.2,1%,1/16W,CHIP,G2A
CLK_50M_CKMNG_OCP        J9B3             29       SCONN120_A28699018_SM-SCONN,A2A
CLK_50M_CKMNG_OCP        R2T42            2        RES_0402-22.1,1.0%,1/16W,CHIP,A
CLK_50M_CKMNG_OCP_R      EU8F2            33       ICS9FGP204_MLFP-IC,E95226-001
CLK_50M_CKMNG_OCP_R      R2T42            1        RES_0402-22.1,1.0%,1/16W,CHIP,A
CLK_50M_CKMNG_PCH_10GBE  R7C20            1        RES_0402-10.0K,1%,1/16W,CHIP,GA
CLK_50M_CKMNG_PCH_10GBE  R8G24            2        RES_0402-33.2,1%,1/16W,CHIP,G2A
CLK_50M_CKMNG_PCH_10GBE  U7C1             AJ1      LBG_CORE_QAT_EXT_D_BGA1-IC,H91A
CLK_50M_CKMNG_PCH_10GBE_R EU8F2            25       ICS9FGP204_MLFP-IC,E95226-001
CLK_50M_CKMNG_PCH_10GBE_R R8G24            1        RES_0402-33.2,1%,1/16W,CHIP,G2A
CLK_50M_CKMNG_SPRVLLE    EU9E1            2        SPRINGVILLE_SM1-IC,G47144-004
CLK_50M_CKMNG_SPRVLLE    R1R12            1        RES_0402-10.0K,1%,1/16W,CHIP,GA
CLK_50M_CKMNG_SPRVLLE    R8G25            2        RES_0402-33.2,1%,1/16W,CHIP,G2A
CLK_50M_CKMNG_SPRVLLE_R  EU8F2            28       ICS9FGP204_MLFP-IC,E95226-001
CLK_50M_CKMNG_SPRVLLE_R  R8G25            1        RES_0402-33.2,1%,1/16W,CHIP,G2A
DMI_CPU0_PCH_RX_C_DN<0>  C3M44            2        CAP_0402-0.22UF,16V,10%,X7R,A3A
DMI_CPU0_PCH_RX_C_DN<0>  U5D1             CK9      SKX_EXT_B_BGA1-IC,TBD
DMI_CPU0_PCH_RX_C_DN<1>  C3M41            2        CAP_0402-0.22UF,16V,10%,X7R,A3A
DMI_CPU0_PCH_RX_C_DN<1>  U5D1             CM11     SKX_EXT_B_BGA1-IC,TBD
DMI_CPU0_PCH_RX_C_DN<2>  C3M45            2        CAP_0402-0.22UF,16V,10%,X7R,A3A
DMI_CPU0_PCH_RX_C_DN<2>  U5D1             CR12     SKX_EXT_B_BGA1-IC,TBD
DMI_CPU0_PCH_RX_C_DN<3>  C3N13            2        CAP_0402-0.22UF,16V,10%,X7R,A3A
DMI_CPU0_PCH_RX_C_DN<3>  U5D1             CT11     SKX_EXT_B_BGA1-IC,TBD
DMI_CPU0_PCH_RX_C_DP<0>  C3M40            2        CAP_0402-0.22UF,16V,10%,X7R,A3A
DMI_CPU0_PCH_RX_C_DP<0>  U5D1             CL10     SKX_EXT_B_BGA1-IC,TBD
DMI_CPU0_PCH_RX_C_DP<1>  C3M37            2        CAP_0402-0.22UF,16V,10%,X7R,A3A
DMI_CPU0_PCH_RX_C_DP<1>  U5D1             CN10     SKX_EXT_B_BGA1-IC,TBD
DMI_CPU0_PCH_RX_C_DP<2>  C3N9             2        CAP_0402-0.22UF,16V,10%,X7R,A3A
DMI_CPU0_PCH_RX_C_DP<2>  U5D1             CP11     SKX_EXT_B_BGA1-IC,TBD
DMI_CPU0_PCH_RX_C_DP<3>  C3N8             2        CAP_0402-0.22UF,16V,10%,X7R,A3A
DMI_CPU0_PCH_RX_C_DP<3>  U5D1             CV11     SKX_EXT_B_BGA1-IC,TBD
DMI_CPU0_PCH_RX_DN<0>    C3M44            1        CAP_0402-0.22UF,16V,10%,X7R,A3A
DMI_CPU0_PCH_RX_DN<0>    U7C1             H46      LBG_CORE_QAT_EXT_D_BGA1-IC,H91A
DMI_CPU0_PCH_RX_DN<1>    C3M41            1        CAP_0402-0.22UF,16V,10%,X7R,A3A
DMI_CPU0_PCH_RX_DN<1>    U7C1             J48      LBG_CORE_QAT_EXT_D_BGA1-IC,H91A
DMI_CPU0_PCH_RX_DN<2>    C3M45            1        CAP_0402-0.22UF,16V,10%,X7R,A3A
DMI_CPU0_PCH_RX_DN<2>    U7C1             K50      LBG_CORE_QAT_EXT_D_BGA1-IC,H91A
DMI_CPU0_PCH_RX_DN<3>    C3N13            1        CAP_0402-0.22UF,16V,10%,X7R,A3A
DMI_CPU0_PCH_RX_DN<3>    U7C1             P52      LBG_CORE_QAT_EXT_D_BGA1-IC,H91A
DMI_CPU0_PCH_RX_DP<0>    C3M40            1        CAP_0402-0.22UF,16V,10%,X7R,A3A
DMI_CPU0_PCH_RX_DP<0>    U7C1             K46      LBG_CORE_QAT_EXT_D_BGA1-IC,H91A
DMI_CPU0_PCH_RX_DP<1>    C3M37            1        CAP_0402-0.22UF,16V,10%,X7R,A3A
DMI_CPU0_PCH_RX_DP<1>    U7C1             H50      LBG_CORE_QAT_EXT_D_BGA1-IC,H91A
DMI_CPU0_PCH_RX_DP<2>    C3N9             1        CAP_0402-0.22UF,16V,10%,X7R,A3A
DMI_CPU0_PCH_RX_DP<2>    U7C1             M52      LBG_CORE_QAT_EXT_D_BGA1-IC,H91A
DMI_CPU0_PCH_RX_DP<3>    C3N8             1        CAP_0402-0.22UF,16V,10%,X7R,A3A
DMI_CPU0_PCH_RX_DP<3>    U7C1             N54      LBG_CORE_QAT_EXT_D_BGA1-IC,H91A
DMI_CPU0_PCH_TX_C_DN<0>  C7C3             2        CAP_0402-0.22UF,16V,10%,X7R,A3A
DMI_CPU0_PCH_TX_C_DN<0>  U7C1             D42      LBG_CORE_QAT_EXT_D_BGA1-IC,H91A
DMI_CPU0_PCH_TX_C_DN<1>  C7C1             2        CAP_0402-0.22UF,16V,10%,X7R,A3A
DMI_CPU0_PCH_TX_C_DN<1>  U7C1             C43      LBG_CORE_QAT_EXT_D_BGA1-IC,H91A
DMI_CPU0_PCH_TX_C_DN<2>  C7B29            2        CAP_0402-0.22UF,16V,10%,X7R,A3A
DMI_CPU0_PCH_TX_C_DN<2>  U7C1             D44      LBG_CORE_QAT_EXT_D_BGA1-IC,H91A
DMI_CPU0_PCH_TX_C_DN<3>  C7B26            2        CAP_0402-0.22UF,16V,10%,X7R,A3A
DMI_CPU0_PCH_TX_C_DN<3>  U7C1             C45      LBG_CORE_QAT_EXT_D_BGA1-IC,H91A
DMI_CPU0_PCH_TX_C_DP<0>  C7C2             2        CAP_0402-0.22UF,16V,10%,X7R,A3A
DMI_CPU0_PCH_TX_C_DP<0>  U7C1             B42      LBG_CORE_QAT_EXT_D_BGA1-IC,H91A
DMI_CPU0_PCH_TX_C_DP<1>  C7B28            2        CAP_0402-0.22UF,16V,10%,X7R,A3A
DMI_CPU0_PCH_TX_C_DP<1>  U7C1             A43      LBG_CORE_QAT_EXT_D_BGA1-IC,H91A
DMI_CPU0_PCH_TX_C_DP<2>  C7B27            2        CAP_0402-0.22UF,16V,10%,X7R,A3A
DMI_CPU0_PCH_TX_C_DP<2>  U7C1             B44      LBG_CORE_QAT_EXT_D_BGA1-IC,H91A
DMI_CPU0_PCH_TX_C_DP<3>  C7B25            2        CAP_0402-0.22UF,16V,10%,X7R,A3A
DMI_CPU0_PCH_TX_C_DP<3>  U7C1             A45      LBG_CORE_QAT_EXT_D_BGA1-IC,H91A
DMI_CPU0_PCH_TX_DN<0>    C7C3             1        CAP_0402-0.22UF,16V,10%,X7R,A3A
DMI_CPU0_PCH_TX_DN<0>    U5D1             CG4      SKX_EXT_B_BGA1-IC,TBD
DMI_CPU0_PCH_TX_DN<1>    C7C1             1        CAP_0402-0.22UF,16V,10%,X7R,A3A
DMI_CPU0_PCH_TX_DN<1>    U5D1             CJ4      SKX_EXT_B_BGA1-IC,TBD
DMI_CPU0_PCH_TX_DN<2>    C7B29            1        CAP_0402-0.22UF,16V,10%,X7R,A3A
DMI_CPU0_PCH_TX_DN<2>    U5D1             CN4      SKX_EXT_B_BGA1-IC,TBD
DMI_CPU0_PCH_TX_DN<3>    C7B26            1        CAP_0402-0.22UF,16V,10%,X7R,A3A
DMI_CPU0_PCH_TX_DN<3>    U5D1             CP5      SKX_EXT_B_BGA1-IC,TBD
DMI_CPU0_PCH_TX_DP<0>    C7C2             1        CAP_0402-0.22UF,16V,10%,X7R,A3A
DMI_CPU0_PCH_TX_DP<0>    U5D1             CH5      SKX_EXT_B_BGA1-IC,TBD
DMI_CPU0_PCH_TX_DP<1>    C7B28            1        CAP_0402-0.22UF,16V,10%,X7R,A3A
DMI_CPU0_PCH_TX_DP<1>    U5D1             CL4      SKX_EXT_B_BGA1-IC,TBD
DMI_CPU0_PCH_TX_DP<2>    C7B27            1        CAP_0402-0.22UF,16V,10%,X7R,A3A
DMI_CPU0_PCH_TX_DP<2>    U5D1             CM3      SKX_EXT_B_BGA1-IC,TBD
DMI_CPU0_PCH_TX_DP<3>    C7B25            1        CAP_0402-0.22UF,16V,10%,X7R,A3A
DMI_CPU0_PCH_TX_DP<3>    U5D1             CR4      SKX_EXT_B_BGA1-IC,TBD
FAN_PWM_OUT_SYS0         U7C1             BG11     LBG_CORE_QAT_EXT_D_BGA1-IC,H91A
FAN_PWM_OUT_SYS0         U8G2             2        TTL1G07_A_SOP-74LVC1G07,IC,C88B
FAN_PWM_OUT_SYS0         U9F4             W4       AST1250_BGA-IC,G85138-002
FAN_PWM_OUT_SYS0_BUF     R2U42            1        RES_0402-221,1.0%,1/16W,CHIP,GA
FAN_PWM_OUT_SYS0_BUF     U8G2             4        TTL1G07_A_SOP-74LVC1G07,IC,C88B
FAN_PWM_OUT_SYS0_R       CR1E1            2        DIODE_SM-SDMK0340L,EMPTY,H7179A
FAN_PWM_OUT_SYS0_R       J1F2             4        CONN6_C74770005_PIP-HDR,C74770A
FAN_PWM_OUT_SYS0_R       R1E12            2        RES_0402-4.75K,1%,1/16W,CHIP,GA
FAN_PWM_OUT_SYS0_R       R2U42            2        RES_0402-221,1.0%,1/16W,CHIP,GA
FAN_PWM_OUT_SYS0_R       R9T1             1        RES_0402-0.0,5%,1/16W,CHIP,G21A
FAN_PWM_OUT_SYS0_R1      J1F1             F4       CONN76_H22707001_THMT1-CONN,H2A
FAN_PWM_OUT_SYS0_R1      R1F9             2        RES_0402-0.0,5%,1/16W,EMPTY,G2A
FAN_PWM_OUT_SYS0_R1      R9T1             2        RES_0402-0.0,5%,1/16W,CHIP,G21A
FAN_PWM_OUT_SYS1         U7C1             AV11     LBG_CORE_QAT_EXT_D_BGA1-IC,H91A
FAN_PWM_OUT_SYS1         U8G3             2        TTL1G07_A_SOP-74LVC1G07,IC,C88B
FAN_PWM_OUT_SYS1         U9F4             Y3       AST1250_BGA-IC,G85138-002
FAN_PWM_OUT_SYS1_BUF     R2U44            1        RES_0402-221,1.0%,1/16W,CHIP,GA
FAN_PWM_OUT_SYS1_BUF     U8G3             4        TTL1G07_A_SOP-74LVC1G07,IC,C88B
FAN_PWM_OUT_SYS1_R       CR1B1            2        DIODE_SM-SDMK0340L,EMPTY,H7179A
FAN_PWM_OUT_SYS1_R       J1B2             4        CONN6_C74770005_PIP-HDR,C74770A
FAN_PWM_OUT_SYS1_R       R2U44            2        RES_0402-221,1.0%,1/16W,CHIP,GA
FAN_PWM_OUT_SYS1_R       R7F33            2        RES_0402-4.75K,1%,1/16W,CHIP,GA
FAN_TACH0                C1F9             1        CAP_A_0402V-0.01UF,25V,10%,X7RA
FAN_TACH0                R1F1             2        RES_0402-4.75K,1%,1/16W,CHIP,GA
FAN_TACH0                R1F2             1        RES_0402-100.0,1%,1/16W,CHIP,GA
FAN_TACH0                R1F8             1        RES_0402-0.0,5%,1/16W,CHIP,G21A
FAN_TACH0                R1U1             1        RES_0402-100.0K,1%,1/16W,CHIP,A
FAN_TACH0                U7C1             AY11     LBG_CORE_QAT_EXT_D_BGA1-IC,H91A
FAN_TACH0                U9F4             V6       AST1250_BGA-IC,G85138-002
FAN_TACH0_CPU0_D1        CR1F1            1        DIODE_SM-SDMK0340L,IC,H71799-0A
FAN_TACH0_CPU0_D1        J1F2             3        CONN6_C74770005_PIP-HDR,C74770A
FAN_TACH0_CPU0_D2        CR1F1            2        DIODE_SM-SDMK0340L,IC,H71799-0A
FAN_TACH0_CPU0_D2        R1F2             2        RES_0402-100.0,1%,1/16W,CHIP,GA
FAN_TACH0_R              J1F1             D4       CONN76_H22707001_THMT1-CONN,H2A
FAN_TACH0_R              R1C31            2        RES_0402-0.0,5%,1/16W,EMPTY,G2A
FAN_TACH0_R              R1F8             2        RES_0402-0.0,5%,1/16W,CHIP,G21A
FAN_TACH1                C9T1             1        CAP_A_0402V-0.01UF,25V,10%,X7RA
FAN_TACH1                R1U2             1        RES_0402-100.0K,1%,1/16W,CHIP,A
FAN_TACH1                R9R10            1        RES_0402-0.0,5%,1/16W,CHIP,G21A
FAN_TACH1                R9T5             2        RES_0402-4.75K,1%,1/16W,CHIP,GA
FAN_TACH1                R9T7             1        RES_0402-100.0,1%,1/16W,CHIP,GA
FAN_TACH1                U7C1             AV15     LBG_CORE_QAT_EXT_D_BGA1-IC,H91A
FAN_TACH1                U9F4             Y5       AST1250_BGA-IC,G85138-002
FAN_TACH1_CPU1_D1        CR1F2            1        DIODE_SM-SDMK0340L,IC,H71799-0A
FAN_TACH1_CPU1_D1        J1F2             5        CONN6_C74770005_PIP-HDR,C74770A
FAN_TACH1_CPU1_D2        CR1F2            2        DIODE_SM-SDMK0340L,IC,H71799-0A
FAN_TACH1_CPU1_D2        R9T7             2        RES_0402-100.0,1%,1/16W,CHIP,GA
FAN_TACH1_R              J1F1             C4       CONN76_H22707001_THMT1-CONN,H2A
FAN_TACH1_R              R1C11            2        RES_0402-0.0,5%,1/16W,EMPTY,G2A
FAN_TACH1_R              R9R10            2        RES_0402-0.0,5%,1/16W,CHIP,G21A
FAN_TACH2                C1B15            1        CAP_A_0402V-0.01UF,25V,10%,X7RA
FAN_TACH2                R1B21            2        RES_0402-4.75K,1%,1/16W,CHIP,GA
FAN_TACH2                R1B22            1        RES_0402-100.0,1%,1/16W,CHIP,GA
FAN_TACH2                R1U4             1        RES_0402-100.0K,1%,1/16W,CHIP,A
FAN_TACH2                R9R12            1        RES_0402-0.0,5%,1/16W,CHIP,G21A
FAN_TACH2                U7C1             BE22     LBG_CORE_QAT_EXT_D_BGA1-IC,H91A
FAN_TACH2                U9F4             AA4      AST1250_BGA-IC,G85138-002
FAN_TACH2_CPU1_D1        CR1B2            1        DIODE_SM-SDMK0340L,IC,H71799-0A
FAN_TACH2_CPU1_D1        J1B2             3        CONN6_C74770005_PIP-HDR,C74770A
FAN_TACH2_CPU1_D2        CR1B2            2        DIODE_SM-SDMK0340L,IC,H71799-0A
FAN_TACH2_CPU1_D2        R1B22            2        RES_0402-100.0,1%,1/16W,CHIP,GA
FAN_TACH2_R              J1F1             B4       CONN76_H22707001_THMT1-CONN,H2A
FAN_TACH2_R              R1C9             2        RES_0402-0.0,5%,1/16W,EMPTY,G2A
FAN_TACH2_R              R9R12            2        RES_0402-0.0,5%,1/16W,CHIP,G21A
FAN_TACH3                C1B17            1        CAP_A_0402V-0.01UF,25V,10%,X7RA
FAN_TACH3                R1B23            1        RES_0402-100.0,1%,1/16W,CHIP,GA
FAN_TACH3                R1B24            2        RES_0402-4.75K,1%,1/16W,CHIP,GA
FAN_TACH3                R1U5             1        RES_0402-100.0K,1%,1/16W,CHIP,A
FAN_TACH3                R9R9             1        RES_0402-0.0,5%,1/16W,CHIP,G21A
FAN_TACH3                U7C1             AY7      LBG_CORE_QAT_EXT_D_BGA1-IC,H91A
FAN_TACH3                U9F4             AB3      AST1250_BGA-IC,G85138-002
FAN_TACH3_CPU1_D1        CR1B3            1        DIODE_SM-SDMK0340L,IC,H71799-0A
FAN_TACH3_CPU1_D1        J1B2             5        CONN6_C74770005_PIP-HDR,C74770A
FAN_TACH3_CPU1_D2        CR1B3            2        DIODE_SM-SDMK0340L,IC,H71799-0A
FAN_TACH3_CPU1_D2        R1B23            2        RES_0402-100.0,1%,1/16W,CHIP,GA
FAN_TACH3_R              J1F1             A4       CONN76_H22707001_THMT1-CONN,H2A
FAN_TACH3_R              R1C10            2        RES_0402-0.0,5%,1/16W,EMPTY,G2A
FAN_TACH3_R              R9R9             2        RES_0402-0.0,5%,1/16W,CHIP,G21A
FM_100M_N                EU4D2            4        NB3W1200L_LCC-IC,H13585-001
FM_100M_N                R4D40            2        RES_0402-4.75K,1%,1/16W,CHIP,GA
FM_100M_N                R6P23            1        RES_0402-4.75K,1%,1/16W,EMPTY,A
FM_10GBE_LOM_DISABLE_N   R8C23            2        RES_0402-0.0,5%,1/16W,EMPTY,G2A
FM_10GBE_LOM_DISABLE_N   U7C1             BY21     LBG_CORE_QAT_EXT_D_BGA1-IC,H91A
FM_156M_CPU0_BRD_OSC_EN  R8D43            1        RES_0402-0.0,5%,1/16W,CHIP,G21A
FM_156M_CPU0_BRD_OSC_EN  U8D7             T10      LCMXO2_A_256BGA-IC,H63395-001
FM_156M_CPU1_BRD_OSC_EN  R7D36            1        RES_0402-0.0,5%,1/16W,CHIP,G21A
FM_156M_CPU1_BRD_OSC_EN  U8D7             N8       LCMXO2_A_256BGA-IC,H63395-001
FM_1GB_LOM_DISABLE_N     EU9E1            28       SPRINGVILLE_SM1-IC,G47144-004
FM_1GB_LOM_DISABLE_N     R8C24            2        RES_0402-0.0,5%,1/16W,CHIP,G21A
FM_ADC128_A0             EU9G1            7        ADC128D818_SM-IC,H63642-001
FM_ADC128_A0             R1U45            1        RES_0402-4.75K,1%,1/16W,CHIP,GA
FM_ADC128_A0             R9G23            2        RES_0402-4.75K,1%,1/16W,EMPTY,A
FM_ADC128_A1             EU9G1            8        ADC128D818_SM-IC,H63642-001
FM_ADC128_A1             R1U48            1        RES_0402-4.75K,1%,1/16W,CHIP,GA
FM_ADC128_A1             R9G25            2        RES_0402-4.75K,1%,1/16W,EMPTY,A
FM_ADR_COMPLETE          R2N26            1        RES_0402-33.2,1%,1/16W,CHIP,G2A
FM_ADR_COMPLETE          R4T2             1        RES_0402-0.0,5%,1/16W,EMPTY,G2A
FM_ADR_COMPLETE          U8D7             C8       LCMXO2_A_256BGA-IC,H63395-001
FM_ADR_COMPLETE_ABC_N    J4G1             230      SCONN288_H44441004_PIP-SCONN,HA
FM_ADR_COMPLETE_ABC_N    J4G2             230      SCONN288_H44441004_PIP-SCONN,HA
FM_ADR_COMPLETE_ABC_N    J4G3             230      SCONN288_H44441004_PIP-SCONN,HA
FM_ADR_COMPLETE_ABC_N    J6T1             230      SCONN288_H44441003_PIP-SCONN,HA
FM_ADR_COMPLETE_ABC_N    J6U1             230      SCONN288_H44441003_PIP-SCONN,HA
FM_ADR_COMPLETE_ABC_N    J6U2             230      SCONN288_H44441003_PIP-SCONN,HA
FM_ADR_COMPLETE_ABC_N    R6F4             2        RES_0402-49.9,1%,1/16W,CHIP,G2A
FM_ADR_COMPLETE_DEF_N    J4A1             230      SCONN288_H44441004_PIP-SCONN,HA
FM_ADR_COMPLETE_DEF_N    J4A2             230      SCONN288_H44441004_PIP-SCONN,HA
FM_ADR_COMPLETE_DEF_N    J4B1             230      SCONN288_H44441004_PIP-SCONN,HA
FM_ADR_COMPLETE_DEF_N    J6L1             230      SCONN288_H44441003_PIP-SCONN,HA
FM_ADR_COMPLETE_DEF_N    J6L2             230      SCONN288_H44441003_PIP-SCONN,HA
FM_ADR_COMPLETE_DEF_N    J6M1             230      SCONN288_H44441003_PIP-SCONN,HA
FM_ADR_COMPLETE_DEF_N    R6F1             2        RES_0402-49.9,1%,1/16W,CHIP,G2A
FM_ADR_COMPLETE_DLY      R4T1             1        RES_0402-0.0,5%,1/16W,CHIP,G21A
FM_ADR_COMPLETE_DLY      U8D7             B16      LCMXO2_A_256BGA-IC,H63395-001
FM_ADR_COMPLETE_GHJ_N    J1G1             230      SCONN288_H44441004_PIP-SCONN,HA
FM_ADR_COMPLETE_GHJ_N    J1G2             230      SCONN288_H44441004_PIP-SCONN,HA
FM_ADR_COMPLETE_GHJ_N    J1G3             230      SCONN288_H44441004_PIP-SCONN,HA
FM_ADR_COMPLETE_GHJ_N    J9T1             230      SCONN288_H44441003_PIP-SCONN,HA
FM_ADR_COMPLETE_GHJ_N    J9U1             230      SCONN288_H44441003_PIP-SCONN,HA
FM_ADR_COMPLETE_GHJ_N    J9U2             230      SCONN288_H44441003_PIP-SCONN,HA
FM_ADR_COMPLETE_GHJ_N    R6F5             2        RES_0402-49.9,1%,1/16W,CHIP,G2A
FM_ADR_COMPLETE_KLM_N    J1A1             230      SCONN288_H44441004_PIP-SCONN,HA
FM_ADR_COMPLETE_KLM_N    J1A2             230      SCONN288_H44441004_PIP-SCONN,HA
FM_ADR_COMPLETE_KLM_N    J1B1             230      SCONN288_H44441004_PIP-SCONN,HA
FM_ADR_COMPLETE_KLM_N    J9L1             230      SCONN288_H44441003_PIP-SCONN,HA
FM_ADR_COMPLETE_KLM_N    J9L2             230      SCONN288_H44441003_PIP-SCONN,HA
FM_ADR_COMPLETE_KLM_N    J9M1             230      SCONN288_H44441003_PIP-SCONN,HA
FM_ADR_COMPLETE_KLM_N    R6F2             2        RES_0402-49.9,1%,1/16W,CHIP,G2A
FM_ADR_COMPLETE_R        Q6F1             1        FET_N_SOT23-2N7002,FET,C79254-A
FM_ADR_COMPLETE_R        R4T1             2        RES_0402-0.0,5%,1/16W,CHIP,G21A
FM_ADR_COMPLETE_R        R4T2             2        RES_0402-0.0,5%,1/16W,EMPTY,G2A
FM_ADR_COMPLETE_R1       R2N26            2        RES_0402-33.2,1%,1/16W,CHIP,G2A
FM_ADR_COMPLETE_R1       U7C1             BD9      LBG_CORE_QAT_EXT_D_BGA1-IC,H91A
FM_ADR_MODE_SEL          R2M7             2        RES_0402-33.2,1%,1/16W,CHIP,G2A
FM_ADR_MODE_SEL          U8D7             T2       LCMXO2_A_256BGA-IC,H63395-001
FM_ADR_MODE_SEL_R        R2M7             1        RES_0402-33.2,1%,1/16W,CHIP,G2A
FM_ADR_MODE_SEL_R        U7C1             CA43     LBG_CORE_QAT_EXT_D_BGA1-IC,H91A
FM_ADR_SMI_GPIO_N        R2M2             2        RES_0402-4.75K,1%,1/16W,CHIP,GA
FM_ADR_SMI_GPIO_N        R2P12            2        RES_0402-0.0,5%,1/16W,EMPTY,G2A
FM_ADR_SMI_GPIO_N        R2R4             2        RES_0402-0.0,5%,1/16W,CHIP,G21A
FM_ADR_SMI_GPIO_N        R8E11            2        RES_0402-0.0,5%,1/16W,EMPTY,G2A
FM_ADR_SMI_GPIO_N        U7C1             BJ48     LBG_CORE_QAT_EXT_D_BGA1-IC,H91A
FM_ADR_SMI_GPIO_R_N      R2R4             1        RES_0402-0.0,5%,1/16W,CHIP,G21A
FM_ADR_SMI_GPIO_R_N      U8D7             C4       LCMXO2_A_256BGA-IC,H63395-001
FM_ALL_WAKE_N            R8E21            2        RES_0402-0.0,5%,1/16W,CHIP,G21A
FM_ALL_WAKE_N            R8E26            2        RES_0402-0.0,5%,1/16W,CHIP,G21A
FM_ALL_WAKE_N            R8E27            2        RES_0402-0.0,5%,1/16W,CHIP,G21A
FM_ALL_WAKE_N            R8E28            2        RES_0402-0.0,5%,1/16W,CHIP,G21A
FM_ALL_WAKE_N            R8E29            2        RES_0402-0.0,5%,1/16W,EMPTY,G2A
FM_ALL_WAKE_N            R8E30            2        RES_0402-10.0K,1%,1/16W,CHIP,GA
FM_ALL_WAKE_N            U8E4             2        TTL1G126_A_SOT-74HC1G126,IC,A7B
FM_BACKUP_BIOS_SEL_N     Q8F1             1        FET_N_SOT23LF-2N7002,FET,C7925A
FM_BACKUP_BIOS_SEL_N     R2T6             2        RES_0402-4.75K,1%,1/16W,CHIP,GA
FM_BACKUP_BIOS_SEL_N     U2T2             1        TTL1G32_A_SOT-74LVC1G32,IC,E60B
FM_BACKUP_BIOS_SEL_N     U7C1             AW4      LBG_CORE_QAT_EXT_D_BGA1-IC,H91A
FM_BACKUP_BIOS_SEL_N     U9F4             W5       AST1250_BGA-IC,G85138-002
FM_BATTERY_SENSE_EN      Q9G1             5        FET_N_DUAL_SMLF-NTJD4001N,FET,A
FM_BATTERY_SENSE_EN      Q9G1             6        FET_N_DUAL_SMLF-NTJD4001N,FET,A
FM_BATTERY_SENSE_EN      R1U49            2        RES_0402-2.7K,1%,1/16W,CHIP,G2A
FM_BATTERY_SENSE_EN_N    Q9G1             2        FET_N_DUAL_SMLF-NTJD4001N,FET,A
FM_BATTERY_SENSE_EN_N    R9G35            2        RES_0402-2.7K,1%,1/16W,CHIP,G2A
FM_BATTERY_SENSE_EN_N    U7C1             H9       LBG_CORE_QAT_EXT_D_BGA1-IC,H91A
FM_BATTERY_SENSE_EN_N    U9F4             B13      AST1250_BGA-IC,G85138-002
FM_BB_BMC_MP_GPIO        J1C1             C4       CONN76_H22707001_THMT1-CONN,H2A
FM_BB_BMC_MP_GPIO        U7C1             BW39     LBG_CORE_QAT_EXT_D_BGA1-IC,H91A
FM_BB_BMC_MP_GPIO        U9F4             A15      AST1250_BGA-IC,G85138-002
FM_BEEP_LED_P            DS9A3            2        LED_1NCLF-YELLOW,IC,C96565-003
FM_BEEP_LED_P            R1L33            1        RES_0402-221,1.0%,1/16W,CHIP,GA
FM_BIOS_MRC_DEBUG_MSG_DIS_N U7C1             BV25     LBG_CORE_QAT_EXT_D_BGA1-IC,H91A
FM_BIOS_MRC_DEBUG_MSG_DIS_N U9F4             U20      AST1250_BGA-IC,G85138-002
FM_BIOS_POST_CMPLT_N     R8C6             2        RES_0402-4.75K,1%,1/16W,CHIP,GA
FM_BIOS_POST_CMPLT_N     U7C1             BJ22     LBG_CORE_QAT_EXT_D_BGA1-IC,H91A
FM_BIOS_POST_CMPLT_N     U7C1             BY33     LBG_CORE_QAT_EXT_D_BGA1-IC,H91A
FM_BIOS_POST_CMPLT_N     U9F4             A4       AST1250_BGA-IC,G85138-002
FM_BIOS_PREFRB2_GOOD     R2N13            1        RES_0402-10.0K,1%,1/16W,CHIP,GA
FM_BIOS_PREFRB2_GOOD     U7C1             BK20     LBG_CORE_QAT_EXT_D_BGA1-IC,H91A
FM_BIOS_PREFRB2_GOOD     U9F4             AA2      AST1250_BGA-IC,G85138-002
FM_BIOS_SMI_ACTIVE_N     R2N32            2        RES_0402-4.75K,1%,1/16W,CHIP,GA
FM_BIOS_SMI_ACTIVE_N     U7C1             BA2      LBG_CORE_QAT_EXT_D_BGA1-IC,H91A
FM_BIOS_SMI_ACTIVE_N     U7C1             BE15     LBG_CORE_QAT_EXT_D_BGA1-IC,H91A
FM_BIOS_SMI_ACTIVE_N     U9F4             J20      AST1250_BGA-IC,G85138-002
FM_BIOS_SPI_BMC_CTRL     R1U6             1        RES_0402-10.0K,1%,1/16W,CHIP,GA
FM_BIOS_SPI_BMC_CTRL     U2T1             1        PI3B3257A_TSSOPLF-IC,E16801-001
FM_BIOS_SPI_BMC_CTRL     U8F1             1        PI3B3257A_TSSOPLF-IC,E16801-001
FM_BIOS_SPI_BMC_CTRL     U9F4             Y4       AST1250_BGA-IC,G85138-002
FM_BIOS_TOP_SWAP         J7G3             10       CONN12_C73564003_PIP-CONN,C735A
FM_BIOS_TOP_SWAP         R8E16            1        RES_0402-20.0K,1%,1/16W,CHIP,GA
FM_BIOS_TOP_SWAP         R8E19            2        RES_0402-4.75K,1%,1/16W,EMPTY,A
FM_BIOS_TOP_SWAP         U7C1             AP15     LBG_CORE_QAT_EXT_D_BGA1-IC,H91A
FM_BIOS_TOP_SWAP         U8E3             2        TTL1G126_A_SOT-74HC1G126,IC,A7B
FM_BIOS_TOP_SWAP         U9F4             V1       AST1250_BGA-IC,G85138-002
FM_BIOS_TOP_SWAP_SPKR    Q9A3             1        FET_N_SOT23LF-2N7002,FET,C7925A
FM_BIOS_TOP_SWAP_SPKR    R8E20            2        RES_0402-33.2,1%,1/16W,CHIP,G2A
FM_BIOS_TOP_SWAP_SPKR    U7C1             BH13     LBG_CORE_QAT_EXT_D_BGA1-IC,H91A
FM_BIOS_TOP_SWAP_SPKR_R  R8E20            1        RES_0402-33.2,1%,1/16W,CHIP,G2A
FM_BIOS_TOP_SWAP_SPKR_R  U8E3             4        TTL1G126_A_SOT-74HC1G126,IC,A7B
FM_BIOS_USB_RECOVERY     J7G3             4        CONN12_C73564003_PIP-CONN,C735A
FM_BIOS_USB_RECOVERY     R3T14            1        RES_0402-10.0K,1%,1/16W,CHIP,GA
FM_BIOS_USB_RECOVERY     U7C1             AH17     LBG_CORE_QAT_EXT_D_BGA1-IC,H91A
FM_BMC_CPLD_GPO          R2M5             2        RES_0402-4.75K,1%,1/16W,CHIP,GA
FM_BMC_CPLD_GPO          U7C1             CA45     LBG_CORE_QAT_EXT_D_BGA1-IC,H91A
FM_BMC_CPLD_GPO          U8D7             R1       LCMXO2_A_256BGA-IC,H63395-001
FM_BMC_CPLD_GPO          U9F4             E18      AST1250_BGA-IC,G85138-002
FM_BMC_CPLD_MP_RST_N     R1L7             2        RES_0402-4.75K,1%,1/16W,CHIP,GA
FM_BMC_CPLD_MP_RST_N     U7C1             A15      LBG_CORE_QAT_EXT_D_BGA1-IC,H91A
FM_BMC_CPLD_MP_RST_N     U8D7             R4       LCMXO2_A_256BGA-IC,H63395-001
FM_BMC_CPLD_MP_RST_N     U9F4             C14      AST1250_BGA-IC,G85138-002
FM_BMC_DISABLE           J9G1             5        CONN12_C73564003_PIP-CONN,C735A
FM_BMC_DISABLE           R1R11            1        RES_0402-4.75K,1%,1/16W,CHIP,GA
FM_BMC_ENABLE_N          R9E14            2        RES_0402-0.0,5%,1/16W,CHIP,G21A
FM_BMC_ENABLE_N          R9E15            2        RES_0402-0.0,5%,1/16W,EMPTY,G2A
FM_BMC_ENABLE_N          U7C1             BM38     LBG_CORE_QAT_EXT_D_BGA1-IC,H91A
FM_BMC_FAULT_LED         Q9F1             5        FET_N_DUAL_SMLF-NTJD4001N,FET,A
FM_BMC_FAULT_LED         Q9F1             6        FET_N_DUAL_SMLF-NTJD4001N,FET,A
FM_BMC_FAULT_LED         R9F52            2        RES_0402-4.75K,1%,1/16W,CHIP,GA
FM_BMC_FAULT_LED_N       Q9F1             2        FET_N_DUAL_SMLF-NTJD4001N,FET,A
FM_BMC_FAULT_LED_N       R9F30            2        RES_0402-4.75K,1%,1/16W,CHIP,GA
FM_BMC_FAULT_LED_N       U7C1             BR38     LBG_CORE_QAT_EXT_D_BGA1-IC,H91A
FM_BMC_FAULT_LED_N       U9F4             B5       AST1250_BGA-IC,G85138-002
FM_BMC_HEARTBEAT_N       Q9E1             2        FET_N_DUAL_SMLF-NTJD4001N,FET,A
FM_BMC_HEARTBEAT_N       R8B25            2        RES_0402-4.75K,1%,1/16W,CHIP,GA
FM_BMC_HEARTBEAT_N       U7C1             CA48     LBG_CORE_QAT_EXT_D_BGA1-IC,H91A
FM_BMC_HEARTBEAT_N       U9F4             J21      AST1250_BGA-IC,G85138-002
FM_BMC_NMI_N             R2N25            2        RES_0402-51.1,1.0%,1/16W,CHIP,A
FM_BMC_NMI_N             R2N27            2        RES_0402-4.75K,1%,1/16W,CHIP,GA
FM_BMC_NMI_N             U7C1             BF3      LBG_CORE_QAT_EXT_D_BGA1-IC,H91A
FM_BMC_NMI_N             U9F4             AA22     AST1250_BGA-IC,G85138-002
FM_BMC_ONCTL_N           R1T15            1        RES_0402-0.0,5%,1/16W,EMPTY,G2A
FM_BMC_ONCTL_N           U8D7             C7       LCMXO2_A_256BGA-IC,H63395-001
FM_BMC_ONCTL_R_N         R1T15            2        RES_0402-0.0,5%,1/16W,EMPTY,G2A
FM_BMC_ONCTL_R_N         R1T23            1        RES_0402-0.0,5%,1/16W,EMPTY,G2A
FM_BMC_ONCTL_R_N         U9F4             K20      AST1250_BGA-IC,G85138-002
FM_BMC_PWRBTN_OUT_N      R2T34            2        RES_0402-4.75K,1%,1/16W,CHIP,GA
FM_BMC_PWRBTN_OUT_N      U8F3             3        TTL2G07_SOT23LF-74LVC2G07,IC,DB
FM_BMC_PWRBTN_OUT_N      U9F4             A17      AST1250_BGA-IC,G85138-002
FM_BMC_READY_N           R1F9             1        RES_0402-0.0,5%,1/16W,EMPTY,G2A
FM_BMC_READY_N           R7D6             2        RES_0402-4.75K,1%,1/16W,CHIP,GA
FM_BMC_READY_N           U7C1             AH13     LBG_CORE_QAT_EXT_D_BGA1-IC,H91A
FM_BMC_READY_N           U7C1             V1       LBG_CORE_QAT_EXT_D_BGA1-IC,H91A
FM_BMC_READY_N           U9F4             H4       AST1250_BGA-IC,G85138-002
FM_BMC_SYS_THROTTLE_R_N  R2T41            2        RES_0402-22.1,1.0%,1/16W,CHIP,A
FM_BMC_SYS_THROTTLE_R_N  U9F4             E6       AST1250_BGA-IC,G85138-002
FM_BOARD_REV_ID0         R1T4             2        RES_0402-2.7K,1%,1/16W,CHIP,G2A
FM_BOARD_REV_ID0         R1T10            1        RES_0402-1.00K,1%,1/16W,EMPTY,A
FM_BOARD_REV_ID0         U7C1             CA30     LBG_CORE_QAT_EXT_D_BGA1-IC,H91A
FM_BOARD_REV_ID0         U9F4             U21      AST1250_BGA-IC,G85138-002
FM_BOARD_REV_ID1         R1T6             2        RES_0402-2.7K,1%,1/16W,EMPTY,GA
FM_BOARD_REV_ID1         R1T12            1        RES_0402-1.00K,1%,1/16W,CHIP,GA
FM_BOARD_REV_ID1         U7C1             BV38     LBG_CORE_QAT_EXT_D_BGA1-IC,H91A
FM_BOARD_REV_ID1         U9F4             T19      AST1250_BGA-IC,G85138-002
FM_BOARD_REV_ID2         R1T5             2        RES_0402-2.7K,1%,1/16W,EMPTY,GA
FM_BOARD_REV_ID2         R1T11            1        RES_0402-1.00K,1%,1/16W,CHIP,GA
FM_BOARD_REV_ID2         U7C1             BV33     LBG_CORE_QAT_EXT_D_BGA1-IC,H91A
FM_BOARD_REV_ID2         U9F4             V22      AST1250_BGA-IC,G85138-002
FM_BOARD_SKU_ID0         R1U18            1        RES_0402-1.00K,1%,1/16W,CHIP,GA
FM_BOARD_SKU_ID0         R1U23            2        RES_0402-2.7K,1%,1/16W,EMPTY,GA
FM_BOARD_SKU_ID0         U7C1             BD13     LBG_CORE_QAT_EXT_D_BGA1-IC,H91A
FM_BOARD_SKU_ID0         U9F4             Y6       AST1250_BGA-IC,G85138-002
FM_BOARD_SKU_ID1         R1U16            1        RES_0402-1.00K,1%,1/16W,EMPTY,A
FM_BOARD_SKU_ID1         R1U22            2        RES_0402-2.7K,1%,1/16W,CHIP,G2A
FM_BOARD_SKU_ID1         U7C1             AY18     LBG_CORE_QAT_EXT_D_BGA1-IC,H91A
FM_BOARD_SKU_ID1         U9F4             AB5      AST1250_BGA-IC,G85138-002
FM_BOARD_SKU_ID2         R1U17            1        RES_0402-1.00K,1%,1/16W,CHIP,GA
FM_BOARD_SKU_ID2         R1U24            2        RES_0402-2.7K,1%,1/16W,EMPTY,GA
FM_BOARD_SKU_ID2         U7C1             AV7      LBG_CORE_QAT_EXT_D_BGA1-IC,H91A
FM_BOARD_SKU_ID2         U9F4             W7       AST1250_BGA-IC,G85138-002
FM_BOARD_SKU_ID3         R1U15            1        RES_0402-1.00K,1%,1/16W,EMPTY,A
FM_BOARD_SKU_ID3         R1U21            2        RES_0402-2.7K,1%,1/16W,CHIP,G2A
FM_BOARD_SKU_ID3         U7C1             BE18     LBG_CORE_QAT_EXT_D_BGA1-IC,H91A
FM_BOARD_SKU_ID3         U9F4             AA6      AST1250_BGA-IC,G85138-002
FM_BOARD_SKU_ID4         R2N17            2        RES_0402-2.7K,1%,1/16W,EMPTY,GA
FM_BOARD_SKU_ID4         R2N18            1        RES_0402-1.00K,1%,1/16W,CHIP,GA
FM_BOARD_SKU_ID4         U7C1             BD17     LBG_CORE_QAT_EXT_D_BGA1-IC,H91A
FM_BOARD_SKU_ID4         U9F4             W3       AST1250_BGA-IC,G85138-002
FM_CPLD_ADR_TRIGGER_N    R2M1             1        RES_0402-33.2,1%,1/16W,CHIP,G2A
FM_CPLD_ADR_TRIGGER_N    U8D7             E14      LCMXO2_A_256BGA-IC,H63395-001
FM_CPLD_ADR_TRIGGER_R_N  R2M1             2        RES_0402-33.2,1%,1/16W,CHIP,G2A
FM_CPLD_ADR_TRIGGER_R_N  U7C1             BE52     LBG_CORE_QAT_EXT_D_BGA1-IC,H91A
FM_CPLD_BMC_PWRDN_N      R2U4             2        RES_0402-4.75K,1%,1/16W,CHIP,GA
FM_CPLD_BMC_PWRDN_N      U7C1             BW41     LBG_CORE_QAT_EXT_D_BGA1-IC,H91A
FM_CPLD_BMC_PWRDN_N      U8D7             N9       LCMXO2_A_256BGA-IC,H63395-001
FM_CPLD_BMC_PWRDN_N      U9F4             D6       AST1250_BGA-IC,G85138-002
FM_CPLD_DBG_PWR_EN       Q1L2             2        FET_N_DUAL_SMLF-NTJD4001N,FET,A
FM_CPLD_DBG_PWR_EN       Q1L2             3        FET_N_DUAL_SMLF-NTJD4001N,FET,A
FM_CPLD_DBG_PWR_EN       R1L9             2        RES_0402-100.0K,1%,1/16W,CHIP,A
FM_CPLD_DBG_PWR_EN_N     R1L2             1        RES_0402-10.0,1%,1/16W,CHIP,G2A
FM_CPLD_DBG_PWR_EN_N     U8D7             T8       LCMXO2_A_256BGA-IC,H63395-001
FM_CPLD_DBG_PWR_EN_R_N   Q1L2             5        FET_N_DUAL_SMLF-NTJD4001N,FET,A
FM_CPLD_DBG_PWR_EN_R_N   R1L2             2        RES_0402-10.0,1%,1/16W,CHIP,G2A
FM_CPLD_UART_CH_LOCK_N   J8G2             9        CONN12_C73564003_PIP-CONN,C735A
FM_CPLD_UART_CH_LOCK_N   R7D30            2        RES_0402-4.75K,1%,1/16W,CHIP,GA
FM_CPLD_UART_CH_LOCK_N   U8D7             M9       LCMXO2_A_256BGA-IC,H63395-001
FM_CPU0_AND_CPU1_MCP_PRES U1M6             1        74CBTLV1G125_SMLF-IC,C88177-00A
FM_CPU0_AND_CPU1_MCP_PRES U8D7             D11      LCMXO2_A_256BGA-IC,H63395-001
FM_CPU0_CD_PRES          U2M1             6        NC7SB3157_SMLF-IC,C99406-001
FM_CPU0_CD_PRES          U8D7             C11      LCMXO2_A_256BGA-IC,H63395-001
FM_CPU0_FIVR_FAULT_LVT3  R7D29            2        RES_0402-33.2,1%,1/16W,CHIP,G2A
FM_CPU0_FIVR_FAULT_LVT3  U8D7             M16      LCMXO2_A_256BGA-IC,H63395-001
FM_CPU0_FIVR_FAULT_LVT3_N R9G16            1        RES_0402-33.2,1%,1/16W,CHIP,G2A
FM_CPU0_FIVR_FAULT_LVT3_N U7C1             BE11     LBG_CORE_QAT_EXT_D_BGA1-IC,H91A
FM_CPU0_FIVR_FAULT_LVT3_N U8D7             F5       LCMXO2_A_256BGA-IC,H63395-001
FM_CPU0_FIVR_FAULT_LVT3_R_N R9G16            2        RES_0402-33.2,1%,1/16W,CHIP,G2A
FM_CPU0_FIVR_FAULT_LVT3_R_N U9F4             H2       AST1250_BGA-IC,G85138-002
FM_CPU0_FIVR_FAULT_R_LVT3 R7D29            1        RES_0402-33.2,1%,1/16W,CHIP,G2A
FM_CPU0_FIVR_FAULT_R_LVT3 U7D2             12       GTL2014_SM-IC,D66151-001
FM_CPU0_MCP_CLK_EN_N     EU4D2            29       NB3W1200L_LCC-IC,H13585-001
FM_CPU0_MCP_CLK_EN_N     EU4D2            36       NB3W1200L_LCC-IC,H13585-001
FM_CPU0_MCP_CLK_EN_N     EU4D2            37       NB3W1200L_LCC-IC,H13585-001
FM_CPU0_MCP_CLK_EN_N     R4D70            2        RES_0402-4.75K,1%,1/16W,CHIP,GA
FM_CPU0_MCP_CLK_EN_N     U8D7             F15      LCMXO2_A_256BGA-IC,H63395-001
FM_CPU0_OR_CPU1_MCP_PRES U1M5             1        74CBTLV1G125_SMLF-IC,C88177-00A
FM_CPU0_OR_CPU1_MCP_PRES U8D7             A11      LCMXO2_A_256BGA-IC,H63395-001
FM_CPU0_OR_CPU1_MCP_PRES U9A5             1        74CBTLV1G125_SMLF-IC,C88177-00A
FM_CPU0_PKGID0           R5N1             2        RES_0402-10.0K,1%,1/16W,CHIP,GA
FM_CPU0_PKGID0           U5D1             DC72     SKX_EXT_B_BGA1-IC,TBD
FM_CPU0_PKGID0           U8D7             F2       LCMXO2_A_256BGA-IC,H63395-001
FM_CPU0_PKGID1           R5N5             2        RES_0402-10.0K,1%,1/16W,CHIP,GA
FM_CPU0_PKGID1           U4R1             1        74CBTLV1G125_SMLF-IC,C88177-00A
FM_CPU0_PKGID1           U5D1             CW72     SKX_EXT_B_BGA1-IC,TBD
FM_CPU0_PKGID1           U8D7             G3       LCMXO2_A_256BGA-IC,H63395-001
FM_CPU0_PKGID2           R5N3             2        RES_0402-10.0K,1%,1/16W,CHIP,GA
FM_CPU0_PKGID2           U5D1             DA72     SKX_EXT_B_BGA1-IC,TBD
FM_CPU0_PKGID2           U8D7             G2       LCMXO2_A_256BGA-IC,H63395-001
FM_CPU0_PROCHOT_LVT3_BMC_N R1T36            2        RES_0402-0.0,5%,1/16W,CHIP,G21A
FM_CPU0_PROCHOT_LVT3_BMC_N U9F4             AA7      AST1250_BGA-IC,G85138-002
FM_CPU0_PROCHOT_LVT3_K_N R2T38            1        RES_0402-33.2,1%,1/16W,CHIP,G2A
FM_CPU0_PROCHOT_LVT3_K_N R2T67            2        RES_0402-0.0,5%,1/16W,CHIP,G21A
FM_CPU0_PROCHOT_LVT3_K_N R2T71            1        RES_0402-0.0,5%,1/16W,EMPTY,G2A
FM_CPU0_PROCHOT_LVT3_N   R1T35            1        RES_0402-0.0,5%,1/16W,EMPTY,G2A
FM_CPU0_PROCHOT_LVT3_N   R1T36            1        RES_0402-0.0,5%,1/16W,CHIP,G21A
FM_CPU0_PROCHOT_LVT3_N   R2T38            2        RES_0402-33.2,1%,1/16W,CHIP,G2A
FM_CPU0_PROCHOT_LVT3_R_N R2T67            1        RES_0402-0.0,5%,1/16W,CHIP,G21A
FM_CPU0_PROCHOT_LVT3_R_N U2T4             12       GTL2014_SM-IC,D66151-001
FM_CPU0_PROCHOT_PCH_N    R1T35            2        RES_0402-0.0,5%,1/16W,EMPTY,G2A
FM_CPU0_PROCHOT_PCH_N    U7C1             Y7       LBG_CORE_QAT_EXT_D_BGA1-IC,H91A
FM_CPU0_PROC_ID0         R5N4             2        RES_0402-1.8K,1%,1/16W,CHIP,G2A
FM_CPU0_PROC_ID0         U5D1             CY71     SKX_EXT_B_BGA1-IC,TBD
FM_CPU0_PROC_ID0         U8D7             F1       LCMXO2_A_256BGA-IC,H63395-001
FM_CPU0_PROC_ID1         R5N2             2        RES_0402-1.8K,1%,1/16W,CHIP,G2A
FM_CPU0_PROC_ID1         U5D1             DB71     SKX_EXT_B_BGA1-IC,TBD
FM_CPU0_PROC_ID1         U8D7             F3       LCMXO2_A_256BGA-IC,H63395-001
FM_CPU0_RC_EN            R8D44            2        RES_0402-10.0K,1%,1/16W,CHIP,GA
FM_CPU0_RC_EN            U7C1             BD20     LBG_CORE_QAT_EXT_D_BGA1-IC,H91A
FM_CPU0_RC_EN            U8D7             R3       LCMXO2_A_256BGA-IC,H63395-001
FM_CPU0_RC_ERROR_N       R2M8             2        RES_0402-1.5K,1%,1/16W,CHIP,G2A
FM_CPU0_RC_ERROR_N       U5D1             Y23      SKX_EXT_B_BGA1-IC,TBD
FM_CPU0_RC_ERROR_N       U7C1             B14      LBG_CORE_QAT_EXT_D_BGA1-IC,H91A
FM_CPU0_RC_ERROR_N       U7C1             BH50     LBG_CORE_QAT_EXT_D_BGA1-IC,H91A
FM_CPU0_RC_ERROR_N       U9F4             V3       AST1250_BGA-IC,G85138-002
FM_CPU0_SKTOCC_LVT3_N    R4R5             2        RES_0402-4.75K,1%,1/16W,CHIP,GA
FM_CPU0_SKTOCC_LVT3_N    U5D1             AB13     SKX_EXT_B_BGA1-IC,TBD
FM_CPU0_SKTOCC_LVT3_N    U7C1             G11      LBG_CORE_QAT_EXT_D_BGA1-IC,H91A
FM_CPU0_SKTOCC_LVT3_N    U8D7             T14      LCMXO2_A_256BGA-IC,H63395-001
FM_CPU0_SKTOCC_LVT3_N    U9F4             C6       AST1250_BGA-IC,G85138-002
FM_CPU0_SM_WP            R3P54            2        RES_0402-3.32K,1%,1/16W,EMPTY,A
FM_CPU0_SM_WP            R3P56            1        RES_0402-1.00K,1%,1/16W,CHIP,GA
FM_CPU0_SM_WP            U5D1             CV59     SKX_EXT_B_BGA1-IC,TBD
FM_CPU0_STL_BRD_OSC_EN   R7D40            2        RES_0402-0.0,5%,1/16W,EMPTY,G2A
FM_CPU0_STL_BRD_OSC_EN   R8D43            2        RES_0402-0.0,5%,1/16W,CHIP,G21A
FM_CPU0_STL_BRD_OSC_EN   Y6F1             1        OSC_C_6P10-156.25MHZ,OSC,G6383A
FM_CPU0_THERMTRIP_LATCH_LVT3_N U7C1             BN44     LBG_CORE_QAT_EXT_D_BGA1-IC,H91A
FM_CPU0_THERMTRIP_LATCH_LVT3_N U8D7             G12      LCMXO2_A_256BGA-IC,H63395-001
FM_CPU0_THERMTRIP_LATCH_LVT3_N U9F4             H19      AST1250_BGA-IC,G85138-002
FM_CPU0_THERMTRIP_LVT3_N R7D34            2        RES_0402-33.2,1%,1/16W,CHIP,G2A
FM_CPU0_THERMTRIP_LVT3_N U8D7             N15      LCMXO2_A_256BGA-IC,H63395-001
FM_CPU0_THERMTRIP_LVT3_R_N R7D34            1        RES_0402-33.2,1%,1/16W,CHIP,G2A
FM_CPU0_THERMTRIP_LVT3_R_N U7D2             9        GTL2014_SM-IC,D66151-001
FM_CPU0_VRM_322M_156M_OSC_EN J6B1             E1       SCONN120_H61426002_SM-CONN,H61A
FM_CPU0_VRM_322M_156M_OSC_EN R7D39            2        RES_0402-0.0,5%,1/16W,EMPTY,G2A
FM_CPU0_VRM_OSC_EN       R7D39            1        RES_0402-0.0,5%,1/16W,EMPTY,G2A
FM_CPU0_VRM_OSC_EN       R7D40            1        RES_0402-0.0,5%,1/16W,EMPTY,G2A
FM_CPU0_VRM_OSC_EN       U8D7             R13      LCMXO2_A_256BGA-IC,H63395-001
FM_CPU1_CD_PRES          U1M2             6        NC7SB3157_SMLF-IC,C99406-001
FM_CPU1_CD_PRES          U8D7             F10      LCMXO2_A_256BGA-IC,H63395-001
FM_CPU1_FIVR_FAULT_LVT3  R3P46            2        RES_0402-33.2,1%,1/16W,CHIP,G2A
FM_CPU1_FIVR_FAULT_LVT3  U8D7             G13      LCMXO2_A_256BGA-IC,H63395-001
FM_CPU1_FIVR_FAULT_LVT3_N R9G10            1        RES_0402-33.2,1%,1/16W,CHIP,G2A
FM_CPU1_FIVR_FAULT_LVT3_N U7C1             BA20     LBG_CORE_QAT_EXT_D_BGA1-IC,H91A
FM_CPU1_FIVR_FAULT_LVT3_N U8D7             E6       LCMXO2_A_256BGA-IC,H63395-001
FM_CPU1_FIVR_FAULT_LVT3_R_N R9G10            2        RES_0402-33.2,1%,1/16W,CHIP,G2A
FM_CPU1_FIVR_FAULT_LVT3_R_N U9F4             H1       AST1250_BGA-IC,G85138-002
FM_CPU1_FIVR_FAULT_R_LVT3 R3P46            1        RES_0402-33.2,1%,1/16W,CHIP,G2A
FM_CPU1_FIVR_FAULT_R_LVT3 U3P2             12       GTL2014_SM-IC,D66151-001
FM_CPU1_MCP_CLK_EN_N     EU4D2            53       NB3W1200L_LCC-IC,H13585-001
FM_CPU1_MCP_CLK_EN_N     EU4D2            61       NB3W1200L_LCC-IC,H13585-001
FM_CPU1_MCP_CLK_EN_N     EU4D2            62       NB3W1200L_LCC-IC,H13585-001
FM_CPU1_MCP_CLK_EN_N     R4D69            2        RES_0402-4.75K,1%,1/16W,CHIP,GA
FM_CPU1_MCP_CLK_EN_N     U8D7             F16      LCMXO2_A_256BGA-IC,H63395-001
FM_CPU1_PKGID0           R8N2             2        RES_0402-10.0K,1%,1/16W,CHIP,GA
FM_CPU1_PKGID0           U2D1             DC72     SKX_EXT_B_BGA1-IC,TBD
FM_CPU1_PKGID0           U8D7             R12      LCMXO2_A_256BGA-IC,H63395-001
FM_CPU1_PKGID1           R8N5             2        RES_0402-10.0K,1%,1/16W,CHIP,GA
FM_CPU1_PKGID1           U2D1             CW72     SKX_EXT_B_BGA1-IC,TBD
FM_CPU1_PKGID1           U6M1             1        74CBTLV1G125_SMLF-IC,C88177-00A
FM_CPU1_PKGID1           U8D7             P12      LCMXO2_A_256BGA-IC,H63395-001
FM_CPU1_PKGID2           R8N3             2        RES_0402-10.0K,1%,1/16W,CHIP,GA
FM_CPU1_PKGID2           U2D1             DA72     SKX_EXT_B_BGA1-IC,TBD
FM_CPU1_PKGID2           U8D7             T11      LCMXO2_A_256BGA-IC,H63395-001
FM_CPU1_PROCHOT_LVT3_BMC_N R1T37            2        RES_0402-0.0,5%,1/16W,CHIP,G21A
FM_CPU1_PROCHOT_LVT3_BMC_N U9F4             AB7      AST1250_BGA-IC,G85138-002
FM_CPU1_PROCHOT_LVT3_K_N R7D24            1        RES_0402-33.2,1%,1/16W,CHIP,G2A
FM_CPU1_PROCHOT_LVT3_K_N R7D41            2        RES_0402-0.0,5%,1/16W,CHIP,G21A
FM_CPU1_PROCHOT_LVT3_K_N R7D43            1        RES_0402-0.0,5%,1/16W,EMPTY,G2A
FM_CPU1_PROCHOT_LVT3_N   R1T37            1        RES_0402-0.0,5%,1/16W,CHIP,G21A
FM_CPU1_PROCHOT_LVT3_N   R1T38            1        RES_0402-0.0,5%,1/16W,EMPTY,G2A
FM_CPU1_PROCHOT_LVT3_N   R7D24            2        RES_0402-33.2,1%,1/16W,CHIP,G2A
FM_CPU1_PROCHOT_LVT3_R_N R7D41            1        RES_0402-0.0,5%,1/16W,CHIP,G21A
FM_CPU1_PROCHOT_LVT3_R_N U2T4             13       GTL2014_SM-IC,D66151-001
FM_CPU1_PROCHOT_PCH_N    R1T38            2        RES_0402-0.0,5%,1/16W,EMPTY,G2A
FM_CPU1_PROCHOT_PCH_N    U7C1             AA9      LBG_CORE_QAT_EXT_D_BGA1-IC,H91A
FM_CPU1_PROC_ID0         R8N4             2        RES_0402-1.8K,1%,1/16W,CHIP,G2A
FM_CPU1_PROC_ID0         U2D1             CY71     SKX_EXT_B_BGA1-IC,TBD
FM_CPU1_PROC_ID0         U8D7             M15      LCMXO2_A_256BGA-IC,H63395-001
FM_CPU1_PROC_ID1         R8N1             2        RES_0402-1.8K,1%,1/16W,CHIP,G2A
FM_CPU1_PROC_ID1         U2D1             DB71     SKX_EXT_B_BGA1-IC,TBD
FM_CPU1_PROC_ID1         U8D7             M14      LCMXO2_A_256BGA-IC,H63395-001
FM_CPU1_RC_EN            R2P22            2        RES_0402-10.0K,1%,1/16W,CHIP,GA
FM_CPU1_RC_EN            U7C1             BY29     LBG_CORE_QAT_EXT_D_BGA1-IC,H91A
FM_CPU1_RC_EN            U8D7             P4       LCMXO2_A_256BGA-IC,H63395-001
FM_CPU1_RC_ERROR_N       R2N29            2        RES_0402-1.5K,1%,1/16W,CHIP,G2A
FM_CPU1_RC_ERROR_N       U2D1             Y23      SKX_EXT_B_BGA1-IC,TBD
FM_CPU1_RC_ERROR_N       U7C1             AY52     LBG_CORE_QAT_EXT_D_BGA1-IC,H91A
FM_CPU1_RC_ERROR_N       U7C1             BV23     LBG_CORE_QAT_EXT_D_BGA1-IC,H91A
FM_CPU1_RC_ERROR_N       U9F4             W2       AST1250_BGA-IC,G85138-002
FM_CPU1_SKTOCC_LVT3_N    R6P39            2        RES_0402-4.75K,1%,1/16W,CHIP,GA
FM_CPU1_SKTOCC_LVT3_N    U1M4             1        74CBTLV1G125_SMLF-IC,C88177-00A
FM_CPU1_SKTOCC_LVT3_N    U1M7             6        NC7SB3157_SMLF-IC,C99406-001
FM_CPU1_SKTOCC_LVT3_N    U2D1             AB13     SKX_EXT_B_BGA1-IC,TBD
FM_CPU1_SKTOCC_LVT3_N    U7C1             H13      LBG_CORE_QAT_EXT_D_BGA1-IC,H91A
FM_CPU1_SKTOCC_LVT3_N    U8D7             T12      LCMXO2_A_256BGA-IC,H63395-001
FM_CPU1_SKTOCC_LVT3_N    U9F4             A5       AST1250_BGA-IC,G85138-002
FM_CPU1_SM_WP            R1C35            2        RES_0402-3.32K,1%,1/16W,EMPTY,A
FM_CPU1_SM_WP            R1C36            1        RES_0402-1.00K,1%,1/16W,CHIP,GA
FM_CPU1_SM_WP            U2D1             CV59     SKX_EXT_B_BGA1-IC,TBD
FM_CPU1_STL_BRD_OSC_EN   R7D36            2        RES_0402-0.0,5%,1/16W,CHIP,G21A
FM_CPU1_STL_BRD_OSC_EN   R7D38            2        RES_0402-0.0,5%,1/16W,EMPTY,G2A
FM_CPU1_STL_BRD_OSC_EN   Y3F1             1        OSC_C_6P10-156.25MHZ,OSC,G6383A
FM_CPU1_THERMTRIP_LATCH_LVT3_N U7C1             AV18     LBG_CORE_QAT_EXT_D_BGA1-IC,H91A
FM_CPU1_THERMTRIP_LATCH_LVT3_N U8D7             C5       LCMXO2_A_256BGA-IC,H63395-001
FM_CPU1_THERMTRIP_LATCH_LVT3_N U9F4             H20      AST1250_BGA-IC,G85138-002
FM_CPU1_THERMTRIP_LVT3_N R3P42            2        RES_0402-33.2,1%,1/16W,CHIP,G2A
FM_CPU1_THERMTRIP_LVT3_N U8D7             G14      LCMXO2_A_256BGA-IC,H63395-001
FM_CPU1_THERMTRIP_LVT3_R_N R3P42            1        RES_0402-33.2,1%,1/16W,CHIP,G2A
FM_CPU1_THERMTRIP_LVT3_R_N U3P2             9        GTL2014_SM-IC,D66151-001
FM_CPU1_VRM_322M_156M_OSC_EN J4B2             E1       SCONN120_H61426002_SM-CONN,H61A
FM_CPU1_VRM_322M_156M_OSC_EN R7D37            2        RES_0402-0.0,5%,1/16W,EMPTY,G2A
FM_CPU1_VRM_OSC_EN       R7D37            1        RES_0402-0.0,5%,1/16W,EMPTY,G2A
FM_CPU1_VRM_OSC_EN       R7D38            1        RES_0402-0.0,5%,1/16W,EMPTY,G2A
FM_CPU1_VRM_OSC_EN       U8D7             N14      LCMXO2_A_256BGA-IC,H63395-001
FM_CPU_BMC_INIT          R3D31            1        RES_0402-0.0,5%,1/16W,EMPTY,G2A
FM_CPU_BMC_INIT          R6D16            1        RES_0402-0.0,5%,1/16W,EMPTY,G2A
FM_CPU_BMC_INIT          U7C1             AD1      LBG_CORE_QAT_EXT_D_BGA1-IC,H91A
FM_CPU_BMC_INIT          U9F4             A14      AST1250_BGA-IC,G85138-002
FM_CPU_CATERR_DLY_LVT3_N R2N1             2        RES_0402-33.2,1%,1/16W,CHIP,G2A
FM_CPU_CATERR_DLY_LVT3_N U8D7             E2       LCMXO2_A_256BGA-IC,H63395-001
FM_CPU_CATERR_DLY_LVT3_R_N R2N1             1        RES_0402-33.2,1%,1/16W,CHIP,G2A
FM_CPU_CATERR_DLY_LVT3_R_N U7C1             CA37     LBG_CORE_QAT_EXT_D_BGA1-IC,H91A
FM_CPU_CATERR_LVT3_N     R3P43            2        RES_0402-33.2,1%,1/16W,CHIP,G2A
FM_CPU_CATERR_LVT3_N     U8D7             R14      LCMXO2_A_256BGA-IC,H63395-001
FM_CPU_CATERR_LVT3_N     U9F4             B19      AST1250_BGA-IC,G85138-002
FM_CPU_CATERR_LVT3_R2_N  R3P43            1        RES_0402-33.2,1%,1/16W,CHIP,G2A
FM_CPU_CATERR_LVT3_R2_N  U3P2             10       GTL2014_SM-IC,D66151-001
FM_CPU_ERR0_LVT3_BMC_N   R8F38            2        RES_0402-0.0,5%,1/16W,CHIP,G21A
FM_CPU_ERR0_LVT3_BMC_N   U9F4             A16      AST1250_BGA-IC,G85138-002
FM_CPU_ERR0_LVT3_K_N     R2T30            1        RES_0402-33.2,1%,1/16W,CHIP,G2A
FM_CPU_ERR0_LVT3_K_N     R2T58            2        RES_0402-0.0,5%,1/16W,EMPTY,G2A
FM_CPU_ERR0_LVT3_K_N     R2T65            2        RES_0402-0.0,5%,1/16W,CHIP,G21A
FM_CPU_ERR0_LVT3_N       R2T30            2        RES_0402-33.2,1%,1/16W,CHIP,G2A
FM_CPU_ERR0_LVT3_N       R8F37            1        RES_0402-0.0,5%,1/16W,EMPTY,G2A
FM_CPU_ERR0_LVT3_N       R8F38            1        RES_0402-0.0,5%,1/16W,CHIP,G21A
FM_CPU_ERR0_LVT3_R_N     R2T65            1        RES_0402-0.0,5%,1/16W,CHIP,G21A
FM_CPU_ERR0_LVT3_R_N     U2T4             9        GTL2014_SM-IC,D66151-001
FM_CPU_ERR0_PCH_N        R8F37            2        RES_0402-0.0,5%,1/16W,EMPTY,G2A
FM_CPU_ERR0_PCH_N        U7C1             AE7      LBG_CORE_QAT_EXT_D_BGA1-IC,H91A
FM_CPU_ERR1_LVT3_BMC_N   R2T64            2        RES_0402-0.0,5%,1/16W,CHIP,G21A
FM_CPU_ERR1_LVT3_BMC_N   U9F4             E15      AST1250_BGA-IC,G85138-002
FM_CPU_ERR1_LVT3_K_N     R2T33            1        RES_0402-33.2,1%,1/16W,CHIP,G2A
FM_CPU_ERR1_LVT3_K_N     R2T62            2        RES_0402-0.0,5%,1/16W,EMPTY,G2A
FM_CPU_ERR1_LVT3_K_N     R2T66            2        RES_0402-0.0,5%,1/16W,CHIP,G21A
FM_CPU_ERR1_LVT3_N       R2T33            2        RES_0402-33.2,1%,1/16W,CHIP,G2A
FM_CPU_ERR1_LVT3_N       R2T63            1        RES_0402-0.0,5%,1/16W,EMPTY,G2A
FM_CPU_ERR1_LVT3_N       R2T64            1        RES_0402-0.0,5%,1/16W,CHIP,G21A
FM_CPU_ERR1_LVT3_R_N     R2T66            1        RES_0402-0.0,5%,1/16W,CHIP,G21A
FM_CPU_ERR1_LVT3_R_N     U2T4             10       GTL2014_SM-IC,D66151-001
FM_CPU_ERR1_PCH_N        R2T63            2        RES_0402-0.0,5%,1/16W,EMPTY,G2A
FM_CPU_ERR1_PCH_N        U7C1             AG11     LBG_CORE_QAT_EXT_D_BGA1-IC,H91A
FM_CPU_ERR2_LVT3_N       R7D31            2        RES_0402-33.2,1%,1/16W,CHIP,G2A
FM_CPU_ERR2_LVT3_N       U7C1             AV52     LBG_CORE_QAT_EXT_D_BGA1-IC,H91A
FM_CPU_ERR2_LVT3_N       U9F4             N21      AST1250_BGA-IC,G85138-002
FM_CPU_ERR2_LVT3_R_N     R7D31            1        RES_0402-33.2,1%,1/16W,CHIP,G2A
FM_CPU_ERR2_LVT3_R_N     U7D2             10       GTL2014_SM-IC,D66151-001
FM_CPU_MSMI_LVT3_N       R7D25            2        RES_0402-33.2,1%,1/16W,CHIP,G2A
FM_CPU_MSMI_LVT3_N       U7C1             AT52     LBG_CORE_QAT_EXT_D_BGA1-IC,H91A
FM_CPU_MSMI_LVT3_N       U8D7             T13      LCMXO2_A_256BGA-IC,H63395-001
FM_CPU_MSMI_LVT3_N       U9F4             AB1      AST1250_BGA-IC,G85138-002
FM_CPU_MSMI_LVT3_R_N     R7D25            1        RES_0402-33.2,1%,1/16W,CHIP,G2A
FM_CPU_MSMI_LVT3_R_N     U7D2             13       GTL2014_SM-IC,D66151-001
FM_CTNR_PS_ON            EU8B1            2        SLG55021_SM-IC,G56246-001
FM_CTNR_PS_ON            R8B4             1        RES_0402-100.0K,1%,1/16W,CHIP,A
FM_CTNR_PS_ON            R8E5             2        RES_0402-33.2,1%,1/16W,CHIP,G2A
FM_CTNR_PS_ON            R8E12            2        RES_0402-4.75K,1%,1/16W,EMPTY,A
FM_CTNR_PS_ON            U1E2             1        TTL1G08_SOTLF-NC7SZ08,IC,D1032B
FM_CTNR_PS_ON            U8D7             B3       LCMXO2_A_256BGA-IC,H63395-001
FM_CTNR_PS_ON_R          R8E5             1        RES_0402-33.2,1%,1/16W,CHIP,G2A
FM_CTNR_PS_ON_R          U8E1             8        TTL08_QFN15-74LVC08A,IC,D90404B
FM_DB1200ZL_BCLKS_EN_N   EU4D2            19       NB3W1200L_LCC-IC,H13585-001
FM_DB1200ZL_BCLKS_EN_N   EU4D2            20       NB3W1200L_LCC-IC,H13585-001
FM_DB1200ZL_BCLKS_EN_N   EU4D2            28       NB3W1200L_LCC-IC,H13585-001
FM_DB1200ZL_BCLKS_EN_N   EU4D2            44       NB3W1200L_LCC-IC,H13585-001
FM_DB1200ZL_BCLKS_EN_N   EU4D2            45       NB3W1200L_LCC-IC,H13585-001
FM_DB1200ZL_BCLKS_EN_N   EU4D2            52       NB3W1200L_LCC-IC,H13585-001
FM_DB1200ZL_BCLKS_EN_N   R6P48            2        RES_0402-4.75K,1%,1/16W,CHIP,GA
FM_DB1200ZL_BCLKS_EN_N   U8D7             R11      LCMXO2_A_256BGA-IC,H63395-001
FM_DB1200_PWRGD          EU4D2            6        NB3W1200L_LCC-IC,H13585-001
FM_DB1200_PWRGD          U8D7             C15      LCMXO2_A_256BGA-IC,H63395-001
FM_DB1200_SMB_SA0        EU4D2            11       NB3W1200L_LCC-IC,H13585-001
FM_DB1200_SMB_SA0        R4D35            2        RES_0402-10.0K,1%,1/16W,EMPTY,A
FM_DB1200_SMB_SA0        R6P21            1        RES_0402-1.00K,1%,1/16W,CHIP,GA
FM_DB1200_SMB_SA1        EU4D2            14       NB3W1200L_LCC-IC,H13585-001
FM_DB1200_SMB_SA1        R4D38            2        RES_0402-10.0K,1%,1/16W,EMPTY,A
FM_DB1200_SMB_SA1        R6P20            1        RES_0402-1.00K,1%,1/16W,CHIP,GA
FM_DB_PRESENT            Q1L3             3        NPN_SM-MMBT3904,IC,C52245-001
FM_DB_PRESENT            Q1L4             2        FET_N_DUAL_SMLF-2N7002DW,FET,DA
FM_DB_PRESENT            R1L36            2        RES_0402-1.00K,1%,1/16W,CHIP,GA
FM_DB_UART_SEL0_N        CR1L1            2        DIODE_SM-1N4148W,IC,D89194-001
FM_DB_UART_SEL0_N        R1L6             2        RES_0402-0.0,5%,1/16W,CHIP,G21A
FM_DB_UART_SEL1_N        CR1L1            1        DIODE_SM-1N4148W,IC,D89194-001
FM_DB_UART_SEL1_N        CR1L2            2        DIODE_SM-1N4148W,IC,D89194-001
FM_DB_UART_SEL2_N        CR1L2            1        DIODE_SM-1N4148W,IC,D89194-001
FM_DB_UART_SEL2_N        CR1L3            2        DIODE_SM-1N4148W,IC,D89194-001
FM_DB_UART_SEL3_N        CR1L3            1        DIODE_SM-1N4148W,IC,D89194-001
FM_DB_UART_SEL3_N        CR1L4            2        DIODE_SM-1N4148W,IC,D89194-001
FM_DB_UART_SEL4_N        CR1L4            1        DIODE_SM-1N4148W,IC,D89194-001
FM_DB_UART_SEL4_N        Q1L3             1        NPN_SM-MMBT3904,IC,C52245-001
FM_DEBUG_RST_BTN_N       J9A2             11       CONN14_H54902001_PIP-CONN,H549A
FM_DEBUG_RST_BTN_N       R1L19            2        RES_0402-4.75K,1%,1/16W,EMPTY,A
FM_DEBUG_RST_BTN_N       R1L22            1        RES_0402-200.0,1%,1/16W,CHIP,GA
FM_DEBUG_RST_BTN_N       R1L29            2        RES_0402-33.2,1%,1/16W,CHIP,G2A
FM_DEBUG_RST_BTN_N       S9A1             1        SWITCH_D37771002_SM-IC,D37771-A
FM_DEBUG_RST_BTN_N       S9A1             2        SWITCH_D37771002_SM-IC,D37771-A
FM_DEBUG_RST_BTN_N       U8D7             G5       LCMXO2_A_256BGA-IC,H63395-001
FM_DEBUG_RST_BTN_R1_N    R1L28            2        RES_0402-4.75K,1%,1/16W,CHIP,GA
FM_DEBUG_RST_BTN_R1_N    R1L29            1        RES_0402-33.2,1%,1/16W,CHIP,G2A
FM_DEBUG_RST_BTN_R1_N    U1L4             4        TTL1G07_A_SOP-74LVC1G07,IC,C88B
FM_DIMM_EVENT_COD_N      J1A1             78       SCONN288_H44441004_PIP-SCONN,HA
FM_DIMM_EVENT_COD_N      J1A2             78       SCONN288_H44441004_PIP-SCONN,HA
FM_DIMM_EVENT_COD_N      J1B1             78       SCONN288_H44441004_PIP-SCONN,HA
FM_DIMM_EVENT_COD_N      J1G1             78       SCONN288_H44441004_PIP-SCONN,HA
FM_DIMM_EVENT_COD_N      J1G2             78       SCONN288_H44441004_PIP-SCONN,HA
FM_DIMM_EVENT_COD_N      J1G3             78       SCONN288_H44441004_PIP-SCONN,HA
FM_DIMM_EVENT_COD_N      J4A1             78       SCONN288_H44441004_PIP-SCONN,HA
FM_DIMM_EVENT_COD_N      J4A2             78       SCONN288_H44441004_PIP-SCONN,HA
FM_DIMM_EVENT_COD_N      J4B1             78       SCONN288_H44441004_PIP-SCONN,HA
FM_DIMM_EVENT_COD_N      J4G1             78       SCONN288_H44441004_PIP-SCONN,HA
FM_DIMM_EVENT_COD_N      J4G2             78       SCONN288_H44441004_PIP-SCONN,HA
FM_DIMM_EVENT_COD_N      J4G3             78       SCONN288_H44441004_PIP-SCONN,HA
FM_DIMM_EVENT_COD_N      J6L1             78       SCONN288_H44441003_PIP-SCONN,HA
FM_DIMM_EVENT_COD_N      J6L2             78       SCONN288_H44441003_PIP-SCONN,HA
FM_DIMM_EVENT_COD_N      J6M1             78       SCONN288_H44441003_PIP-SCONN,HA
FM_DIMM_EVENT_COD_N      J6T1             78       SCONN288_H44441003_PIP-SCONN,HA
FM_DIMM_EVENT_COD_N      J6U1             78       SCONN288_H44441003_PIP-SCONN,HA
FM_DIMM_EVENT_COD_N      J6U2             78       SCONN288_H44441003_PIP-SCONN,HA
FM_DIMM_EVENT_COD_N      J9L1             78       SCONN288_H44441003_PIP-SCONN,HA
FM_DIMM_EVENT_COD_N      J9L2             78       SCONN288_H44441003_PIP-SCONN,HA
FM_DIMM_EVENT_COD_N      J9M1             78       SCONN288_H44441003_PIP-SCONN,HA
FM_DIMM_EVENT_COD_N      J9T1             78       SCONN288_H44441003_PIP-SCONN,HA
FM_DIMM_EVENT_COD_N      J9U1             78       SCONN288_H44441003_PIP-SCONN,HA
FM_DIMM_EVENT_COD_N      J9U2             78       SCONN288_H44441003_PIP-SCONN,HA
FM_DIMM_EVENT_COD_N      Q4U1             2        FET_N_DUAL_SMLF-NTJD4001N,FET,A
FM_DIMM_EVENT_COD_N      R4U2             2        RES_0402-2.21K,1%,1/16W,CHIP,GA
FM_DIMM_EVENT_FET        Q4U1             5        FET_N_DUAL_SMLF-NTJD4001N,FET,A
FM_DIMM_EVENT_FET        Q4U1             6        FET_N_DUAL_SMLF-NTJD4001N,FET,A
FM_DIMM_EVENT_FET        R4U3             2        RES_0402-4.75K,1%,1/16W,CHIP,GA
FM_DIMM_EVENT_FET        R4U4             1        RES_0402-33.0K,5%,1/16W,CHIP,GA
FM_DISABLE_FAN_N         CR9P1            2        DIODE_SMLF-BAT54WS,IC,C73510-0A
FM_DISABLE_FAN_N         CR9P2            2        DIODE_SMLF-BAT54WS,IC,C73510-0A
FM_DISABLE_FAN_N         R9P5             2        RES_0402-10.0K,1%,1/16W,CHIP,GA
FM_DISABLE_FAN_N         U1E2             2        TTL1G08_SOTLF-NC7SZ08,IC,D1032B
FM_DIS_ADR_DLY           J8G2             10       CONN12_C73564003_PIP-CONN,C735A
FM_DIS_ADR_DLY           R2P19            2        RES_0402-10.0K,1%,1/16W,CHIP,GA
FM_DIS_ADR_DLY           U8D7             T3       LCMXO2_A_256BGA-IC,H63395-001
FM_DUAL_BIOS_SEL_N       Q8F1             3        FET_N_SOT23LF-2N7002,FET,C7925A
FM_DUAL_BIOS_SEL_N       R2T11            2        RES_0402-4.75K,1%,1/16W,CHIP,GA
FM_DUAL_BIOS_SEL_N       U2T3             1        TTL1G32_A_SOT-74LVC1G32,IC,E60B
FM_ENABLE_FAN_POWER      EU9M1            2        SLG55021_SM-IC,G56246-001
FM_ENABLE_FAN_POWER      J1F1             I3       CONN76_H22707001_THMT1-CONN,H2A
FM_ENABLE_FAN_POWER      R1E11            2        RES_0402-10.0K,1%,1/16W,EMPTY,A
FM_ENABLE_FAN_POWER      U1E2             4        TTL1G08_SOTLF-NC7SZ08,IC,D1032B
FM_FAST_PROCHOT_AND_OUT_0_N U8E1             3        TTL08_QFN15-74LVC08A,IC,D90404B
FM_FAST_PROCHOT_AND_OUT_0_N U8E1             12       TTL08_QFN15-74LVC08A,IC,D90404B
FM_FAST_PROCHOT_AND_OUT_1_N U8E1             6        TTL08_QFN15-74LVC08A,IC,D90404B
FM_FAST_PROCHOT_AND_OUT_1_N U8E1             13       TTL08_QFN15-74LVC08A,IC,D90404B
FM_FAST_PROCHOT_EN       Q8F2             3        FET_N_SOT23LF-2N7002,FET,C7925A
FM_FAST_PROCHOT_EN       R9F3             2        RES_0402-4.75K,1%,1/16W,CHIP,GA
FM_FAST_PROCHOT_EN       U1R2             1        TTL1G126_A_SOT-74HC1G126,IC,A7B
FM_FAST_PROCHOT_EN_N     Q8F2             1        FET_N_SOT23LF-2N7002,FET,C7925A
FM_FAST_PROCHOT_EN_N     R2T3             2        RES_0402-4.75K,1%,1/16W,CHIP,GA
FM_FAST_PROCHOT_EN_N     U7C1             BH17     LBG_CORE_QAT_EXT_D_BGA1-IC,H91A
FM_FAST_PROCHOT_EN_N     U9F4             F18      AST1250_BGA-IC,G85138-002
FM_FAST_PROCHOT_THROTTLE_DLY_BU R1R5             2        RES_0402-4.75K,1%,1/16W,CHIP,GA
FM_FAST_PROCHOT_THROTTLE_DLY_BU U1R1             2        TTL1G07_A_SOP-74LVC1G07,IC,C88B
FM_FAST_PROCHOT_THROTTLE_DLY_BU U1R2             4        TTL1G126_A_SOT-74HC1G126,IC,A7B
FM_FAST_PROCHOT_THROTTLE_DLY_N U1R2             2        TTL1G126_A_SOT-74HC1G126,IC,A7B
FM_FAST_PROCHOT_THROTTLE_DLY_N U8D7             J12      LCMXO2_A_256BGA-IC,H63395-001
FM_FAST_PROCHOT_THROTTLE_IN_N U8D7             G16      LCMXO2_A_256BGA-IC,H63395-001
FM_FAST_PROCHOT_THROTTLE_IN_N U8E1             11       TTL08_QFN15-74LVC08A,IC,D90404B
FM_FLASH_ATTACH_CFG_STRAP R3P62            2        RES_0402-4.75K,1%,1/16W,EMPTY,A
FM_FLASH_ATTACH_CFG_STRAP R3P64            1        RES_0402-1.00K,1%,1/16W,EMPTY,A
FM_FLASH_ATTACH_CFG_STRAP U7C1             BB1      LBG_CORE_QAT_EXT_D_BGA1-IC,H91A
FM_FLASH_DESC_OVERRIDE   R1T24            2        RES_0402-0.0,5%,1/16W,EMPTY,G2A
FM_FLASH_DESC_OVERRIDE   R3N2             2        RES_0402-4.75K,1%,1/16W,EMPTY,A
FM_FLASH_DESC_OVERRIDE   U7C1             U24      LBG_CORE_QAT_EXT_D_BGA1-IC,H91A
FM_FLASH_DESC_OVERRIDE_R R1T24            1        RES_0402-0.0,5%,1/16W,EMPTY,G2A
FM_FLASH_DESC_OVERRIDE_R U9F4             U19      AST1250_BGA-IC,G85138-002
FM_FORCE_ADR_N           R2R7             2        RES_0402-4.75K,1%,1/16W,CHIP,GA
FM_FORCE_ADR_N           U7C1             AR13     LBG_CORE_QAT_EXT_D_BGA1-IC,H91A
FM_FORCE_ADR_N           U8D7             D7       LCMXO2_A_256BGA-IC,H63395-001
FM_FORCE_ADR_N           U9F4             A3       AST1250_BGA-IC,G85138-002
FM_GBE0_LVC3_MOD_ABS     J8E4             37       SCONN64_H87568002_A_SMT-CONN,HA
FM_GBE0_LVC3_MOD_ABS     U7C1             BV10     LBG_CORE_QAT_EXT_D_BGA1-IC,H91A
FM_GBE1_LVC3_MOD_ABS     J8E4             38       SCONN64_H87568002_A_SMT-CONN,HA
FM_GBE1_LVC3_MOD_ABS     U7C1             BY10     LBG_CORE_QAT_EXT_D_BGA1-IC,H91A
FM_GBE2_LVC3_MOD_ABS     J8E4             31       SCONN64_H87568002_A_SMT-CONN,HA
FM_GBE2_LVC3_MOD_ABS     U7C1             BW13     LBG_CORE_QAT_EXT_D_BGA1-IC,H91A
FM_GBE3_LVC3_MOD_ABS     J8E4             32       SCONN64_H87568002_A_SMT-CONN,HA
FM_GBE3_LVC3_MOD_ABS     U7C1             BY12     LBG_CORE_QAT_EXT_D_BGA1-IC,H91A
FM_GBE_LOM_DISABLE_N     R2N6             2        RES_0402-10.0K,1%,1/16W,CHIP,GA
FM_GBE_LOM_DISABLE_N     R8C23            1        RES_0402-0.0,5%,1/16W,EMPTY,G2A
FM_GBE_LOM_DISABLE_N     R8C24            1        RES_0402-0.0,5%,1/16W,CHIP,G21A
FM_GBE_LOM_DISABLE_N     U7C1             A13      LBG_CORE_QAT_EXT_D_BGA1-IC,H91A
FM_GLOBAL_RST_WARN_N     U7C1             BL18     LBG_CORE_QAT_EXT_D_BGA1-IC,H91A
FM_GLOBAL_RST_WARN_N     U8D7             P1       LCMXO2_A_256BGA-IC,H63395-001
FM_HBW_BYPASS_LOWBW_N    EU4D2            5        NB3W1200L_LCC-IC,H13585-001
FM_HBW_BYPASS_LOWBW_N    R4D41            2        RES_0402-4.75K,1%,1/16W,CHIP,GA
FM_HBW_BYPASS_LOWBW_N    R6P22            1        RES_0402-4.75K,1%,1/16W,EMPTY,A
FM_HEARTBEAT_LED         Q9E1             5        FET_N_DUAL_SMLF-NTJD4001N,FET,A
FM_HEARTBEAT_LED         Q9E1             6        FET_N_DUAL_SMLF-NTJD4001N,FET,A
FM_HEARTBEAT_LED         R9E21            2        RES_0402-4.75K,1%,1/16W,CHIP,GA
FM_HEARTBEAT_LED_A       DS9E1            1        LED_A1LF-GREEN,IC,C97278-010
FM_HEARTBEAT_LED_A       R9E24            1        RES_0402-221,1.0%,1/16W,CHIP,GA
FM_HEARTBEAT_LED_K       DS9E1            2        LED_A1LF-GREEN,IC,C97278-010
FM_HEARTBEAT_LED_K       Q9E1             3        FET_N_DUAL_SMLF-NTJD4001N,FET,A
FM_HSC_TIMER_EXP_N       R9P20            2        RES_0402-2.7K,1%,1/16W,CHIP,G2A
FM_HSC_TIMER_EXP_N       U7C1             AK9      LBG_CORE_QAT_EXT_D_BGA1-IC,H91A
FM_HSC_TIMER_EXP_N       U8E1             5        TTL08_QFN15-74LVC08A,IC,D90404B
FM_HSC_TIMER_EXP_N       U9F4             U3       AST1250_BGA-IC,G85138-002
FM_HSC_TIMER_EXP_N       U9P2             1        TPS3700_SM-IC,H69492-001
FM_IE_DISABLE_N          J8G2             4        CONN12_C73564003_PIP-CONN,C735A
FM_IE_DISABLE_N          R8D21            2        RES_0402-1.00K,1%,1/16W,CHIP,GA
FM_IE_DISABLE_N          U7C1             AU13     LBG_CORE_QAT_EXT_D_BGA1-IC,H91A
FM_IE_DISABLE_N          U8D7             L9       LCMXO2_A_256BGA-IC,H63395-001
FM_INTRUDER_HDR_PCH_N    R3N10            2        RES_0402-10.0K,1%,1/16W,CHIP,GA
FM_INTRUDER_HDR_PCH_N    U7C1             AG18     LBG_CORE_QAT_EXT_D_BGA1-IC,H91A
FM_JTAG_PLD_EN_DEBUG     R3R11            1        RES_0402-10.0K,1%,1/16W,EMPTY,A
FM_JTAG_PLD_EN_DEBUG     R3R15            2        RES_0402-1.00K,1%,1/16W,CHIP,GA
FM_JTAG_PLD_EN_DEBUG     U8D7             C10      LCMXO2_A_256BGA-IC,H63395-001
FM_M2_DET_LVC3           R2P14            1        RES_0402-0.0,5%,1/16W,CHIP,G21A
FM_M2_DET_LVC3           R2P16            2        RES_0402-10.0K,1%,1/16W,CHIP,GA
FM_M2_DET_LVC3           U2P1             4        TTL1G07_A_SOP-74LVC1G07,IC,C88B
FM_M2_SSD_PEDET          J8F1             69       SCONN75K_H17033002_SMT1-SCONN,A
FM_M2_SSD_PEDET          R2P15            2        RES_0402-10.0K,1%,1/16W,CHIP,GA
FM_M2_SSD_PEDET          U2P1             2        TTL1G07_A_SOP-74LVC1G07,IC,C88B
FM_MATED_IN_D1_N         CR1F3            2        DIODE_SM-SDMK0340L,IC,H71799-0A
FM_MATED_IN_D1_N         CR1F4            1        DIODE_SM-SDMK0340L,IC,H71799-0A
FM_MATED_IN_D2_N         CR1F3            1        DIODE_SM-SDMK0340L,IC,H71799-0A
FM_MATED_IN_D2_N         Q9T1             1        NPN_SM-MMBT3904,IC,C52245-001
FM_MATED_IN_N            CR1F4            2        DIODE_SM-SDMK0340L,IC,H71799-0A
FM_MATED_IN_N            J1F1             E4       CONN76_H22707001_THMT1-CONN,H2A
FM_MATED_IN_N            J1F3             4        CONN8_H62179001_PIP-CONN,H6217A
FM_MATED_IN_N            R9T8             1        RES_0402-0.0,5%,1/16W,EMPTY,G2A
FM_MATED_IN_N            R9T9             2        RES_0402-4.75K,1%,1/16W,CHIP,GA
FM_MB_SLOT_ID0           J1F1             F5       CONN76_H22707001_THMT1-CONN,H2A
FM_MB_SLOT_ID0           R7D5             2        RES_0402-2.26K,1.0%,1/16W,CHIPA
FM_MB_SLOT_ID0           U7C1             T4       LBG_CORE_QAT_EXT_D_BGA1-IC,H91A
FM_MB_SLOT_ID0           U9F4             V20      AST1250_BGA-IC,G85138-002
FM_MB_SLOT_ID1           J1F1             G5       CONN76_H22707001_THMT1-CONN,H2A
FM_MB_SLOT_ID1           R7D9             2        RES_0402-2.26K,1.0%,1/16W,CHIPA
FM_MB_SLOT_ID1           U7C1             AB3      LBG_CORE_QAT_EXT_D_BGA1-IC,H91A
FM_MB_SLOT_ID1           U9F4             W21      AST1250_BGA-IC,G85138-002
FM_MB_SLOT_ID2           J1F1             H5       CONN76_H22707001_THMT1-CONN,H2A
FM_MB_SLOT_ID2           R3P61            2        RES_0402-2.26K,1.0%,1/16W,CHIPA
FM_MB_SLOT_ID2           U7C1             AC4      LBG_CORE_QAT_EXT_D_BGA1-IC,H91A
FM_MB_SLOT_ID2           U9F4             Y22      AST1250_BGA-IC,G85138-002
FM_MEM_EVENT_FUNC        R7E19            2        RES_0402-1.00K,1%,1/16W,EMPTY,A
FM_MEM_EVENT_FUNC        R7E20            1        RES_0402-1.00K,1%,1/16W,CHIP,GA
FM_MEM_EVENT_FUNC        U8D7             D2       LCMXO2_A_256BGA-IC,H63395-001
FM_MEM_THERM_EVENT_LVT3_N Q4U1             3        FET_N_DUAL_SMLF-NTJD4001N,FET,A
FM_MEM_THERM_EVENT_LVT3_N R4U1             2        RES_0402-4.75K,1%,1/16W,CHIP,GA
FM_MEM_THERM_EVENT_LVT3_N R8E11            1        RES_0402-0.0,5%,1/16W,EMPTY,G2A
FM_MEM_THERM_EVENT_LVT3_N U8D7             K13      LCMXO2_A_256BGA-IC,H63395-001
FM_MEM_THERM_EVENT_PCH_N U7C1             AL15     LBG_CORE_QAT_EXT_D_BGA1-IC,H91A
FM_MEM_THERM_EVENT_PCH_N U8D7             K12      LCMXO2_A_256BGA-IC,H63395-001
FM_MEM_THERM_EVENT_PCH_N U9F4             U4       AST1250_BGA-IC,G85138-002
FM_MEZZA_PRSNT1_N        J9B3             1        SCONN120_A28699018_SM-SCONN,A2A
FM_MEZZA_PRSNT1_N        R9B7             2        RES_0402-100.0,1%,1/16W,CHIP,GA
FM_MEZZ_PRSNTB1_N        J8E3             1        SCONN80_E67482007_SM-CONN,E674A
FM_MEZZ_PRSNTB1_N        R2R8             1        RES_0402-100.0,1%,1/16W,CHIP,GA
FM_ME_RECOVER_N          J7G3             3        CONN12_C73564003_PIP-CONN,C735A
FM_ME_RECOVER_N          R7G26            2        RES_0402-10.0K,1%,1/16W,CHIP,GA
FM_ME_RECOVER_N          U7C1             V3       LBG_CORE_QAT_EXT_D_BGA1-IC,H91A
FM_MODPRST_HFI0_CPU0_LVT2_N J8B1             3        SCONN24_H46321001_SM-SCONN,H46A
FM_MODPRST_HFI0_CPU0_LVT2_N R8B3             2        RES_0402-4.75K,1%,1/16W,CHIP,GA
FM_MODPRST_HFI0_CPU0_LVT2_N U5D1             BR20     SKX_EXT_B_BGA1-IC,TBD
FM_MODPRST_HFI1_CPU0_LVT2_N J8B1             11       SCONN24_H46321001_SM-SCONN,H46A
FM_MODPRST_HFI1_CPU0_LVT2_N R8B19            2        RES_0402-4.75K,1%,1/16W,CHIP,GA
FM_MODPRST_HFI1_CPU0_LVT2_N U5D1             BT19     SKX_EXT_B_BGA1-IC,TBD
FM_MP_PS_FAIL_N          J1F3             3        CONN8_H62179001_PIP-CONN,H6217A
FM_MP_PS_FAIL_N          R3N12            2        RES_0402-4.75K,1%,1/16W,CHIP,GA
FM_MP_PS_FAIL_N          U7C1             AK20     LBG_CORE_QAT_EXT_D_BGA1-IC,H91A
FM_MP_PS_FAIL_N          U8D7             H4       LCMXO2_A_256BGA-IC,H63395-001
FM_MP_PS_FAIL_N          U9F4             W6       AST1250_BGA-IC,G85138-002
FM_MP_PS_REDUNDANT_LOST_N J1F3             2        CONN8_H62179001_PIP-CONN,H6217A
FM_MP_PS_REDUNDANT_LOST_N R3N11            2        RES_0402-4.75K,1%,1/16W,CHIP,GA
FM_MP_PS_REDUNDANT_LOST_N U7C1             AK13     LBG_CORE_QAT_EXT_D_BGA1-IC,H91A
FM_MP_PS_REDUNDANT_LOST_N U9F4             AA5      AST1250_BGA-IC,G85138-002
FM_NMI_EVENT_N           R2N25            1        RES_0402-51.1,1.0%,1/16W,CHIP,A
FM_NMI_EVENT_N           U7C1             BE7      LBG_CORE_QAT_EXT_D_BGA1-IC,H91A
FM_OC0_USB_N             R1M24            2        RES_0402-10.0K,1%,1/16W,CHIP,GA
FM_OC0_USB_N             U1M3             3        TPS2061_SM-IC,H66405-001
FM_OC0_USB_N             U7C1             BL48     LBG_CORE_QAT_EXT_D_BGA1-IC,H91A
FM_OCP_MEZZA_PRES_N      J9B3             120      SCONN120_A28699018_SM-SCONN,A2A
FM_OCP_MEZZA_PRES_N      R7D12            2        RES_0402-10.0K,1%,1/16W,CHIP,GA
FM_OCP_MEZZA_PRES_N      U7C1             AE2      LBG_CORE_QAT_EXT_D_BGA1-IC,H91A
FM_OCP_MEZZB_PRES_N      J8E3             80       SCONN80_E67482007_SM-CONN,E674A
FM_OCP_MEZZB_PRES_N      R7D44            2        RES_0402-4.75K,1%,1/16W,CHIP,GA
FM_OCP_MEZZB_PRES_N      U7C1             AD9      LBG_CORE_QAT_EXT_D_BGA1-IC,H91A
FM_OCP_MEZZC_PRES_N      J8E4             64       SCONN64_H87568002_A_SMT-CONN,HA
FM_OCP_MEZZC_PRES_N      R3P53            2        RES_0402-4.75K,1%,1/16W,CHIP,GA
FM_OCP_MEZZC_PRES_N      U7C1             AD17     LBG_CORE_QAT_EXT_D_BGA1-IC,H91A
FM_OC_DETECT_EN          Q1D2             3        FET_N_SOT23LF-2N7002,FET,C7925A
FM_OC_DETECT_EN          R1D21            2        RES_0402-4.75K,1%,1/16W,CHIP,GA
FM_OC_DETECT_EN          U1D1             1        TTL1G126_A_SOT-74HC1G126,IC,A7B
FM_OC_DETECT_EN_N        Q1D2             1        FET_N_SOT23LF-2N7002,FET,C7925A
FM_OC_DETECT_EN_N        R1D35            2        RES_0402-4.75K,1%,1/16W,CHIP,GA
FM_OC_DETECT_EN_N        R7D19            1        RES_0402-1.00K,1%,1/16W,EMPTY,A
FM_OC_DETECT_EN_N        U7C1             BC4      LBG_CORE_QAT_EXT_D_BGA1-IC,H91A
FM_OC_DETECT_EN_N        U9F4             V4       AST1250_BGA-IC,G85138-002
FM_OC_DETECT_N           R1D22            2        RES_0402-10.0K,1%,1/16W,CHIP,GA
FM_OC_DETECT_N           U1D1             4        TTL1G126_A_SOT-74HC1G126,IC,A7B
FM_OC_DETECT_N           U8E1             2        TTL08_QFN15-74LVC08A,IC,D90404B
FM_P12V_HOTSWAP0_EN      C1D11            1        CAP_A_0402V-0.1UF,16V,10%,X7R,A
FM_P12V_HOTSWAP0_EN      EU1D2            12       ADM1278_SM-IC,G99251-001
FM_P12V_HOTSWAP0_EN      Q9T1             3        NPN_SM-MMBT3904,IC,C52245-001
FM_P12V_HOTSWAP0_EN      R9T3             1        RES_0402-6.19K,1%,1/16W,CHIP,GA
FM_P12V_HOTSWAP0_EN      R9T6             2        RES_0402-15.0K,1%,1/16W,CHIP,GA
FM_P12V_HSC_ADR1         EU1D2            7        ADM1278_SM-IC,G99251-001
FM_P12V_HSC_ADR1         R1D29            2        RES_0402-4.75K,1%,1/16W,EMPTY,A
FM_P12V_HSC_ADR1         R9P17            1        RES_0402-150.0K,1%,1/16W,CHIP,A
FM_P12V_HSC_ADR2         EU1D2            8        ADM1278_SM-IC,G99251-001
FM_P12V_HSC_ADR2         R1D27            2        RES_0402-4.75K,1%,1/16W,EMPTY,A
FM_P12V_HSC_ADR2         R9P16            1        RES_0402-0.0,5%,1/16W,CHIP,G21A
FM_P12V_MAIN_SW_EN       EU7E1            2        SLG55021_SM-IC,G56246-001
FM_P12V_MAIN_SW_EN       U8D7             R16      LCMXO2_A_256BGA-IC,H63395-001
FM_P1V8MCP_CPU0_EN       J6B1             A15      SCONN120_H61426002_SM-CONN,H61A
FM_P1V8MCP_CPU0_EN       U8D7             E16      LCMXO2_A_256BGA-IC,H63395-001
FM_P1V8MCP_CPU1_EN       J4B2             A15      SCONN120_H61426002_SM-CONN,H61A
FM_P1V8MCP_CPU1_EN       U8D7             F12      LCMXO2_A_256BGA-IC,H63395-001
FM_P3V3_CPLD_EN          EU2T1            2        SLG55021_SM-IC,G56246-001
FM_P3V3_CPLD_EN          U8D7             A4       LCMXO2_A_256BGA-IC,H63395-001
FM_PASSWORD_CLEAR_N      J7G3             9        CONN12_C73564003_PIP-CONN,C735A
FM_PASSWORD_CLEAR_N      R2N28            2        RES_0402-10.0K,1%,1/16W,CHIP,GA
FM_PASSWORD_CLEAR_N      U7C1             BW32     LBG_CORE_QAT_EXT_D_BGA1-IC,H91A
FM_PCH_BMC_THERMTRIP_EXI_STRAP_ Q8D2             2        FET_N_SOT23-2N7002,FET,C79254-A
FM_PCH_BMC_THERMTRIP_EXI_STRAP_ R2N10            2        RES_0402-4.75K,1%,1/16W,CHIP,GA
FM_PCH_BMC_THERMTRIP_EXI_STRAP_ U7C1             BM20     LBG_CORE_QAT_EXT_D_BGA1-IC,H91A
FM_PCH_BMC_THERMTRIP_N   Q8D2             3        FET_N_SOT23-2N7002,FET,C79254-A
FM_PCH_BMC_THERMTRIP_N   R2P17            2        RES_0402-4.75K,1%,1/16W,CHIP,GA
FM_PCH_BMC_THERMTRIP_N   U7C1             BH2      LBG_CORE_QAT_EXT_D_BGA1-IC,H91A
FM_PCH_BMC_THERMTRIP_N   U9F4             D18      AST1250_BGA-IC,G85138-002
FM_PCH_LVC1_THERMTRIP_N  Q7D1             3        FET_N_SOT23-2N7002,FET,C79254-A
FM_PCH_LVC1_THERMTRIP_N  R7C21            2        RES_0402-10.0K,1%,1/16W,CHIP,GA
FM_PCH_LVC1_THERMTRIP_N  U7C1             V15      LBG_CORE_QAT_EXT_D_BGA1-IC,H91A
FM_PCH_PLD_DATA          R2M3             2        RES_0402-33.2,1%,1/16W,CHIP,G2A
FM_PCH_PLD_DATA          R2R5             2        RES_0402-1.00K,1%,1/16W,CHIP,GA
FM_PCH_PLD_DATA          U8D7             C2       LCMXO2_A_256BGA-IC,H63395-001
FM_PCH_PLD_DATA_R        R2M3             1        RES_0402-33.2,1%,1/16W,CHIP,G2A
FM_PCH_PLD_DATA_R        U7C1             BM42     LBG_CORE_QAT_EXT_D_BGA1-IC,H91A
FM_PCH_PRSNT_N           R7B6             2        RES_0402-10.0K,1%,1/16W,CHIP,GA
FM_PCH_PRSNT_N           U7C1             C70      LBG_CORE_QAT_EXT_D_BGA1-IC,H91A
FM_PCH_PRSNT_N           U8D7             A3       LCMXO2_A_256BGA-IC,H63395-001
FM_PCH_PWRBTN_N          R2T28            2        RES_0402-33.2,1%,1/16W,CHIP,G2A
FM_PCH_PWRBTN_N          U7C1             C15      LBG_CORE_QAT_EXT_D_BGA1-IC,H91A
FM_PCH_PWRBTN_N          U8D7             B12      LCMXO2_A_256BGA-IC,H63395-001
FM_PCH_PWRBTN_OUT_N      R8G2             2        RES_0402-4.75K,1%,1/16W,CHIP,GA
FM_PCH_PWRBTN_OUT_N      U7C1             BG15     LBG_CORE_QAT_EXT_D_BGA1-IC,H91A
FM_PCH_PWRBTN_OUT_N      U8G1             3        TTL2G07_SOT23LF-74LVC2G07,IC,DB
FM_PCH_PWRBTN_R_N        R2T28            1        RES_0402-33.2,1%,1/16W,CHIP,G2A
FM_PCH_PWRBTN_R_N        R8F26            2        RES_0402-10.0K,1%,1/16W,CHIP,GA
FM_PCH_PWRBTN_R_N        U8F3             4        TTL2G07_SOT23LF-74LVC2G07,IC,DB
FM_PCH_PWRBTN_R_N        U8G1             4        TTL2G07_SOT23LF-74LVC2G07,IC,DB
FM_PCH_SATA_RAID_KEY     R9A13            2        RES_0402-33.2,1%,1/16W,CHIP,G2A
FM_PCH_SATA_RAID_KEY     U7C1             BV31     LBG_CORE_QAT_EXT_D_BGA1-IC,H91A
FM_PCH_SATA_RAID_KEY_R   J9A1             4        CONN4_D42317002_PIP-CONN,D4231A
FM_PCH_SATA_RAID_KEY_R   R9A12            1        RES_0402-2.21K,1%,1/16W,CHIP,GA
FM_PCH_SATA_RAID_KEY_R   R9A13            1        RES_0402-33.2,1%,1/16W,CHIP,G2A
FM_PE_BMC_WAKE_N         R8E29            1        RES_0402-0.0,5%,1/16W,EMPTY,G2A
FM_PE_BMC_WAKE_N         R9F46            1        RES_0402-100.0K,1%,1/16W,CHIP,A
FM_PE_BMC_WAKE_N         U9F4             J22      AST1250_BGA-IC,G85138-002
FM_PE_M2_WAKE_N          J8F1             54       SCONN75K_H17033002_SMT1-SCONN,A
FM_PE_M2_WAKE_N          R8E27            1        RES_0402-0.0,5%,1/16W,CHIP,G21A
FM_PE_OCP_WAKE_N         J9B3             34       SCONN120_A28699018_SM-SCONN,A2A
FM_PE_OCP_WAKE_N         R8E26            1        RES_0402-0.0,5%,1/16W,CHIP,G21A
FM_PE_SLOTX24_WAKE_N     J8G1             28       SCONN200_H68296001_SM-CONN,H68A
FM_PE_SLOTX24_WAKE_N     R8E28            1        RES_0402-0.0,5%,1/16W,CHIP,G21A
FM_PE_SLOTX24_WAKE_N     R8E36            2        RES_0402-10.0K,1%,1/16W,CHIP,GA
FM_PE_SPRV_WAKE_N        EU9E1            16       SPRINGVILLE_SM1-IC,G47144-004
FM_PE_SPRV_WAKE_N        R8E21            1        RES_0402-0.0,5%,1/16W,CHIP,G21A
FM_PI7C9X1172_A0         EU9F3            30       PI7C9X1172_QFN-IC,H66899-001
FM_PI7C9X1172_A0         R9F49            2        RES_0402-4.75K,1%,1/16W,EMPTY,A
FM_PI7C9X1172_A0         R9F51            1        RES_0402-1.00K,1%,1/16W,CHIP,GA
FM_PI7C9X1172_A1         EU9F3            31       PI7C9X1172_QFN-IC,H66899-001
FM_PI7C9X1172_A1         R9F48            2        RES_0402-4.75K,1%,1/16W,EMPTY,A
FM_PI7C9X1172_A1         R9F50            1        RES_0402-1.00K,1%,1/16W,CHIP,GA
FM_PLD_DEBUG_MODE_N      R2R3             2        RES_0402-10.0K,1%,1/16W,CHIP,GA
FM_PLD_DEBUG_MODE_N      U8D7             F7       LCMXO2_A_256BGA-IC,H63395-001
FM_PMBUS_ALERT_BUF_EN    Q2P1             3        FET_N_SOT23LF-2N7002,FET,C7925A
FM_PMBUS_ALERT_BUF_EN    R2P5             2        RES_0402-4.75K,1%,1/16W,CHIP,GA
FM_PMBUS_ALERT_BUF_EN    U8D5             1        TTL1G126_A_SOT-74HC1G126,IC,A7B
FM_PMBUS_ALERT_BUF_EN_N  Q2P1             1        FET_N_SOT23LF-2N7002,FET,C7925A
FM_PMBUS_ALERT_BUF_EN_N  R2P11            1        RES_0402-1.00K,1%,1/16W,EMPTY,A
FM_PMBUS_ALERT_BUF_EN_N  R2P13            2        RES_0402-4.75K,1%,1/16W,CHIP,GA
FM_PMBUS_ALERT_BUF_EN_N  U7C1             BK9      LBG_CORE_QAT_EXT_D_BGA1-IC,H91A
FM_PMBUS_ALERT_BUF_EN_N  U7C1             BY35     LBG_CORE_QAT_EXT_D_BGA1-IC,H91A
FM_PMBUS_ALERT_BUF_EN_N  U9F4             V2       AST1250_BGA-IC,G85138-002
FM_POST_CARD_PRES_BMC_N  Q1L4             6        FET_N_DUAL_SMLF-2N7002DW,FET,DA
FM_POST_CARD_PRES_BMC_N  R1L38            2        RES_0402-1.00K,1%,1/16W,CHIP,GA
FM_POST_CARD_PRES_BMC_N  U7C1             BG52     LBG_CORE_QAT_EXT_D_BGA1-IC,H91A
FM_POST_CARD_PRES_BMC_N  U7C1             W4       LBG_CORE_QAT_EXT_D_BGA1-IC,H91A
FM_POST_CARD_PRES_BMC_N  U9F4             H18      AST1250_BGA-IC,G85138-002
FM_PRSNT_2_1_N           J8G1             27       SCONN200_H68296001_SM-CONN,H68A
FM_PRSNT_2_1_N           R3P7             2        RES_0402-1.00K,1%,1/16W,CHIP,GA
FM_PRSNT_2_1_N           U7C1             AE18     LBG_CORE_QAT_EXT_D_BGA1-IC,H91A
FM_PRSNT_2_2_N           J8G1             30       SCONN200_H68296001_SM-CONN,H68A
FM_PRSNT_2_2_N           R3P5             2        RES_0402-1.00K,1%,1/16W,CHIP,GA
FM_PRSNT_2_2_N           U7C1             AE15     LBG_CORE_QAT_EXT_D_BGA1-IC,H91A
FM_PRSNT_2_3_N           J8G1             32       SCONN200_H68296001_SM-CONN,H68A
FM_PRSNT_2_3_N           R3P6             2        RES_0402-1.00K,1%,1/16W,CHIP,GA
FM_PRSNT_2_3_N           U7C1             AE11     LBG_CORE_QAT_EXT_D_BGA1-IC,H91A
FM_PRSNT_2_4_N           J8G1             63       SCONN200_H68296001_SM-CONN,H68A
FM_PRSNT_2_4_N           R3N15            2        RES_0402-1.00K,1%,1/16W,CHIP,GA
FM_PRSNT_2_4_N           U7C1             Y18      LBG_CORE_QAT_EXT_D_BGA1-IC,H91A
FM_PRSNT_2_5_N           J8G1             66       SCONN200_H68296001_SM-CONN,H68A
FM_PRSNT_2_5_N           R3N16            2        RES_0402-1.00K,1%,1/16W,CHIP,GA
FM_PRSNT_2_5_N           U7C1             AA20     LBG_CORE_QAT_EXT_D_BGA1-IC,H91A
FM_PRSNT_2_6_N           J8G1             199      SCONN200_H68296001_SM-CONN,H68A
FM_PRSNT_2_6_N           R3P8             2        RES_0402-1.00K,1%,1/16W,CHIP,GA
FM_PRSNT_2_6_N           U7C1             AA17     LBG_CORE_QAT_EXT_D_BGA1-IC,H91A
FM_PS_EN                 C2R6             1        CAP_0402LF-470PF,50V,10%,EMPTYA
FM_PS_EN                 U8D7             F9       LCMXO2_A_256BGA-IC,H63395-001
FM_PS_EN                 U8E1             9        TTL08_QFN15-74LVC08A,IC,D90404B
FM_PVCCIN_CPU0_PWR_IN_ALERT_N EU4D4            14       PXE1610B_QFN-IC,H79206-001
FM_PVCCIN_CPU0_PWR_IN_ALERT_N R4E4             2        RES_0402-2.26K,1.0%,1/16W,CHIPA
FM_PVCCIN_CPU0_PWR_IN_ALERT_N U7E2             1        TTL1G08_SOTLF-NC7SZ08,IC,D1032B
FM_PVCCIN_CPU1_PWR_IN_ALERT_N EU1C2            14       PXE1610B_QFN-IC,H79206-001
FM_PVCCIN_CPU1_PWR_IN_ALERT_N R1D7             2        RES_0402-2.26K,1.0%,1/16W,CHIPA
FM_PVCCIN_CPU1_PWR_IN_ALERT_N U7E3             1        TTL1G08_SOTLF-NC7SZ08,IC,D1032B
FM_PVCCIN_PVCCSA_CPU0_EN_LVC1 R6P18            1        RES_0402-0.0,5%,1/16W,CHIP,G21A
FM_PVCCIN_PVCCSA_CPU0_EN_LVC1 U8D7             A10      LCMXO2_A_256BGA-IC,H63395-001
FM_PVCCIN_PVCCSA_CPU1_EN_LVC1 R9N16            1        RES_0402-0.0,5%,1/16W,CHIP,G21A
FM_PVCCIN_PVCCSA_CPU1_EN_LVC1 U8D7             N16      LCMXO2_A_256BGA-IC,H63395-001
FM_PVCCIOMCP_CPU0_EN     J6B1             A16      SCONN120_H61426002_SM-CONN,H61A
FM_PVCCIOMCP_CPU0_EN     U8D7             K1       LCMXO2_A_256BGA-IC,H63395-001
FM_PVCCIOMCP_CPU1_EN     J4B2             A16      SCONN120_H61426002_SM-CONN,H61A
FM_PVCCIOMCP_CPU1_EN     U8D7             P7       LCMXO2_A_256BGA-IC,H63395-001
FM_PVCCIO_CPU0_EN        R3P26            1        RES_0402-0.0,5%,1/16W,CHIP,G21A
FM_PVCCIO_CPU0_EN        U8D7             M7       LCMXO2_A_256BGA-IC,H63395-001
FM_PVCCIO_CPU1_EN        R6P41            1        RES_0402-0.0,5%,1/16W,CHIP,G21A
FM_PVCCIO_CPU1_EN        U8D7             T7       LCMXO2_A_256BGA-IC,H63395-001
FM_PVCCMCP_CPU0_EN       J6B1             C20      SCONN120_H61426002_SM-CONN,H61A
FM_PVCCMCP_CPU0_EN       U8D7             H2       LCMXO2_A_256BGA-IC,H63395-001
FM_PVCCMCP_CPU1_EN       J4B2             C20      SCONN120_H61426002_SM-CONN,H61A
FM_PVCCMCP_CPU1_EN       U8D7             M8       LCMXO2_A_256BGA-IC,H63395-001
FM_PVDDQ_ABC_EN          R7F21            1        RES_0402-0.0,5%,1/16W,CHIP,G21A
FM_PVDDQ_ABC_EN          U8D7             K14      LCMXO2_A_256BGA-IC,H63395-001
FM_PVDDQ_DEF_EN          R3M6             1        RES_0402-0.0,5%,1/16W,CHIP,G21A
FM_PVDDQ_DEF_EN          U8D7             K15      LCMXO2_A_256BGA-IC,H63395-001
FM_PVDDQ_GHJ_EN          R9U7             1        RES_0402-0.0,5%,1/16W,CHIP,G21A
FM_PVDDQ_GHJ_EN          U8D7             H13      LCMXO2_A_256BGA-IC,H63395-001
FM_PVDDQ_KLM_EN          R9M9             1        RES_0402-0.0,5%,1/16W,CHIP,G21A
FM_PVDDQ_KLM_EN          U8D7             H15      LCMXO2_A_256BGA-IC,H63395-001
FM_PVPP_CPU0_EN          C7B9             1        CAP_0402LF-1000PF,50V,10%,EMPTA
FM_PVPP_CPU0_EN          C7F8             1        CAP_0402LF-1000PF,50V,10%,EMPTA
FM_PVPP_CPU0_EN          R7B9             1        RES_0402-0.0,5%,1/16W,CHIP,G21A
FM_PVPP_CPU0_EN          R7F9             1        RES_0402-0.0,5%,1/16W,CHIP,G21A
FM_PVPP_CPU0_EN          R7F14            1        RES_0402-10.0K,1%,1/16W,CHIP,GA
FM_PVPP_CPU0_EN          U8D7             P15      LCMXO2_A_256BGA-IC,H63395-001
FM_PVPP_CPU1_EN          C4B5             1        CAP_0402LF-1000PF,50V,10%,EMPTA
FM_PVPP_CPU1_EN          C4G7             1        CAP_0402LF-1000PF,50V,10%,EMPTA
FM_PVPP_CPU1_EN          R4B1             1        RES_0402-0.0,5%,1/16W,CHIP,G21A
FM_PVPP_CPU1_EN          R4G4             1        RES_0402-0.0,5%,1/16W,CHIP,G21A
FM_PVPP_CPU1_EN          R4G5             1        RES_0402-10.0K,1%,1/16W,CHIP,GA
FM_PVPP_CPU1_EN          U8D7             P16      LCMXO2_A_256BGA-IC,H63395-001
FM_PVPP_PVDDQ_CPU0_EN_ABC EU7F1            40       NCP3232L_SM-IC,H86355-001
FM_PVPP_PVDDQ_CPU0_EN_ABC R7F9             2        RES_0402-0.0,5%,1/16W,CHIP,G21A
FM_PVPP_PVDDQ_CPU0_EN_DEF EU7B1            40       NCP3232L_SM-IC,H86355-001
FM_PVPP_PVDDQ_CPU0_EN_DEF R7B9             2        RES_0402-0.0,5%,1/16W,CHIP,G21A
FM_PVPP_PVDDQ_CPU1_EN_GHJ EU4G1            40       NCP3232L_SM-IC,H86355-001
FM_PVPP_PVDDQ_CPU1_EN_GHJ R4G4             2        RES_0402-0.0,5%,1/16W,CHIP,G21A
FM_PVPP_PVDDQ_CPU1_EN_KLM EU4A3            40       NCP3232L_SM-IC,H86355-001
FM_PVPP_PVDDQ_CPU1_EN_KLM R4B1             2        RES_0402-0.0,5%,1/16W,CHIP,G21A
FM_PVTT_ABC_EN_R         C4G23            1        CAP_0402LF-1000PF,50V,10%,EMPTA
FM_PVTT_ABC_EN_R         EU4G3            7        MIC5166_DFN-IC,H55101-001
FM_PVTT_ABC_EN_R         R4G23            2        RES_0402-0.0,5%,1/16W,CHIP,G21A
FM_PVTT_ABC_EN_R         R6U15            2        RES_0402-1.0M,1%,1/16W,EMPTY,GA
FM_PVTT_DEF_EN_R         C4A2             1        CAP_0402LF-1000PF,50V,10%,EMPTA
FM_PVTT_DEF_EN_R         EU4A1            7        MIC5166_DFN-IC,H55101-001
FM_PVTT_DEF_EN_R         R4A2             2        RES_0402-0.0,5%,1/16W,CHIP,G21A
FM_PVTT_DEF_EN_R         R6L4             2        RES_0402-1.0M,1%,1/16W,EMPTY,GA
FM_PVTT_GHJ_EN_R         C4G12            1        CAP_0402LF-1000PF,50V,10%,EMPTA
FM_PVTT_GHJ_EN_R         EU4G2            7        MIC5166_DFN-IC,H55101-001
FM_PVTT_GHJ_EN_R         R4G16            2        RES_0402-0.0,5%,1/16W,CHIP,G21A
FM_PVTT_GHJ_EN_R         R6U3             2        RES_0402-1.0M,1%,1/16W,EMPTY,GA
FM_PVTT_KLM_EN_R         C4A6             1        CAP_0402LF-1000PF,50V,10%,EMPTA
FM_PVTT_KLM_EN_R         EU4A2            7        MIC5166_DFN-IC,H55101-001
FM_PVTT_KLM_EN_R         R4A3             2        RES_0402-0.0,5%,1/16W,CHIP,G21A
FM_PVTT_KLM_EN_R         R6L5             2        RES_0402-1.0M,1%,1/16W,EMPTY,GA
FM_PWRBRK_N              Q7E8             3        FET_N_SOT23-2N7002,FET,C79254-A
FM_PWRBRK_N              R7E21            2        RES_0402-4.75K,1%,1/16W,CHIP,GA
FM_PWRBRK_N              R7E22            1        RES_0402-0.0,5%,1/16W,CHIP,G21A
FM_PWRBRK_SLOT_N         J8G1             20       SCONN200_H68296001_SM-CONN,H68A
FM_PWRBRK_SLOT_N         R2U50            2        RES_0402-0.0,5%,1/16W,EMPTY,G2A
FM_PWRBRK_SLOT_N         R7E22            2        RES_0402-0.0,5%,1/16W,CHIP,G21A
FM_PWR_BTN_N             R1L26            2        RES_0402-33.2,1%,1/16W,CHIP,G2A
FM_PWR_BTN_N             U7C1             BH20     LBG_CORE_QAT_EXT_D_BGA1-IC,H91A
FM_PWR_BTN_N             U8D7             G6       LCMXO2_A_256BGA-IC,H63395-001
FM_PWR_BTN_N             U9F4             B17      AST1250_BGA-IC,G85138-002
FM_PWR_BTN_R_N           R1L26            1        RES_0402-33.2,1%,1/16W,CHIP,G2A
FM_PWR_BTN_R_N           U9A4             4        TTL2G14_SMLF-74LVC2G14,IC,D184B
FM_PWR_LED               Q9A2             5        FET_N_DUAL_SMLF-NTJD4001N,FET,A
FM_PWR_LED               Q9A2             6        FET_N_DUAL_SMLF-NTJD4001N,FET,A
FM_PWR_LED               R9A18            2        RES_0402-4.75K,1%,1/16W,CHIP,GA
FM_PWR_LED_A             DS9A5            1        LED_A1LF-GREEN,IC,C97278-010
FM_PWR_LED_A             R9A20            1        RES_0402-221,1.0%,1/16W,CHIP,GA
FM_PWR_LED_K             DS9A5            2        LED_A1LF-GREEN,IC,C97278-010
FM_PWR_LED_K             Q9A2             3        FET_N_DUAL_SMLF-NTJD4001N,FET,A
FM_PWR_LED_N             Q9A2             2        FET_N_DUAL_SMLF-NTJD4001N,FET,A
FM_PWR_LED_N             R9A21            2        RES_0402-4.75K,1%,1/16W,CHIP,GA
FM_PWR_LED_N             U7C1             BK46     LBG_CORE_QAT_EXT_D_BGA1-IC,H91A
FM_QAT_EN_N              R2N23            2        RES_0402-10.0K,1%,1/16W,CHIP,GA
FM_QAT_EN_N              R2N24            1        RES_0402-1.00K,1%,1/16W,EMPTY,A
FM_QAT_EN_N              U7C1             BR9      LBG_CORE_QAT_EXT_D_BGA1-IC,H91A
FM_RED_LED_ANODE         DS9F1            1        LED_A1-RED,IC,D14725-005
FM_RED_LED_ANODE         R9F28            2        RES_0402-221,1.0%,1/16W,CHIP,GA
FM_RED_LED_CATHODE       DS9F1            2        LED_A1-RED,IC,D14725-005
FM_RED_LED_CATHODE       Q9F1             3        FET_N_DUAL_SMLF-NTJD4001N,FET,A
FM_ROMA<0>               J9G1             3        CONN12_C73564003_PIP-CONN,C735A
FM_ROMA<0>               R9E15            1        RES_0402-0.0,5%,1/16W,EMPTY,G2A
FM_ROMA<0>               U9F4             R20      AST1250_BGA-IC,G85138-002
FM_ROMA<1>               R9F40            1        RES_0402-4.75K,1%,1/16W,CHIP,GA
FM_ROMA<1>               U9F4             R21      AST1250_BGA-IC,G85138-002
FM_ROMA<2>               R9F39            1        RES_0402-4.75K,1%,1/16W,EMPTY,A
FM_ROMA<2>               U9F4             R22      AST1250_BGA-IC,G85138-002
FM_ROMA<3>               R9F19            1        RES_0402-4.75K,1%,1/16W,EMPTY,A
FM_ROMA<3>               U9F4             P18      AST1250_BGA-IC,G85138-002
FM_ROMA<4>               R9F18            1        RES_0402-4.75K,1%,1/16W,EMPTY,A
FM_ROMA<4>               U9F4             P19      AST1250_BGA-IC,G85138-002
FM_ROMA<5>               R1T16            1        RES_0402-4.75K,1%,1/16W,EMPTY,A
FM_ROMA<5>               U9F4             P20      AST1250_BGA-IC,G85138-002
FM_ROMA<6>               R9F10            1        RES_0402-4.75K,1%,1/16W,EMPTY,A
FM_ROMA<6>               U9F4             P21      AST1250_BGA-IC,G85138-002
FM_ROMA<7>               R9F38            1        RES_0402-4.75K,1%,1/16W,EMPTY,A
FM_ROMA<7>               U9F4             P22      AST1250_BGA-IC,G85138-002
FM_ROMA<8>               R9F15            1        RES_0402-4.75K,1%,1/16W,CHIP,GA
FM_ROMA<8>               U9F4             M19      AST1250_BGA-IC,G85138-002
FM_ROMA<9>               R1T19            1        RES_0402-4.75K,1%,1/16W,EMPTY,A
FM_ROMA<9>               U9F4             M20      AST1250_BGA-IC,G85138-002
FM_ROMA<10>              R9F16            1        RES_0402-4.75K,1%,1/16W,CHIP,GA
FM_ROMA<10>              U9F4             M21      AST1250_BGA-IC,G85138-002
FM_ROMA<11>              R9F37            1        RES_0402-4.75K,1%,1/16W,EMPTY,A
FM_ROMA<11>              U9F4             M22      AST1250_BGA-IC,G85138-002
FM_ROMA<12>              R1T14            1        RES_0402-4.75K,1%,1/16W,CHIP,GA
FM_ROMA<12>              U9F4             L18      AST1250_BGA-IC,G85138-002
FM_ROMA<13>              R1T21            1        RES_0402-4.75K,1%,1/16W,EMPTY,A
FM_ROMA<13>              U9F4             L19      AST1250_BGA-IC,G85138-002
FM_ROMA<14>              R9F9             1        RES_0402-4.75K,1%,1/16W,CHIP,GA
FM_ROMA<14>              U9F4             L20      AST1250_BGA-IC,G85138-002
FM_ROMA<15>              R9F35            1        RES_0402-4.75K,1%,1/16W,CHIP,GA
FM_ROMA<15>              U9F4             L21      AST1250_BGA-IC,G85138-002
FM_ROMA<16>              R1T22            1        RES_0402-4.75K,1%,1/16W,EMPTY,A
FM_ROMA<16>              U9F4             T18      AST1250_BGA-IC,G85138-002
FM_ROMA<17>              R1T20            1        RES_0402-4.75K,1%,1/16W,EMPTY,A
FM_ROMA<17>              U9F4             N18      AST1250_BGA-IC,G85138-002
FM_ROMA<18>              R1T18            1        RES_0402-4.75K,1%,1/16W,EMPTY,A
FM_ROMA<18>              U9F4             N19      AST1250_BGA-IC,G85138-002
FM_ROMA<19>              R9F14            1        RES_0402-4.75K,1%,1/16W,CHIP,GA
FM_ROMA<19>              U9F4             M18      AST1250_BGA-IC,G85138-002
FM_ROMA<20>              R9F17            1        RES_0402-4.75K,1%,1/16W,EMPTY,A
FM_ROMA<20>              U9F4             N22      AST1250_BGA-IC,G85138-002
FM_ROMA<21>              R1T17            1        RES_0402-4.75K,1%,1/16W,EMPTY,A
FM_ROMA<21>              U9F4             N20      AST1250_BGA-IC,G85138-002
FM_ROMA<22>              R9F36            1        RES_0402-4.75K,1%,1/16W,EMPTY,A
FM_ROMA<22>              U9F4             L22      AST1250_BGA-IC,G85138-002
FM_ROMA<23>              R1T13            1        RES_0402-4.75K,1%,1/16W,EMPTY,A
FM_ROMA<23>              U9F4             K18      AST1250_BGA-IC,G85138-002
FM_SINT_PRSNT_N          R7C5             2        RES_0402-10.0K,1%,1/16W,CHIP,GA
FM_SINT_PRSNT_N          U7C1             C18      LBG_CORE_QAT_EXT_D_BGA1-IC,H91A
FM_SINT_PRSNT_N          U8D7             B14      LCMXO2_A_256BGA-IC,H63395-001
FM_SLPS3_N               U7C1             D14      LBG_CORE_QAT_EXT_D_BGA1-IC,H91A
FM_SLPS3_N               U8D7             G1       LCMXO2_A_256BGA-IC,H63395-001
FM_SLPS3_N               U9F4             D13      AST1250_BGA-IC,G85138-002
FM_SLPS4_N               U7C1             B16      LBG_CORE_QAT_EXT_D_BGA1-IC,H91A
FM_SLPS4_N               U8D7             C12      LCMXO2_A_256BGA-IC,H63395-001
FM_SLPS4_N               U9F4             C13      AST1250_BGA-IC,G85138-002
FM_SLP_SUS_N             U7C1             P7       LBG_CORE_QAT_EXT_D_BGA1-IC,H91A
FM_SLP_SUS_N             U8D7             E9       LCMXO2_A_256BGA-IC,H63395-001
FM_SLT_CFG0              J8G1             19       SCONN200_H68296001_SM-CONN,H68A
FM_SLT_CFG0              R8C7             2        RES_0402-4.75K,1%,1/16W,CHIP,GA
FM_SLT_CFG0              U7C1             CA32     LBG_CORE_QAT_EXT_D_BGA1-IC,H91A
FM_SLT_CFG1              J8G1             18       SCONN200_H68296001_SM-CONN,H68A
FM_SLT_CFG1              R8C1             2        RES_0402-4.75K,1%,1/16W,CHIP,GA
FM_SLT_CFG1              U7C1             BW37     LBG_CORE_QAT_EXT_D_BGA1-IC,H91A
FM_SLT_CFG2_R            R2U48            2        RES_0402-4.75K,1%,1/16W,CHIP,GA
FM_SLT_CFG2_R            R2U50            1        RES_0402-0.0,5%,1/16W,EMPTY,G2A
FM_SLT_CFG2_R            U7C1             BY31     LBG_CORE_QAT_EXT_D_BGA1-IC,H91A
FM_SOL_UART_CH_SEL       Q1L1             3        NPN_SM-MMBT3904,IC,C52245-001
FM_SOL_UART_CH_SEL       R1L5             2        RES_0402-1.00K,1%,1/16W,CHIP,GA
FM_SOL_UART_CH_SEL       U7C1             BG7      LBG_CORE_QAT_EXT_D_BGA1-IC,H91A
FM_SOL_UART_CH_SEL       U8D7             L10      LCMXO2_A_256BGA-IC,H63395-001
FM_SOL_UART_CH_SEL       U9F4             R18      AST1250_BGA-IC,G85138-002
FM_SPEAKER_PCH_N         DS9A3            1        LED_1NCLF-YELLOW,IC,C96565-003
FM_SPEAKER_PCH_N         Q9A3             3        FET_N_SOT23LF-2N7002,FET,C7925A
FM_SSATA_PCIE_M2_SEL     R2P14            2        RES_0402-0.0,5%,1/16W,CHIP,G21A
FM_SSATA_PCIE_M2_SEL     U7C1             BH4      LBG_CORE_QAT_EXT_D_BGA1-IC,H91A
FM_SYS_THROTTLE_LVC3     Q2U1             2        FET_N_DUAL_SMLF-NTJD4001N,FET,A
FM_SYS_THROTTLE_LVC3     Q2U1             5        FET_N_DUAL_SMLF-NTJD4001N,FET,A
FM_SYS_THROTTLE_LVC3     Q4B2             2        FET_N_DUAL_SMLF-NTJD4001N,FET,A
FM_SYS_THROTTLE_LVC3     Q4B2             5        FET_N_DUAL_SMLF-NTJD4001N,FET,A
FM_SYS_THROTTLE_LVC3     Q7E3             2        FET_N_DUAL_SMLF-NTJD4001N,FET,A
FM_SYS_THROTTLE_LVC3     Q7E3             5        FET_N_DUAL_SMLF-NTJD4001N,FET,A
FM_SYS_THROTTLE_LVC3     Q7E4             3        FET_N_SOT23-2N7002,FET,C79254-A
FM_SYS_THROTTLE_LVC3     Q7E8             1        FET_N_SOT23-2N7002,FET,C79254-A
FM_SYS_THROTTLE_LVC3     R7E7             2        RES_0402-4.75K,1%,1/16W,CHIP,GA
FM_THERMTRIP_DLY         R7D18            1        RES_0402-1.00K,1%,1/16W,CHIP,GA
FM_THERMTRIP_DLY         U8D7             L15      LCMXO2_A_256BGA-IC,H63395-001
FM_THERMTRIP_DLY_R       Q7D1             1        FET_N_SOT23-2N7002,FET,C79254-A
FM_THERMTRIP_DLY_R       R7D18            2        RES_0402-1.00K,1%,1/16W,CHIP,GA
FM_THROTTLE_N            R1R8             2        RES_0402-0.0,5%,1/16W,CHIP,G21A
FM_THROTTLE_N            R7E9             1        RES_0402-0.0,5%,1/16W,CHIP,G21A
FM_THROTTLE_N            R8B31            2        RES_0402-4.75K,1%,1/16W,CHIP,GA
FM_THROTTLE_N            U7C1             AY15     LBG_CORE_QAT_EXT_D_BGA1-IC,H91A
FM_THROTTLE_N            U7C1             CA39     LBG_CORE_QAT_EXT_D_BGA1-IC,H91A
FM_THROTTLE_N            U9F4             V21      AST1250_BGA-IC,G85138-002
FM_THROTTLE_R1_N         R1R8             1        RES_0402-0.0,5%,1/16W,CHIP,G21A
FM_THROTTLE_R1_N         U1R1             4        TTL1G07_A_SOP-74LVC1G07,IC,C88B
FM_THROTTLE_R_N          Q7E4             1        FET_N_SOT23-2N7002,FET,C79254-A
FM_THROTTLE_R_N          R7E9             2        RES_0402-0.0,5%,1/16W,CHIP,G21A
FM_TPM_PRES_N            J8E1             8        SCONN11_H67026001_SM-CONN,H670A
FM_TPM_PRES_N            R8E3             2        RES_0402-10.0K,1%,1/16W,CHIP,GA
FM_TPM_PRES_N            U7C1             AE4      LBG_CORE_QAT_EXT_D_BGA1-IC,H91A
FM_UARTSW_LSB_N          DS9A4            2        LED_A1LF-GREEN,IC,D14725-022
FM_UARTSW_LSB_N          U7C1             AT4      LBG_CORE_QAT_EXT_D_BGA1-IC,H91A
FM_UARTSW_LSB_N          U8D7             R9       LCMXO2_A_256BGA-IC,H63395-001
FM_UARTSW_LSB_N          U9F1             6        FSA3357_SM-IC,C63273-001
FM_UARTSW_LSB_N          U9F2             6        FSA3357_SM-IC,C63273-001
FM_UARTSW_LSB_N          U9F4             AA3      AST1250_BGA-IC,G85138-002
FM_UARTSW_LSB_R_N        DS9A4            1        LED_A1LF-GREEN,IC,D14725-022
FM_UARTSW_LSB_R_N        R1L43            1        RES_0402-330,5%,1/16W,CHIP,G21A
FM_UARTSW_MSB_N          DS9A7            2        LED_A1LF-GREEN,IC,D14725-022
FM_UARTSW_MSB_N          U7C1             BA13     LBG_CORE_QAT_EXT_D_BGA1-IC,H91A
FM_UARTSW_MSB_N          U8D7             P11      LCMXO2_A_256BGA-IC,H63395-001
FM_UARTSW_MSB_N          U9F1             5        FSA3357_SM-IC,C63273-001
FM_UARTSW_MSB_N          U9F2             5        FSA3357_SM-IC,C63273-001
FM_UARTSW_MSB_N          U9F4             AB2      AST1250_BGA-IC,G85138-002
FM_UARTSW_MSB_R_N        DS9A7            1        LED_A1LF-GREEN,IC,D14725-022
FM_UARTSW_MSB_R_N        R1L44            1        RES_0402-330,5%,1/16W,CHIP,G21A
FM_UART_ALERT_N          EU9F3            20       PI7C9X1172_QFN-IC,H66899-001
FM_UART_ALERT_N          R9F55            2        RES_0402-4.75K,1%,1/16W,CHIP,GA
FM_UART_ALERT_N          U7C1             BK13     LBG_CORE_QAT_EXT_D_BGA1-IC,H91A
FM_UART_ALERT_N          U8D7             P2       LCMXO2_A_256BGA-IC,H63395-001
FM_UART_PRES_N           J9G1             9        CONN12_C73564003_PIP-CONN,C735A
FM_UART_PRES_N           R7C13            2        RES_0402-10.0K,1%,1/16W,CHIP,GA
FM_UART_PRES_N           U7C1             T2       LBG_CORE_QAT_EXT_D_BGA1-IC,H91A
FM_UART_SEL_N            Q1L1             1        NPN_SM-MMBT3904,IC,C52245-001
FM_UART_SEL_N            R1L4             2        RES_0402-40.2K,1%,1/16W,CHIP,GA
FM_UART_SWITCH_N         J9A2             12       CONN14_H54902001_PIP-CONN,H549A
FM_UART_SWITCH_N         R1L4             1        RES_0402-40.2K,1%,1/16W,CHIP,GA
FM_UART_SWITCH_N         R1L6             1        RES_0402-0.0,5%,1/16W,CHIP,G21A
FM_UART_SWITCH_N         R9A5             2        RES_0402-20.0K,1%,1/16W,CHIP,GA
FM_USB_P0_EN_BOOT_BIOS_STRAP_N R1M25            1        RES_0402-10.0K,1%,1/16W,CHIP,GA
FM_USB_P0_EN_BOOT_BIOS_STRAP_N R2N14            2        RES_0402-1.00K,1%,1/16W,EMPTY,A
FM_USB_P0_EN_BOOT_BIOS_STRAP_N U1M3             4        TPS2061_SM-IC,H66405-001
FM_USB_P0_EN_BOOT_BIOS_STRAP_N U7C1             BR17     LBG_CORE_QAT_EXT_D_BGA1-IC,H91A
FM_UV_ADR_TRIGGER_EN     R2U30            2        RES_0402-4.75K,1%,1/16W,CHIP,GA
FM_UV_ADR_TRIGGER_EN     U7C1             BL15     LBG_CORE_QAT_EXT_D_BGA1-IC,H91A
FM_UV_ADR_TRIGGER_EN     U8D7             H12      LCMXO2_A_256BGA-IC,H63395-001
FM_UV_ADR_TRIGGER_EN     U9F4             D5       AST1250_BGA-IC,G85138-002
FM_UV_ADR_TRIGGER_N      CR9P2            1        DIODE_SMLF-BAT54WS,IC,C73510-0A
FM_UV_ADR_TRIGGER_N      R9P6             2        RES_0402-10.0K,1%,1/16W,CHIP,GA
FM_UV_ADR_TRIGGER_N      U8D7             G15      LCMXO2_A_256BGA-IC,H63395-001
FM_UV_ADR_TRIGGER_N      U9P1             6        TPS3700_SM-IC,H69492-001
FM_WBG_PRSNT_N           R7C8             2        RES_0402-10.0K,1%,1/16W,CHIP,GA
FM_WBG_PRSNT_N           U7C1             D8       LBG_CORE_QAT_EXT_D_BGA1-IC,H91A
FM_WBG_PRSNT_N           U8D7             G11      LCMXO2_A_256BGA-IC,H63395-001
FM_XRC_PRESENT_N         J1C1             G5       CONN76_H22707001_THMT1-CONN,H2A
FM_XRC_PRESENT_N         R8B23            2        RES_0402-1.00K,1%,1/16W,CHIP,GA
FM_XRC_PRESENT_N         U7C1             BW48     LBG_CORE_QAT_EXT_D_BGA1-IC,H91A
FM_XRC_PRESENT_N         U9F4             AB4      AST1250_BGA-IC,G85138-002
FM_XRC_READY_N           J1C1             H5       CONN76_H22707001_THMT1-CONN,H2A
FM_XRC_READY_N           R1C31            1        RES_0402-0.0,5%,1/16W,EMPTY,G2A
FM_XRC_READY_N           R8B30            2        RES_0402-1.00K,1%,1/16W,CHIP,GA
FM_XRC_READY_N           U7C1             CA41     LBG_CORE_QAT_EXT_D_BGA1-IC,H91A
FM_XRC_READY_N           U9F4             V7       AST1250_BGA-IC,G85138-002
FP_ID_LED_P5V_STBY_N     DS9A1            1        LED_1NC-BLUE,IC,C96565-012
FP_ID_LED_P5V_STBY_N     U1L2             4        TTL1G86_SOTLF-74AHCT1G86,IC,D3B
FP_ID_LED_XOR_R          DS9A1            2        LED_1NC-BLUE,IC,C96565-012
FP_ID_LED_XOR_R          R1L8             2        RES_0402-470.0,5%,1/16W,CHIP,GA
FP_LED_HDD_ACTIVITY_AND_N DS9A2            1        LED_1NCLF-GREEN,IC,C96565-011
FP_LED_HDD_ACTIVITY_AND_N U1M1             4        TTL1G08_SOTLF-NC7SZ08,IC,D1032C
FP_LED_HDD_ACTIVITY_AND_R_N DS9A2            2        LED_1NCLF-GREEN,IC,C96565-011
FP_LED_HDD_ACTIVITY_AND_R_N R1L21            2        RES_0402-64.9,1.0%,1/16W,CHIP,A
FP_NMI_BTN               U2R1             1        TTL2G14_SMLF-74LVC2G14,IC,D184B
FP_NMI_BTN               U2R1             4        TTL2G14_SMLF-74LVC2G14,IC,D184B
FP_NMI_BTN_N             R2R10            2        RES_0402-33.2,1%,1/16W,CHIP,G2A
FP_NMI_BTN_N             R8F24            2        RES_0402-4.75K,1%,1/16W,CHIP,GA
FP_NMI_BTN_N             U7C1             BN11     LBG_CORE_QAT_EXT_D_BGA1-IC,H91A
FP_NMI_BTN_N             U9F4             A18      AST1250_BGA-IC,G85138-002
FP_NMI_BTN_OUT_N         C2R12            1        CAP_A_0402V-1.0UF,6.3V,10%,X6SA
FP_NMI_BTN_OUT_N         R2R9             2        RES_0402-200.0,1%,1/16W,CHIP,GA
FP_NMI_BTN_OUT_N         U2R1             3        TTL2G14_SMLF-74LVC2G14,IC,D184B
FP_NMI_BTN_OUT_R_N       R2R9             1        RES_0402-200.0,1%,1/16W,CHIP,GA
FP_NMI_BTN_OUT_R_N       R8E32            2        RES_0402-4.75K,1%,1/16W,CHIP,GA
FP_NMI_BTN_OUT_R_N       S8E1             2        SWITCH_D90553001_SMLF-IC,D9055A
FP_NMI_BTN_R_N           R2R10            1        RES_0402-33.2,1%,1/16W,CHIP,G2A
FP_NMI_BTN_R_N           U2R1             6        TTL2G14_SMLF-74LVC2G14,IC,D184B
FP_PWR_BTN_BUF1_N        U9A4             3        TTL2G14_SMLF-74LVC2G14,IC,D184B
FP_PWR_BTN_BUF1_N        U9A4             6        TTL2G14_SMLF-74LVC2G14,IC,D184B
FP_PWR_BTN_R1_N          C1L18            1        CAP_A_0402V-1.0UF,6.3V,10%,X6SA
FP_PWR_BTN_R1_N          R1L31            2        RES_0402-200.0,1%,1/16W,CHIP,GA
FP_PWR_BTN_R1_N          U9A4             1        TTL2G14_SMLF-74LVC2G14,IC,D184B
FP_PWR_BTN_R_N           R1L27            2        RES_0402-4.75K,1%,1/16W,CHIP,GA
FP_PWR_BTN_R_N           R1L31            1        RES_0402-200.0,1%,1/16W,CHIP,GA
FP_PWR_BTN_R_N           S9A2             1        SW_H67881001_SM-IC,H67881-001
FP_PWR_BTN_R_N           S9A2             2        SW_H67881001_SM-IC,H67881-001
FP_PWR_ID_LED_N          R8D14            2        RES_0402-4.75K,1%,1/16W,CHIP,GA
FP_PWR_ID_LED_N          U1L2             2        TTL1G86_SOTLF-74AHCT1G86,IC,D3B
FP_PWR_ID_LED_N          U7C1             BD3      LBG_CORE_QAT_EXT_D_BGA1-IC,H91A
FP_PWR_ID_LED_N          U9F4             H3       AST1250_BGA-IC,G85138-002
FP_RST_BTN_BUF1_N        U9A3             3        TTL2G14_SMLF-74LVC2G14,IC,D184B
FP_RST_BTN_BUF1_N        U9A3             6        TTL2G14_SMLF-74LVC2G14,IC,D184B
FP_RST_BTN_R_N           C1L10            1        CAP_A_0402V-1.0UF,6.3V,10%,X6SA
FP_RST_BTN_R_N           R1L22            2        RES_0402-200.0,1%,1/16W,CHIP,GA
FP_RST_BTN_R_N           U9A3             1        TTL2G14_SMLF-74LVC2G14,IC,D184B
GND                      C1A1             2        CAP_0805LF-22UF,4V,20%,X6S,C95A
GND                      C1A2             2        CAP_A_0402V-1.0UF,6.3V,10%,X6SA
GND                      C1A4             2        CAP_0805-10UF,16V,10%,X7R,G106A
GND                      C1A5             2        CAP_A_0402V-0.01UF,25V,10%,X7RA
GND                      C1A6             2        CAP_0402-1.0UF,16V,10%,X6S,D97A
GND                      C1A9             2        CAP_0402-1.0UF,16V,10%,X6S,D97A
GND                      C1A10            2        CAP_A_0402V-0.1UF,16V,10%,X7R,A
GND                      C1A11            2        CAP_A_0402V-1.0UF,6.3V,10%,X6SA
GND                      C1A12            2        CAP_0805LF-22UF,4V,20%,X6S,C95A
GND                      C1A13            2        CAP_0402-0.22UF,16V,10%,X7R,A3A
GND                      C1A16            2        CAP_0805-10UF,16V,10%,X7R,G106A
GND                      C1A17            2        CAP_A_0402V-0.01UF,25V,10%,X7RA
GND                      C1A19            2        CAP_0402-1.0UF,16V,10%,X6S,D97A
GND                      C1A20            2        CAP_A_0402V-0.1UF,16V,10%,X7R,A
GND                      C1B2             2        CAP_A_0402V-0.1UF,16V,10%,X7R,A
GND                      C1B3             2        CAP_A_0402V-1.0UF,6.3V,10%,X6SA
GND                      C1B4             2        CAP_0402LF-1000PF,50V,10%,X7R,A
GND                      C1B5             2        CAP_A_0402V-0.1UF,16V,10%,X7R,A
GND                      C1B6             2        CAP_A_0402V-1.0UF,6.3V,10%,X6SA
GND                      C1B7             2        CAP_0805-10UF,16V,10%,X7R,G106A
GND                      C1B8             2        CAP_0402LF-1000PF,50V,10%,X7R,A
GND                      C1B9             2        CAP_A_0402V-0.01UF,25V,10%,X7RA
GND                      C1B10            2        CAPP_2626-270UF,16V,20%,OSCON,A
GND                      C1B11            2        CAP_0402LF-220PF,50V,10%,X7R,AA
GND                      C1B14            2        CAPP_4040LF-470UF,16V,20%,ALUMA
GND                      C1B15            2        CAP_A_0402V-0.01UF,25V,10%,X7RA
GND                      C1B16            2        CAP_A_0402V-0.1UF,16V,10%,EMPTA
GND                      C1B17            2        CAP_A_0402V-0.01UF,25V,10%,X7RA
GND                      C1B18            2        CAP_0805-10UF,16V,10%,X6S,C953A
GND                      C1B19            2        CAP_A_0402V-0.1UF,16V,10%,X7R,A
GND                      C1B20            2        CAP_0402-1.0UF,16V,10%,X6S,D97A
GND                      C1B21            2        CAP_0402-0.22UF,16V,10%,X7R,A3A
GND                      C1C1             2        CAPP_2626-270UF,16V,20%,OSCON,A
GND                      C1C2             2        CAPP_2626-270UF,16V,20%,OSCON,A
GND                      C1C3             2        CAP_A_0402V-1.0UF,6.3V,10%,X6SA
GND                      C1C4             2        CAP_0402-0.22UF,16V,10%,X7R,A3A
GND                      C1C5             2        CAP_0402-1.0UF,16V,10%,X6S,D97A
GND                      C1C7             2        CAP_A_0402V-1.0UF,6.3V,10%,X6SA
GND                      C1C8             2        CAP_0402LF-1000PF,50V,10%,X7R,A
GND                      C1C9             2        CAP_A_0402V-0.1UF,16V,10%,X7R,A
GND                      C1C10            2        CAP_0402LF-220PF,50V,10%,X7R,AA
GND                      C1C11            2        CAP_0402LF-220PF,50V,10%,X7R,AA
GND                      C1C13            2        CAP_A_0402V-1.0UF,6.3V,10%,X6SA
GND                      C1C14            2        CAP_A_0402V-0.1UF,16V,10%,X7R,A
GND                      C1C15            2        CAP_0402-1.0UF,16V,10%,X6S,D97A
GND                      C1C17            2        CAP_A_0402V-0.1UF,16V,10%,X7R,A
GND                      C1C18            2        CAP_A_0402V-1.0UF,6.3V,10%,X6SA
GND                      C1C19            2        CAP_A_0603V-22.0UF,4V,20%,X6S,A
GND                      C1C23            2        CAP_0402LF-1000PF,50V,10%,X7R,A
GND                      C1C25            2        CAP_A_0402V-0.1UF,16V,10%,X7R,A
GND                      C1C26            2        CAP_0402-1.0UF,16V,10%,X6S,D97A
GND                      C1D3             2        CAP_A_0603V-22.0UF,4V,20%,X6S,A
GND                      C1D5             2        CAP_A_0402V-1.0UF,6.3V,10%,X6SA
GND                      C1D6             2        CAP_0402-0.22UF,16V,10%,X7R,A3A
GND                      C1D7             2        CAP_0402-1.0UF,16V,10%,X6S,D97A
GND                      C1D12            2        CAP_0402-1.0UF,16V,10%,X6S,D97A
GND                      C1D13            2        CAP_A_0402V-0.1UF,16V,10%,X7R,A
GND                      C1D14            2        CAP_A_0603V-22.0UF,4V,20%,X6S,A
GND                      C1D15            2        CAP_A_0402V-1.0UF,6.3V,10%,X6SA
GND                      C1D16            2        CAP_0402-0.22UF,16V,10%,X7R,A3A
GND                      C1D17            2        CAP_0402-1.0UF,16V,10%,X6S,D97A
GND                      C1D23            2        CAP_0402-1.0UF,16V,10%,X6S,D97A
GND                      C1D24            2        CAP_A_0603V-22.0UF,4V,20%,X6S,A
GND                      C1D28            2        CAP_A_0402V-0.1UF,16V,10%,X7R,A
GND                      C1D32            2        CAP_0402-1.0UF,16V,10%,X6S,D97A
GND                      C1D33            2        CAP_0402-0.22UF,16V,10%,X7R,A3A
GND                      C1D34            2        CAP_A_0402V-0.1UF,16V,10%,X7R,A
GND                      C1D35            2        CAP_0402-1.0UF,16V,10%,X6S,D97A
GND                      C1E2             2        CAP_1206-0.068UF,50V,20%,X7R,1A
GND                      C1E3             2        CAP_A_0603V-22.0UF,4V,20%,X6S,A
GND                      C1E6             2        CAP_A_0402V-1.0UF,6.3V,10%,X6SA
GND                      C1E7             2        CAP_0402-0.22UF,16V,10%,X7R,A3A
GND                      C1E8             2        CAP_0402-1.0UF,16V,10%,X6S,D97A
GND                      C1E9             2        CAP_A_0603V-22.0UF,4V,20%,X6S,A
GND                      C1E12            2        CAP_0805-10UF,16V,10%,X6S,C953A
GND                      C1E13            2        CAP_0402-1.0UF,16V,10%,X6S,D97A
GND                      C1E14            2        CAP_A_0402V-0.1UF,16V,10%,X7R,A
GND                      C1E15            2        CAP_0805-10UF,16V,10%,X6S,C953A
GND                      C1E16            2        CAP_A_0402V-0.1UF,16V,10%,X7R,A
GND                      C1E17            2        CAP_A_0402V-0.1UF,16V,10%,X7R,A
GND                      C1E18            2        CAPP_2626-270UF,16V,20%,OSCON,A
GND                      C1E20            2        CAP_A_0402V-0.1UF,16V,10%,X7R,A
GND                      C1E21            2        CAP_0805-10UF,16V,10%,X6S,C953A
GND                      C1E22            2        CAP_A_0402V-0.1UF,16V,10%,X7R,A
GND                      C1E23            2        CAP_A_0402V-1.0UF,6.3V,10%,X6SA
GND                      C1E24            2        CAP_0402-1.0UF,16V,10%,X6S,D97A
GND                      C1E25            2        CAP_0402-0.22UF,16V,10%,X7R,A3A
GND                      C1F7             2        CAPP_4040LF-470UF,16V,20%,ALUMA
GND                      C1F9             2        CAP_A_0402V-0.01UF,25V,10%,X7RA
GND                      C1F19            2        CAP_A_0402V-0.01UF,25V,10%,X7RA
GND                      C1F21            2        CAP_A_0402V-1.0UF,6.3V,10%,X6SA
GND                      C1F22            2        CAP_A_0402V-0.01UF,25V,10%,X7RA
GND                      C1F27            2        CAP_0402-1.0UF,16V,10%,X6S,D97A
GND                      C1F28            2        CAP_A_0402V-0.1UF,16V,10%,X7R,A
GND                      C1G2             2        CAP_1210-47UF,16V,20%,X6S,D384A
GND                      C1G4             2        CAP_A_0402V-1.0UF,6.3V,10%,X6SA
GND                      C1G5             2        CAP_0402-0.22UF,16V,10%,X7R,A3A
GND                      C1G6             2        CAP_0402-1.0UF,16V,10%,X6S,D97A
GND                      C1G7             2        CAP_1210-47UF,16V,20%,X6S,D384A
GND                      C1G8             2        CAP_A_0402V-0.01UF,25V,10%,X7RA
GND                      C1G10            2        CAP_A_0402V-0.01UF,25V,10%,X7RA
GND                      C1G12            2        CAP_1210-47UF,16V,20%,X6S,D384A
GND                      C1G13            2        CAP_0402-1.0UF,16V,10%,X6S,D97A
GND                      C1G14            2        CAP_A_0402V-0.1UF,16V,10%,X7R,A
GND                      C1G15            2        CAP_1210-47UF,16V,20%,X6S,D384A
GND                      C1G17            2        CAP_0805LF-22UF,4V,20%,X6S,C95A
GND                      C1G18            2        CAP_A_0402V-0.01UF,25V,10%,X7RA
GND                      C1G19            2        CAP_A_0402V-0.01UF,25V,10%,X7RA
GND                      C1G20            2        CAP_0805LF-22UF,4V,20%,X6S,C95A
GND                      C1G21            2        CAP_0402LF-1000PF,50V,10%,X7R,A
GND                      C1G22            2        CAP_A_0402V-0.1UF,16V,10%,X7R,A
GND                      C1G23            2        CAP_A_0402V-1.0UF,6.3V,10%,X6SA
GND                      C1G24            2        CAP_0402LF-220PF,50V,10%,X7R,AA
GND                      C1G25            2        CAP_A_0402V-0.1UF,16V,10%,X7R,A
GND                      C1G26            2        CAP_0402LF-1000PF,50V,10%,X7R,A
GND                      C1G27            2        CAP_A_0402V-1.0UF,6.3V,10%,X6SA
GND                      C1G28            2        CAP_0402-1.0UF,16V,10%,X6S,D97A
GND                      C1G29            2        CAP_0402-0.22UF,16V,10%,X7R,A3A
GND                      C1L1             2        CAP_0402-1.0UF,16V,10%,X6S,D97A
GND                      C1L4             2        CAP_A_0402V-0.1UF,16V,10%,X7R,A
GND                      C1L5             2        CAP_A_0402V-1.0UF,6.3V,10%,X6SA
GND                      C1L8             2        CAP_A_0402V-0.1UF,16V,10%,X7R,A
GND                      C1L9             2        CAP_A_0402V-0.1UF,16V,10%,X7R,A
GND                      C1L10            2        CAP_A_0402V-1.0UF,6.3V,10%,X6SA
GND                      C1L11            2        CAP_A_0402V-0.1UF,16V,10%,X7R,A
GND                      C1L16            2        CAP_A_0402V-0.1UF,16V,10%,X7R,A
GND                      C1L17            2        CAP_A_0402V-0.1UF,16V,10%,X7R,A
GND                      C1L18            2        CAP_A_0402V-1.0UF,6.3V,10%,X6SA
GND                      C1L19            2        CAP_0402-1.0UF,16V,10%,X6S,D97A
GND                      C1L20            2        CAP_A_0402V-0.01UF,25V,10%,X7RA
GND                      C1M3             2        CAP_A_0402V-1.0UF,6.3V,10%,X6SA
GND                      C1M5             2        CAPP_3018-68UF,16V,20%,TANT,72A
GND                      C1M20            2        CAP_A_0402V-0.1UF,16V,10%,X7R,A
GND                      C1M21            2        CAP_A_0402V-1.0UF,6.3V,10%,X6SA
GND                      C1M22            2        CAP_A_0402V-0.1UF,16V,10%,X7R,A
GND                      C1M23            2        CAP_A_0402V-0.1UF,16V,10%,X7R,A
GND                      C1M24            2        CAP_A_0402V-0.1UF,16V,10%,X7R,A
GND                      C1M25            2        CAP_A_0402V-1.0UF,6.3V,10%,X6SA
GND                      C1M26            2        CAP_0805-10UF,16V,10%,X6S,C953A
GND                      C1M27            2        CAP_0805-10UF,16V,10%,X6S,C953A
GND                      C1M28            2        CAP_A_0402V-0.01UF,25V,10%,X7RA
GND                      C1M29            2        CAP_A_0402V-0.1UF,16V,10%,X7R,A
GND                      C1M30            2        CAP_A_0402V-0.01UF,25V,10%,X7RA
GND                      C1M31            2        CAP_A_0402V-0.01UF,25V,10%,X7RA
GND                      C1M32            2        CAP_A_0402V-1.0UF,6.3V,10%,X6SA
GND                      C1M33            2        CAP_A_0402V-0.1UF,16V,10%,X7R,A
GND                      C1M34            2        CAP_A_0402V-0.01UF,25V,10%,X7RA
GND                      C1M35            2        CAP_A_0402V-0.01UF,25V,10%,X7RA
GND                      C1M36            2        CAP_A_0402V-0.01UF,25V,10%,X7RA
GND                      C1M37            2        CAP_A_0402V-1.0UF,6.3V,10%,X6SA
GND                      C1M38            2        CAP_A_0402V-0.1UF,16V,10%,X7R,A
GND                      C1R13            2        CAP_0603-10UF,6.3V,20%,X6S,E15A
GND                      C1R14            2        CAP_A_0402V-0.1UF,16V,10%,X7R,A
GND                      C1R15            2        CAP_A_0402V-0.1UF,16V,10%,X7R,A
GND                      C1R16            2        CAP_0603-10UF,6.3V,20%,X6S,E15A
GND                      C1R17            2        CAP_0603-10UF,6.3V,20%,X6S,E15A
GND                      C1R18            2        CAP_A_0402V-0.1UF,16V,10%,X7R,A
GND                      C1R19            2        CAP_A_0402V-0.1UF,16V,10%,X7R,A
GND                      C1R20            2        CAP_A_0402V-0.1UF,16V,10%,X7R,A
GND                      C1R21            2        CAP_A_0402V-0.1UF,16V,10%,X7R,A
GND                      C1R22            2        CAP_0603-10UF,6.3V,20%,X6S,E15A
GND                      C1R23            2        CAPP_3018-68UF,16V,20%,TANT,72A
GND                      C1R24            2        CAP_A_0402V-0.1UF,16V,10%,X7R,A
GND                      C1R25            2        CAP_A_0402V-0.1UF,16V,10%,X7R,A
GND                      C1R26            2        CAP_A_0402V-0.1UF,16V,10%,X7R,A
GND                      C1R27            2        CAP_A_0402V-0.1UF,16V,10%,X7R,A
GND                      C1R28            2        CAP_A_0402V-0.1UF,16V,10%,X7R,A
GND                      C1R29            2        CAP_A_0402V-0.1UF,16V,10%,X7R,A
GND                      C1R30            2        CAP_0603-10UF,6.3V,20%,X6S,E15A
GND                      C1R31            2        CAP_A_0402V-0.1UF,16V,10%,X7R,A
GND                      C1T3             2        CAP_A_0402V-0.1UF,16V,10%,X7R,A
GND                      C1T4             2        CAP_0603-10UF,6.3V,20%,X6S,E15A
GND                      C1T5             2        CAP_A_0402V-0.1UF,16V,10%,X7R,A
GND                      C1T7             2        CAP_0603-10UF,6.3V,20%,X6S,E15A
GND                      C1T8             2        CAP_A_0402V-0.1UF,16V,10%,X7R,A
GND                      C1T9             2        CAP_0805-22UF,6.3V,20%,X6S,C95A
GND                      C1T10            2        CAP_A_0402V-0.1UF,16V,10%,X7R,A
GND                      C1T11            2        CAP_A_0402V-0.1UF,16V,10%,X7R,A
GND                      C1T12            2        CAP_A_0402V-1.0UF,6.3V,10%,X6SA
GND                      C1T13            2        CAP_0805-22UF,6.3V,20%,X6S,C95A
GND                      C1T14            2        CAP_A_0402V-0.1UF,16V,10%,X7R,A
GND                      C1T15            2        CAP_0603-10UF,6.3V,20%,X6S,E15A
GND                      C1T16            2        CAP_0603-10UF,6.3V,20%,EMPTY,EA
GND                      C1T17            2        CAP_A_0402V-0.1UF,16V,10%,EMPTA
GND                      C1T18            2        CAP_A_0402V-1.0UF,6.3V,10%,EMPA
GND                      C1T19            2        CAP_A_0402V-1.0UF,6.3V,10%,X6SA
GND                      C1T20            2        CAP_0402LF-100.0PF,50V,5%,COG,A
GND                      C1T21            2        CAP_A_0402V-1.0UF,6.3V,10%,X6SA
GND                      C1T22            2        CAP_A_0402V-0.1UF,16V,10%,X7R,A
GND                      C1T23            2        CAP_A_0402V-0.1UF,16V,10%,X7R,A
GND                      C1T24            2        CAP_A_0402V-0.01UF,25V,10%,X7RA
GND                      C1T25            2        CAP_A_0402V-0.1UF,16V,10%,X7R,A
GND                      C1T26            2        CAP_A_0402V-0.1UF,16V,10%,X7R,A
GND                      C1T27            2        CAP_A_0402V-0.01UF,25V,10%,X7RA
GND                      C1T28            2        CAP_A_0402V-1.0UF,6.3V,10%,X6SA
GND                      C1T29            2        CAP_A_0402V-0.1UF,16V,10%,X7R,A
GND                      C1T30            2        CAP_A_0402V-0.1UF,16V,10%,X7R,A
GND                      C1T31            2        CAP_A_0402V-1.0UF,6.3V,10%,X6SA
GND                      C1T32            2        CAP_A_0402V-1.0UF,6.3V,10%,X6SA
GND                      C1T33            2        CAP_A_0402V-0.1UF,16V,10%,X7R,A
GND                      C1T34            2        CAP_A_0402V-0.01UF,25V,10%,X7RA
GND                      C1T35            2        CAP_A_0402V-1.0UF,6.3V,10%,X6SA
GND                      C1T36            2        CAP_A_0402V-0.01UF,25V,10%,X7RA
GND                      C1T37            2        CAP_A_0402V-0.1UF,16V,10%,X7R,A
GND                      C1T38            2        CAP_A_0402V-0.1UF,16V,10%,X7R,A
GND                      C1T40            2        CAP_A_0402V-0.1UF,16V,10%,X7R,A
GND                      C1T41            2        CAP_A_0402V-0.01UF,25V,10%,X7RA
GND                      C1T42            2        CAP_0603-0.47UF,16V,10%,X7R,20A
GND                      C1T43            2        CAP_A_0402V-0.1UF,16V,10%,X7R,A
GND                      C1T44            2        CAP_0603-4.7UF,6.3V,10%,X6S,E1A
GND                      C1T45            2        CAP_A_0402V-0.1UF,16V,10%,X7R,A
GND                      C1T46            2        CAP_A_0402V-1.0UF,6.3V,10%,X6SA
GND                      C1T47            2        CAP_A_0402V-0.1UF,16V,10%,X7R,A
GND                      C1T48            2        CAP_A_0402V-0.1UF,16V,10%,X7R,A
GND                      C1T49            2        CAP_A_0402V-1.0UF,6.3V,10%,X6SA
GND                      C1T50            2        CAP_A_0402V-0.1UF,16V,10%,X7R,A
GND                      C1T51            2        CAP_A_0402V-1.0UF,6.3V,10%,X6SA
GND                      C1T52            2        CAP_A_0402V-0.1UF,16V,10%,X7R,A
GND                      C1T53            2        CAP_A_0402V-0.1UF,16V,10%,X7R,A
GND                      C1T54            2        CAP_A_0402V-0.1UF,16V,10%,X7R,A
GND                      C1T55            2        CAP_A_0402V-1.0UF,6.3V,10%,X6SA
GND                      C1T56            2        CAP_A_0402V-0.1UF,16V,10%,X7R,A
GND                      C1U1             2        CAP_0805-10UF,16V,10%,X6S,C953A
GND                      C1U2             2        CAP_0402LF-100.0PF,50V,5%,COG,A
GND                      C1U3             2        CAP_A_0402V-0.1UF,16V,10%,X7R,A
GND                      C1U4             2        CAP_A_0402V-0.1UF,16V,10%,X7R,A
GND                      C1U5             2        CAP_A_0402V-0.1UF,16V,10%,X7R,A
GND                      C1U6             2        CAP_A_0402V-1.0UF,6.3V,10%,X6SA
GND                      C1U7             2        CAP_A_0402V-1.0UF,6.3V,10%,X6SA
GND                      C1U8             2        CAP_A_0402V-1.0UF,6.3V,10%,X6SA
GND                      C1U9             2        CAP_A_0402V-0.1UF,16V,10%,X7R,A
GND                      C1U10            2        CAP_A_0402V-0.1UF,16V,10%,X7R,A
GND                      C1U11            2        CAP_A_0402V-0.1UF,16V,10%,X7R,A
GND                      C1U12            2        CAP_0805-10UF,16V,10%,X6S,C953A
GND                      C1U13            2        CAP_A_0402V-0.1UF,16V,10%,X7R,A
GND                      C1U14            2        CAP_A_0402V-0.1UF,16V,10%,X7R,A
GND                      C1U15            2        CAP_A_0402V-0.1UF,16V,10%,X7R,A
GND                      C1U16            2        CAP_A_0402V-0.1UF,16V,10%,X7R,A
GND                      C1U17            2        CAP_0402LF-100.0PF,50V,5%,COG,A
GND                      C1U18            2        CAP_A_0402V-1.0UF,6.3V,10%,X6SA
GND                      C1U19            2        CAP_0402-1.0UF,16V,10%,X6S,D97A
GND                      C1U20            2        CAP_0805-10UF,16V,10%,X7R,G106A
GND                      C1U21            2        CAP_0402LF-47.0PF,50V,5%,COG,AA
GND                      C1U22            2        CAP_A_0402V-0.1UF,16V,10%,X7R,A
GND                      C2A1             2        CAP_A_0603V-22.0UF,4V,20%,X6S,A
GND                      C2A2             2        CAP_A_0603V-22.0UF,4V,20%,X6S,A
GND                      C2A3             2        CAP_A_0603V-22.0UF,4V,20%,X6S,A
GND                      C2A4             2        CAP_A_0603V-22.0UF,4V,20%,X6S,A
GND                      C2A5             2        CAP_A_0603V-47UF,4V,20%,X5R,60A
GND                      C2A6             2        CAP_A_0603V-22.0UF,4V,20%,X6S,A
GND                      C2A7             2        CAP_A_0603V-22.0UF,4V,20%,X6S,A
GND                      C2A8             2        CAP_0805-100UF,4V,20%,X5R,6024A
GND                      C2A9             2        CAP_A_0603V-22.0UF,4V,20%,X6S,A
GND                      C2A10            2        CAP_A_0603V-22.0UF,4V,20%,X6S,A
GND                      C2A11            2        CAP_A_0603V-22.0UF,4V,20%,X6S,A
GND                      C2A12            2        CAP_A_0603V-22.0UF,4V,20%,X6S,A
GND                      C2A13            2        CAP_A_0603V-22.0UF,4V,20%,X6S,A
GND                      C2A14            2        CAP_A_0603V-22.0UF,4V,20%,X6S,A
GND                      C2A15            2        CAP_A_0603V-22.0UF,4V,20%,X6S,A
GND                      C2A16            2        CAP_0805-100UF,4V,20%,X5R,6024A
GND                      C2B1             2        CAP_A_0603V-47UF,4V,20%,X5R,60A
GND                      C2B2             2        CAP_A_0603V-47UF,4V,20%,X5R,60A
GND                      C2D1             2        CAP_A_0603V-22.0UF,4V,20%,X6S,A
GND                      C2D2             2        CAP_A_0603V-22.0UF,4V,20%,X6S,A
GND                      C2D3             2        CAP_A_0603V-22.0UF,4V,20%,X6S,A
GND                      C2D4             2        CAP_0603LF-10UF,4V,20%,X6S,E15A
GND                      C2D5             2        CAP_0603LF-10UF,4V,20%,X6S,E15A
GND                      C2D6             2        CAP_0603LF-10UF,4V,20%,X6S,E15A
GND                      C2D7             2        CAP_0603LF-10UF,4V,20%,X6S,E15A
GND                      C2D8             2        CAP_0603LF-10UF,4V,20%,X6S,E15A
GND                      C2D9             2        CAP_0603LF-10UF,4V,20%,X6S,E15A
GND                      C2D10            2        CAP_0603LF-10UF,4V,20%,X6S,E15A
GND                      C2D11            2        CAP_0603LF-10UF,4V,20%,X6S,E15A
GND                      C2D12            2        CAP_A_0603V-22.0UF,4V,20%,X6S,A
GND                      C2D13            2        CAP_A_0603V-22.0UF,4V,20%,X6S,A
GND                      C2D14            2        CAP_A_0603V-22.0UF,4V,20%,X6S,A
GND                      C2D15            2        CAP_A_0603V-22.0UF,4V,20%,X6S,A
GND                      C2D16            2        CAP_A_0603V-22.0UF,4V,20%,X6S,A
GND                      C2D17            2        CAP_A_0603V-22.0UF,4V,20%,X6S,A
GND                      C2D18            2        CAP_A_0603V-22.0UF,4V,20%,X6S,A
GND                      C2D19            2        CAP_A_0603V-22.0UF,4V,20%,X6S,A
GND                      C2D20            2        CAP_A_0603V-22.0UF,4V,20%,X6S,A
GND                      C2D21            2        CAP_A_0603V-22.0UF,4V,20%,X6S,A
GND                      C2D22            2        CAP_A_0603V-22.0UF,4V,20%,X6S,A
GND                      C2D23            2        CAP_A_0603V-22.0UF,4V,20%,X6S,A
GND                      C2D24            2        CAP_A_0603V-22.0UF,4V,20%,X6S,A
GND                      C2D25            2        CAP_A_0603V-22.0UF,4V,20%,X6S,A
GND                      C2D26            2        CAP_A_0603V-22.0UF,4V,20%,X6S,A
GND                      C2D27            2        CAP_A_0603V-22.0UF,4V,20%,X6S,A
GND                      C2D28            2        CAP_A_0603V-22.0UF,4V,20%,X6S,A
GND                      C2D29            2        CAP_A_0603V-22.0UF,4V,20%,X6S,A
GND                      C2D30            2        CAP_A_0603V-22.0UF,4V,20%,X6S,A
GND                      C2D31            2        CAP_A_0603V-22.0UF,4V,20%,X6S,A
GND                      C2D32            2        CAP_A_0603V-22.0UF,4V,20%,X6S,A
GND                      C2D33            2        CAP_A_0603V-22.0UF,4V,20%,X6S,A
GND                      C2D34            2        CAP_A_0603V-22.0UF,4V,20%,X6S,A
GND                      C2D35            2        CAP_A_0603V-22.0UF,4V,20%,X6S,A
GND                      C2D36            2        CAP_A_0603V-22.0UF,4V,20%,X6S,A
GND                      C2D37            2        CAP_A_0603V-22.0UF,4V,20%,X6S,A
GND                      C2D38            2        CAP_A_0603V-22.0UF,4V,20%,X6S,A
GND                      C2D39            2        CAP_A_0603V-22.0UF,4V,20%,X6S,A
GND                      C2D40            2        CAP_A_0603V-22.0UF,4V,20%,X6S,A
GND                      C2D41            2        CAP_0603LF-10UF,4V,20%,X6S,E15A
GND                      C2D42            2        CAP_0603LF-10UF,4V,20%,X6S,E15A
GND                      C2D43            2        CAP_0603LF-10UF,4V,20%,X6S,E15A
GND                      C2D44            2        CAP_0603LF-10UF,4V,20%,X6S,E15A
GND                      C2D45            2        CAP_A_0603V-22.0UF,4V,20%,X6S,A
GND                      C2D46            2        CAP_A_0603V-22.0UF,4V,20%,X6S,A
GND                      C2D47            2        CAP_A_0603V-22.0UF,4V,20%,X6S,A
GND                      C2F1             2        CAP_A_0603V-47UF,4V,20%,X5R,60A
GND                      C2F2             2        CAP_A_0603V-47UF,4V,20%,X5R,60A
GND                      C2G1             2        CAP_A_0603V-22.0UF,4V,20%,X6S,A
GND                      C2G2             2        CAP_A_0603V-22.0UF,4V,20%,X6S,A
GND                      C2G3             2        CAP_A_0603V-22.0UF,4V,20%,X6S,A
GND                      C2G4             2        CAP_A_0603V-22.0UF,4V,20%,X6S,A
GND                      C2G5             2        CAP_A_0603V-22.0UF,4V,20%,X6S,A
GND                      C2G6             2        CAP_A_0603V-22.0UF,4V,20%,X6S,A
GND                      C2G7             2        CAP_0805-100UF,4V,20%,X5R,6024A
GND                      C2G8             2        CAP_A_0603V-47UF,4V,20%,X5R,60A
GND                      C2G9             2        CAP_A_0603V-22.0UF,4V,20%,X6S,A
GND                      C2G10            2        CAP_A_0603V-22.0UF,4V,20%,X6S,A
GND                      C2G11            2        CAP_A_0603V-22.0UF,4V,20%,X6S,A
GND                      C2G12            2        CAP_A_0603V-22.0UF,4V,20%,X6S,A
GND                      C2G13            2        CAP_A_0603V-22.0UF,4V,20%,X6S,A
GND                      C2G14            2        CAP_A_0603V-22.0UF,4V,20%,X6S,A
GND                      C2G15            2        CAP_A_0603V-47UF,4V,20%,X5R,60A
GND                      C2G16            2        CAP_0805-100UF,4V,20%,X5R,6024A
GND                      C2L8             2        CAP_A_0402V-1.0UF,6.3V,10%,X6SA
GND                      C2L11            2        CAP_A_0402V-0.1UF,16V,10%,X7R,A
GND                      C2L25            2        CAPP_SM-470UF,2V,20%,ALUM,6990A
GND                      C2L32            2        CAP_0805-47UF,4V,20%,X6S,C9533A
GND                      C2L45            2        CAP_0805-22UF,6.3V,20%,X6S,C95A
GND                      C2L46            2        CAPP_SM-470UF,2V,20%,ALUM,6990A
GND                      C2M1             2        CAP_A_0603V-22.0UF,4V,20%,X6S,A
GND                      C2M2             2        CAP_A_0603V-22.0UF,4V,20%,X6S,A
GND                      C2M5             2        CAP_0603LF-10UF,4V,20%,X6S,E15A
GND                      C2M6             2        CAP_A_0402V-1.0UF,6.3V,10%,X6SA
GND                      C2M7             2        CAP_A_0402V-1.0UF,6.3V,10%,X6SA
GND                      C2M8             2        CAP_A_0402V-1.0UF,6.3V,10%,X6SA
GND                      C2M9             2        CAP_A_0402V-1.0UF,6.3V,10%,X6SA
GND                      C2M10            2        CAP_0603LF-10UF,4V,20%,X6S,E15A
GND                      C2M11            2        CAP_0805-47UF,4V,20%,X6S,C9533A
GND                      C2M12            2        CAP_A_0603V-22.0UF,4V,20%,X6S,A
GND                      C2M13            2        CAP_A_0603V-22.0UF,4V,20%,X6S,A
GND                      C2M16            2        CAP_A_0402V-1.0UF,6.3V,10%,X6SA
GND                      C2M17            2        CAP_0805-47UF,4V,20%,X6S,C9533A
GND                      C2M18            2        CAP_A_0402V-1.0UF,6.3V,10%,X6SA
GND                      C2M19            2        CAP_A_0402V-1.0UF,6.3V,10%,X6SA
GND                      C2M20            2        CAP_A_0402V-1.0UF,6.3V,10%,X6SA
GND                      C2M21            2        CAP_A_0402V-1.0UF,6.3V,10%,X6SA
GND                      C2M22            2        CAP_A_0402V-1.0UF,6.3V,10%,X6SA
GND                      C2M25            2        CAP_A_0402V-1.0UF,6.3V,10%,X6SA
GND                      C2N2             2        CAP_A_0402V-1.0UF,6.3V,10%,X6SA
GND                      C2N3             2        CAP_A_0402V-1.0UF,6.3V,10%,X6SA
GND                      C2N4             2        CAP_A_0402V-1.0UF,6.3V,10%,X6SA
GND                      C2N5             2        CAP_A_0402V-1.0UF,6.3V,10%,X6SA
GND                      C2N6             2        CAP_0603LF-10UF,4V,20%,X6S,E15A
GND                      C2N7             2        CAP_A_0402V-1.0UF,6.3V,10%,X6SA
GND                      C2N8             2        CAP_A_0402V-1.0UF,6.3V,10%,X6SA
GND                      C2N9             2        CAP_A_0402V-1.0UF,6.3V,10%,X6SA
GND                      C2N10            2        CAP_A_0603V-22.0UF,4V,20%,X6S,A
GND                      C2N11            2        CAP_A_0402V-1.0UF,6.3V,10%,X6SA
GND                      C2N12            2        CAP_A_0402V-1.0UF,6.3V,10%,X6SA
GND                      C2N13            2        CAP_A_0402V-1.0UF,6.3V,10%,X6SA
GND                      C2N14            2        CAP_0603-10UF,6.3V,20%,X6S,E15A
GND                      C2N15            2        CAP_A_0402V-1.0UF,6.3V,10%,X6SA
GND                      C2N16            2        CAP_A_0402V-1.0UF,6.3V,10%,X6SA
GND                      C2N17            2        CAP_0603-10UF,6.3V,20%,X6S,E15A
GND                      C2N18            2        CAP_A_0402V-1.0UF,6.3V,10%,X6SA
GND                      C2N19            2        CAP_A_0402V-1.0UF,6.3V,10%,X6SA
GND                      C2N20            2        CAP_A_0402V-1.0UF,6.3V,10%,X6SA
GND                      C2N21            2        CAP_0603-10UF,6.3V,20%,X6S,E15A
GND                      C2N22            2        CAP_0603-10UF,6.3V,20%,X6S,E15A
GND                      C2N23            2        CAP_0603-10UF,6.3V,20%,X6S,E15A
GND                      C2N24            2        CAP_0603-10UF,6.3V,20%,X6S,E15A
GND                      C2N25            2        CAP_A_0402V-1.0UF,6.3V,10%,X6SA
GND                      C2N26            2        CAP_A_0402V-1.0UF,6.3V,10%,X6SA
GND                      C2P1             2        CAP_A_0402V-0.1UF,16V,10%,X7R,A
GND                      C2P2             2        CAP_A_0402V-0.1UF,16V,10%,X7R,A
GND                      C2P3             2        CAP_A_0402V-0.1UF,16V,10%,X7R,A
GND                      C2P4             2        CAP_A_0402V-0.1UF,16V,10%,X7R,A
GND                      C2P5             2        CAP_A_0402V-0.1UF,16V,10%,X7R,A
GND                      C2P6             2        CAP_A_0402V-0.1UF,16V,10%,X7R,A
GND                      C2P7             2        CAP_A_0402V-0.1UF,16V,10%,X7R,A
GND                      C2P8             2        CAP_A_0402V-0.01UF,25V,10%,X7RA
GND                      C2P9             2        CAP_A_0402V-0.1UF,16V,10%,X7R,A
GND                      C2P10            2        CAP_1206LF-22UF,16V,10%,X6S,D3A
GND                      C2P11            2        CAP_A_0402V-0.1UF,16V,10%,X7R,A
GND                      C2P12            2        CAP_A_0402V-0.1UF,16V,10%,X7R,A
GND                      C2P13            2        CAP_A_0402V-0.1UF,16V,10%,X7R,A
GND                      C2P14            2        CAP_A_0402V-0.1UF,16V,10%,X7R,A
GND                      C2P15            2        CAP_A_0402V-0.1UF,16V,10%,X7R,A
GND                      C2P16            2        CAP_A_0402V-0.1UF,16V,10%,X7R,A
GND                      C2R1             2        CAP_A_0402V-0.1UF,16V,10%,X7R,A
GND                      C2R2             2        CAP_A_0402V-0.1UF,16V,10%,X7R,A
GND                      C2R3             2        CAP_A_0402V-0.1UF,16V,10%,X7R,A
GND                      C2R4             2        CAP_A_0402V-0.1UF,16V,10%,X7R,A
GND                      C2R5             2        CAP_A_0402V-0.1UF,16V,10%,X7R,A
GND                      C2R6             2        CAP_0402LF-470PF,50V,10%,EMPTYA
GND                      C2R12            2        CAP_A_0402V-1.0UF,6.3V,10%,X6SA
GND                      C2R15            2        CAP_A_0402V-0.1UF,16V,10%,X7R,A
GND                      C2R16            2        CAP_A_0402V-0.1UF,16V,10%,X7R,A
GND                      C2R17            2        CAP_A_0402V-0.1UF,16V,10%,X7R,A
GND                      C2R18            2        CAP_A_0402V-0.1UF,16V,10%,X7R,A
GND                      C2T1             2        CAP_A_0402V-0.1UF,16V,10%,X7R,A
GND                      C2T2             2        CAP_A_0402V-0.1UF,16V,10%,X7R,A
GND                      C2T3             2        CAP_A_0402V-0.1UF,16V,10%,X7R,A
GND                      C2T4             2        CAP_A_0402V-0.1UF,16V,10%,X7R,A
GND                      C2T5             2        CAP_A_0402V-0.1UF,16V,10%,X7R,A
GND                      C2T6             2        CAP_0805-22UF,6.3V,20%,X6S,C95A
GND                      C2T7             2        CAP_0805-22UF,6.3V,20%,X6S,C95A
GND                      C2T8             2        CAP_A_0402V-0.1UF,16V,10%,X7R,A
GND                      C2T9             2        CAP_0805-22UF,6.3V,20%,X6S,C95A
GND                      C2T12            2        CAP_A_0402V-0.1UF,16V,10%,X7R,A
GND                      C2T15            2        CAP_A_0402V-0.1UF,16V,10%,X7R,A
GND                      C2T16            2        CAP_A_0402V-0.1UF,16V,10%,X7R,A
GND                      C2T17            2        CAP_A_0402V-0.1UF,16V,10%,X7R,A
GND                      C2T18            2        CAP_A_0402V-0.01UF,25V,10%,X7RA
GND                      C2T19            2        CAP_A_0402V-1.0UF,6.3V,10%,X6SA
GND                      C2T21            2        CAP_A_0402V-0.1UF,16V,10%,X7R,A
GND                      C2T22            2        CAP_0805-10UF,16V,10%,X6S,C953A
GND                      C2T24            2        CAP_A_0402V-0.1UF,16V,10%,X7R,A
GND                      C2T25            2        CAP_A_0402V-0.1UF,16V,10%,X7R,A
GND                      C2T26            2        CAP_A_0402V-0.1UF,16V,10%,X7R,A
GND                      C2T27            2        CAP_A_0402V-0.01UF,25V,10%,X7RA
GND                      C2T28            2        CAP_A_0402V-1.0UF,6.3V,10%,X6SA
GND                      C2T29            2        CAP_A_0402V-0.1UF,16V,10%,X7R,A
GND                      C2T30            2        CAP_A_0402V-0.1UF,16V,10%,X7R,A
GND                      C2T31            2        CAP_A_0402V-1.0UF,6.3V,10%,X6SA
GND                      C2T32            2        CAP_A_0402V-0.1UF,16V,10%,X7R,A
GND                      C2T33            2        CAP_A_0402V-1.0UF,6.3V,10%,X6SA
GND                      C2T34            2        CAP_A_0402V-0.1UF,16V,10%,X7R,A
GND                      C2T35            2        CAP_A_0402V-0.1UF,16V,10%,X7R,A
GND                      C2T36            2        CAP_A_0402V-0.1UF,16V,10%,X7R,A
GND                      C2T37            2        CAP_A_0402V-0.01UF,25V,10%,X7RA
GND                      C2T38            2        CAP_A_0402V-1.0UF,6.3V,10%,X6SA
GND                      C2U1             2        CAP_0805-10UF,16V,10%,X6S,C953A
GND                      C2U2             2        CAP_0805-10UF,16V,10%,X6S,C953A
GND                      C2U19            2        CAP_A_0402V-0.1UF,16V,10%,X7R,A
GND                      C2U20            2        CAP_A_0402V-0.1UF,16V,10%,X7R,A
GND                      C2U21            2        CAP_A_0402V-0.1UF,16V,10%,X7R,A
GND                      C2U22            2        CAP_A_0402V-0.1UF,16V,10%,X7R,A
GND                      C2U23            2        CAP_A_0402V-0.1UF,16V,10%,X7R,A
GND                      C2U24            2        CAP_A_0402V-0.1UF,16V,10%,X7R,A
GND                      C2U25            2        CAP_A_0402V-0.1UF,16V,10%,X7R,A
GND                      C2U26            2        CAP_A_0402V-1.0UF,6.3V,10%,X6SA
GND                      C2U27            2        CAP_A_0402V-0.1UF,16V,10%,X7R,A
GND                      C2U28            2        CAP_A_0402V-0.1UF,16V,10%,X7R,A
GND                      C3A1             2        CAP_A_0603V-22.0UF,4V,20%,X6S,A
GND                      C3A2             2        CAP_A_0603V-22.0UF,4V,20%,X6S,A
GND                      C3A3             2        CAP_0603LF-10UF,4V,20%,X6S,E15A
GND                      C3A4             2        CAP_0603LF-10UF,4V,20%,X6S,E15A
GND                      C3A5             2        CAP_A_0603V-22.0UF,4V,20%,X6S,A
GND                      C3A6             2        CAP_A_0603V-22.0UF,4V,20%,X6S,A
GND                      C3A7             2        CAP_0603LF-10UF,4V,20%,X6S,E15A
GND                      C3A8             2        CAP_0603LF-10UF,4V,20%,X6S,E15A
GND                      C3B1             2        CAP_0603LF-10UF,4V,20%,X6S,E15A
GND                      C3B2             2        CAP_0603LF-10UF,4V,20%,X6S,E15A
GND                      C3B3             2        CAPP_7343LF-330UF,6.3V,20%,POSA
GND                      C3B4             2        CAP_A_0402V-0.1UF,16V,10%,X7R,A
GND                      C3B5             2        CAP_A_0402V-0.1UF,16V,10%,X7R,A
GND                      C3B6             2        CAPP_3018-68UF,16V,20%,TANT,72A
GND                      C3C1             2        CAP_A_0402V-1.0UF,6.3V,10%,X6SA
GND                      C3C2             2        CAP_A_0402V-1.0UF,6.3V,10%,X6SA
GND                      C3D1             2        CAP_A_0603V-22.0UF,4V,20%,X6S,A
GND                      C3D2             2        CAP_A_0603V-22.0UF,4V,20%,X6S,A
GND                      C3D3             2        CAP_0603LF-10UF,4V,20%,X6S,E15A
GND                      C3D4             2        CAP_A_0603V-22.0UF,4V,20%,X6S,A
GND                      C3D5             2        CAP_A_0603V-22.0UF,4V,20%,X6S,A
GND                      C3D6             2        CAP_A_0603V-22.0UF,4V,20%,X6S,A
GND                      C3D7             2        CAP_A_0603V-22.0UF,4V,20%,X6S,A
GND                      C3D8             2        CAP_A_0603V-22.0UF,4V,20%,X6S,A
GND                      C3D9             2        CAP_A_0603V-22.0UF,4V,20%,X6S,A
GND                      C3D10            2        CAP_A_0603V-22.0UF,4V,20%,X6S,A
GND                      C3D11            2        CAP_A_0603V-22.0UF,4V,20%,X6S,A
GND                      C3D12            2        CAP_A_0603V-22.0UF,4V,20%,X6S,A
GND                      C3D13            2        CAP_A_0603V-22.0UF,4V,20%,X6S,A
GND                      C3D14            2        CAP_A_0603V-22.0UF,4V,20%,X6S,A
GND                      C3D15            2        CAP_A_0603V-22.0UF,4V,20%,X6S,A
GND                      C3D16            2        CAP_A_0603V-22.0UF,4V,20%,X6S,A
GND                      C3D17            2        CAP_A_0603V-22.0UF,4V,20%,X6S,A
GND                      C3D18            2        CAP_A_0603V-22.0UF,4V,20%,X6S,A
GND                      C3D19            2        CAP_A_0603V-22.0UF,4V,20%,X6S,A
GND                      C3D20            2        CAP_A_0603V-22.0UF,4V,20%,X6S,A
GND                      C3D21            2        CAP_A_0603V-22.0UF,4V,20%,X6S,A
GND                      C3D22            2        CAP_0805-10UF,16V,10%,X7R,G106A
GND                      C3D23            2        CAP_A_0603V-22.0UF,4V,20%,X6S,A
GND                      C3D24            2        CAP_A_0603V-22.0UF,4V,20%,X6S,A
GND                      C3D25            2        CAP_A_0603V-22.0UF,4V,20%,X6S,A
GND                      C3E1             2        CAP_A_0603V-22.0UF,4V,20%,X6S,A
GND                      C3F1             2        CAP_A_0603V-47UF,4V,20%,X5R,60A
GND                      C3F2             2        CAP_A_0402V-0.1UF,16V,10%,X7R,A
GND                      C3F3             2        CAP_0603LF-10UF,4V,20%,X6S,E15A
GND                      C3F4             2        CAP_0603LF-10UF,4V,20%,X6S,E15A
GND                      C3G1             2        CAP_A_0603V-22.0UF,4V,20%,X6S,A
GND                      C3G2             2        CAP_A_0603V-22.0UF,4V,20%,X6S,A
GND                      C3G3             2        CAP_0603LF-10UF,4V,20%,X6S,E15A
GND                      C3G4             2        CAP_0603LF-10UF,4V,20%,X6S,E15A
GND                      C3G5             2        CAP_A_0603V-22.0UF,4V,20%,X6S,A
GND                      C3G6             2        CAP_A_0603V-22.0UF,4V,20%,X6S,A
GND                      C3G7             2        CAP_0603LF-10UF,4V,20%,X6S,E15A
GND                      C3G8             2        CAP_0603LF-10UF,4V,20%,X6S,E15A
GND                      C3L1             2        CAP_A_0402V-1.0UF,6.3V,10%,X6SA
GND                      C3L2             2        CAP_0805-10UF,16V,10%,X6S,C953A
GND                      C3L4             2        CAP_0805-10UF,16V,10%,X6S,C953A
GND                      C3L6             2        CAPP_3018-470UF,2.5V,20%,ALUM,A
GND                      C3L7             2        CAP_0805-10UF,16V,10%,X6S,C953A
GND                      C3L8             2        CAP_0805-10UF,16V,10%,X6S,C953A
GND                      C3L9             2        CAP_0805-10UF,16V,10%,X6S,C953A
GND                      C3L10            2        CAP_0805-10UF,16V,10%,X6S,C953A
GND                      C3L11            2        CAP_0805-10UF,16V,10%,X6S,C953A
GND                      C3L12            2        CAP_0805-10UF,16V,10%,X6S,C953A
GND                      C3L13            2        CAP_0805-10UF,16V,10%,X6S,C953A
GND                      C3L14            2        CAPP_3018-470UF,2.5V,20%,ALUM,A
GND                      C3L15            2        CAP_0805-10UF,16V,10%,X6S,C953A
GND                      C3L16            2        CAP_0805-10UF,16V,10%,X6S,C953A
GND                      C3L17            2        CAP_0805-10UF,16V,10%,X6S,C953A
GND                      C3L18            2        CAPP_SM-470UF,2V,20%,ALUM,6990A
GND                      C3L19            2        CAPP_SM-470UF,2V,20%,ALUM,6990A
GND                      C3L20            2        CAPP_SM-470UF,2V,20%,ALUM,6990A
GND                      C3L21            2        CAPP_SM-470UF,2V,20%,ALUM,6990A
GND                      C3L22            2        CAP_A_0603V-22.0UF,4V,20%,X6S,A
GND                      C3L23            2        CAP_A_0603V-22.0UF,4V,20%,X6S,A
GND                      C3L24            2        CAP_A_0603V-22.0UF,4V,20%,X6S,A
GND                      C3L25            2        CAP_A_0603V-22.0UF,4V,20%,X6S,A
GND                      C3L26            2        CAP_A_0603V-22.0UF,4V,20%,X6S,A
GND                      C3L27            2        CAP_A_0603V-22.0UF,4V,20%,X6S,A
GND                      C3L29            2        CAP_A_0402V-1.0UF,6.3V,10%,X6SA
GND                      C3L31            2        CAP_A_0402V-0.1UF,16V,10%,X7R,A
GND                      C3M6             2        CAP_A_0603V-22.0UF,4V,20%,X6S,A
GND                      C3M7             2        CAP_A_0603V-22.0UF,4V,20%,X6S,A
GND                      C3M8             2        CAP_0805-10UF,16V,10%,X6S,C953A
GND                      C3M9             2        CAP_0402-1.0UF,16V,10%,X6S,D97A
GND                      C3M15            2        CAP_0805-10UF,16V,10%,X6S,C953A
GND                      C3M16            2        CAP_0805-10UF,16V,10%,X6S,C953A
GND                      C3M17            2        CAP_0603LF-10UF,4V,20%,X6S,E15A
GND                      C3M18            2        CAP_0603LF-10UF,4V,20%,X6S,E15A
GND                      C3M19            2        CAP_A_0402V-1.0UF,6.3V,10%,X6SA
GND                      C3M20            2        CAP_A_0402V-1.0UF,6.3V,10%,X6SA
GND                      C3M21            2        CAP_A_0402V-1.0UF,6.3V,10%,X6SA
GND                      C3M22            2        CAP_A_0402V-1.0UF,6.3V,10%,X6SA
GND                      C3M23            2        CAP_0603LF-10UF,4V,20%,X6S,E15A
GND                      C3M24            2        CAP_0603LF-10UF,4V,20%,X6S,E15A
GND                      C3M27            2        CAP_A_0402V-1.0UF,6.3V,10%,X6SA
GND                      C3M29            2        CAP_A_0402V-1.0UF,6.3V,10%,X6SA
GND                      C3M30            2        CAP_A_0402V-1.0UF,6.3V,10%,X6SA
GND                      C3M31            2        CAP_A_0402V-1.0UF,6.3V,10%,X6SA
GND                      C3M38            2        CAP_A_0402V-1.0UF,6.3V,10%,X6SA
GND                      C3M39            2        CAP_A_0402V-1.0UF,6.3V,10%,X6SA
GND                      C3M42            2        CAP_A_0402V-1.0UF,6.3V,10%,X6SA
GND                      C3M43            2        CAP_A_0402V-1.0UF,6.3V,10%,X6SA
GND                      C3M46            2        CAP_A_0402V-1.0UF,6.3V,10%,X6SA
GND                      C3N1             2        CAP_A_0402V-1.0UF,6.3V,10%,X6SA
GND                      C3N2             2        CAP_A_0402V-1.0UF,6.3V,10%,X6SA
GND                      C3N3             2        CAP_A_0402V-1.0UF,6.3V,10%,X6SA
GND                      C3N4             2        CAP_A_0402V-1.0UF,6.3V,10%,X6SA
GND                      C3N5             2        CAP_A_0402V-1.0UF,6.3V,10%,X6SA
GND                      C3N6             2        CAP_A_0402V-1.0UF,6.3V,10%,X6SA
GND                      C3N7             2        CAP_A_0402V-1.0UF,6.3V,10%,X6SA
GND                      C3N10            2        CAP_A_0603V-22.0UF,4V,20%,X6S,A
GND                      C3N11            2        CAP_A_0603V-22.0UF,4V,20%,X6S,A
GND                      C3N12            2        CAP_A_0603V-22.0UF,4V,20%,X6S,A
GND                      C3N14            2        CAPP_3018-470UF,2.5V,20%,ALUM,A
GND                      C3N15            2        CAP_A_0402V-1.0UF,6.3V,10%,X6SA
GND                      C3N16            2        CAP_A_0402V-1.0UF,6.3V,10%,X6SA
GND                      C3N17            2        CAP_A_0402V-1.0UF,6.3V,10%,X6SA
GND                      C3N18            2        CAP_A_0402V-1.0UF,6.3V,10%,X6SA
GND                      C3N19            2        CAP_A_0402V-1.0UF,6.3V,10%,X6SA
GND                      C3N20            2        CAP_A_0402V-1.0UF,6.3V,10%,X6SA
GND                      C3N21            2        CAP_A_0402V-1.0UF,6.3V,10%,X6SA
GND                      C3N22            2        CAP_A_0402V-1.0UF,6.3V,10%,X6SA
GND                      C3N23            2        CAP_A_0402V-1.0UF,6.3V,10%,X6SA
GND                      C3N24            2        CAP_A_0603V-22.0UF,4V,20%,X6S,A
GND                      C3N25            2        CAP_A_0402V-1.0UF,6.3V,10%,X6SA
GND                      C3N26            2        CAPP_3018-470UF,2.5V,20%,ALUM,A
GND                      C3N27            2        CAP_A_0603V-22.0UF,4V,20%,X6S,A
GND                      C3N28            2        CAP_A_0603V-22.0UF,4V,20%,X6S,A
GND                      C3N29            2        CAP_A_0402V-0.1UF,16V,10%,X7R,A
GND                      C3N30            2        CAP_A_0603V-22.0UF,4V,20%,X6S,A
GND                      C3N31            2        CAP_A_0603V-22.0UF,4V,20%,X6S,A
GND                      C3N32            2        CAP_A_0402V-1.0UF,6.3V,10%,X6SA
GND                      C3N33            2        CAP_0805-10UF,16V,10%,X6S,C953A
GND                      C3N34            2        CAP_0805-10UF,16V,10%,X6S,C953A
GND                      C3N35            2        CAPP_3018-470UF,2.5V,20%,ALUM,A
GND                      C3N36            2        CAP_0805-10UF,16V,10%,X6S,C953A
GND                      C3N38            2        CAPP_3018-470UF,2.5V,20%,ALUM,A
GND                      C3N40            2        CAP_A_0402V-1.0UF,6.3V,10%,X6SA
GND                      C3P2             2        CAP_0402LF-1000PF,50V,10%,X7R,A
GND                      C3P3             2        CAP_A_0402V-1.0UF,6.3V,10%,X6SA
GND                      C3P4             2        CAP_A_0402V-1.0UF,6.3V,10%,X6SA
GND                      C3P5             2        CAP_A_0402V-0.1UF,16V,10%,X7R,A
GND                      C3P6             2        CAP_0402LF-1000PF,50V,10%,X7R,A
GND                      C3P7             2        CAP_A_0402V-0.1UF,16V,10%,X7R,A
GND                      C3P42            2        CAP_A_0402V-1.0UF,6.3V,10%,X6SA
GND                      C3P43            2        CAP_A_0402V-0.1UF,16V,10%,X7R,A
GND                      C3P44            2        CAP_A_0402V-0.1UF,16V,10%,X7R,A
GND                      C3P45            2        CAP_0402-0.047UF,25V,10%,X7R,AA
GND                      C3P46            2        CAP_A_0402V-0.1UF,16V,10%,X7R,A
GND                      C3P47            2        CAP_A_0402V-0.1UF,16V,10%,X7R,A
GND                      C3P48            2        CAP_A_0402V-0.1UF,16V,10%,X7R,A
GND                      C3P49            2        CAP_A_0402V-0.1UF,16V,10%,X7R,A
GND                      C3P50            2        CAP_0402-1.0UF,16V,10%,X6S,D97A
GND                      C3P51            2        CAP_A_0402V-0.1UF,16V,10%,X7R,A
GND                      C3P52            2        CAP_A_0402V-0.1UF,16V,10%,X7R,A
GND                      C3R1             2        CAP_A_0402V-0.1UF,16V,10%,X7R,A
GND                      C3R2             2        CAP_A_0402V-0.1UF,16V,10%,X7R,A
GND                      C3R3             2        CAP_A_0402V-0.1UF,16V,10%,X7R,A
GND                      C3R4             2        CAPP_3018-470UF,2.5V,20%,ALUM,A
GND                      C3T1             2        CAP_A_0603V-47UF,4V,20%,X5R,60A
GND                      C3T2             2        CAP_A_0603V-47UF,4V,20%,X5R,60A
GND                      C3T3             2        CAPP_3018-68UF,16V,20%,TANT,72A
GND                      C3T4             2        CAP_A_0402V-1.0UF,6.3V,10%,X6SA
GND                      C3T5             2        CAP_A_0402V-0.01UF,25V,10%,X7RA
GND                      C3T6             2        CAPP_3018-68UF,16V,20%,TANT,72A
GND                      C3T7             2        CAP_0805-47UF,4V,20%,X6S,C9533A
GND                      C3T8             2        CAP_0805-10UF,16V,10%,X6S,C953A
GND                      C3T9             2        CAP_0805-47UF,4V,20%,X6S,C9533A
GND                      C3T10            2        CAP_0402-1.0UF,16V,10%,X6S,D97A
GND                      C3T12            2        CAP_0805-10UF,16V,10%,X6S,C953A
GND                      C3T13            2        CAPP_3018-68UF,16V,20%,TANT,72A
GND                      C3T14            2        CAP_0805-10UF,16V,10%,X6S,C953A
GND                      C3T15            2        CAPP_3018-68UF,16V,20%,TANT,72A
GND                      C3U1             2        CAPP_3018-470UF,2.5V,20%,ALUM,A
GND                      C3U2             2        CAP_0805-10UF,16V,10%,X6S,C953A
GND                      C3U3             2        CAP_0805-10UF,16V,10%,X6S,C953A
GND                      C3U4             2        CAP_0805-10UF,16V,10%,X6S,C953A
GND                      C3U5             2        CAPP_3018-470UF,2.5V,20%,ALUM,A
GND                      C3U6             2        CAP_0805-10UF,16V,10%,X6S,C953A
GND                      C3U7             2        CAP_0805-10UF,16V,10%,X6S,C953A
GND                      C3U8             2        CAPP_3018-470UF,2.5V,20%,ALUM,A
GND                      C3U9             2        CAP_0805-10UF,16V,10%,X6S,C953A
GND                      C3U10            2        CAP_A_0402V-0.1UF,16V,10%,X7R,A
GND                      C4A1             2        CAP_0805LF-22UF,4V,20%,X6S,C95A
GND                      C4A2             2        CAP_0402LF-1000PF,50V,10%,EMPTA
GND                      C4A3             2        CAP_0402LF-1000PF,50V,10%,X7R,A
GND                      C4A4             2        CAP_0805-10UF,16V,10%,X7R,G106A
GND                      C4A5             2        CAP_A_0402V-0.01UF,25V,10%,X7RA
GND                      C4A6             2        CAP_0402LF-1000PF,50V,10%,EMPTA
GND                      C4A7             2        CAP_0603-4.7UF,6.3V,10%,X6S,E1A
GND                      C4A8             2        CAP_0402-1.0UF,16V,10%,X6S,D97A
GND                      C4A9             2        CAP_0402-1.0UF,16V,10%,X6S,D97A
GND                      C4A10            2        CAP_0402-1.0UF,16V,10%,X6S,D97A
GND                      C4A11            2        CAP_0603-4.7UF,6.3V,10%,X6S,E1A
GND                      C4A12            2        CAP_0402LF-1000PF,50V,10%,X7R,A
GND                      C4A13            2        CAP_0805LF-22UF,4V,20%,X6S,C95A
GND                      C4A14            2        CAP_0402-1.0UF,16V,10%,X6S,D97A
GND                      C4A15            2        CAP_0603LF-10UF,4V,20%,X6S,E15A
GND                      C4A17            2        CAP_0805-10UF,16V,10%,X7R,G106A
GND                      C4A18            2        CAP_A_0402V-0.01UF,25V,10%,X7RA
GND                      C4A19            2        CAP_0805-10UF,16V,10%,X6S,C953A
GND                      C4A20            2        CAP_A_0402V-0.1UF,16V,10%,X7R,A
GND                      C4B1             2        CAP_1210-47UF,16V,20%,X6S,D384A
GND                      C4B2             2        CAP_0805-47UF,4V,20%,X6S,C9533A
GND                      C4B3             2        CAP_0805-47UF,4V,20%,X6S,C9533A
GND                      C4B8             2        CAP_0402LF-1000PF,50V,10%,X7R,A
GND                      C4B11            2        CAP_0805-10UF,16V,10%,X7R,G106A
GND                      C4B12            2        CAP_A_0402V-0.01UF,25V,10%,X7RA
GND                      C4B13            2        CAPP_4040LF-470UF,16V,20%,ALUMA
GND                      C4B14            2        CAPP_3018-68UF,16V,20%,TANT,72A
GND                      C4C1             2        CAPP_3018-470UF,2.5V,20%,ALUM,A
GND                      C4C2             2        CAP_A_0402V-0.1UF,16V,10%,EMPTA
GND                      C4C3             2        CAP_A_0402V-1.0UF,6.3V,10%,X6SA
GND                      C4C4             2        CAP_A_0402V-1.0UF,6.3V,10%,X6SA
GND                      C4C5             2        CAP_0402-0.22UF,16V,10%,X7R,A3A
GND                      C4C6             2        CAP_0402-1.0UF,16V,10%,X6S,D97A
GND                      C4C9             2        CAP_0402-1.0UF,16V,10%,X6S,D97A
GND                      C4C10            2        CAP_A_0402V-0.1UF,16V,10%,X7R,A
GND                      C4C11            2        CAP_A_0603V-22.0UF,4V,20%,X6S,A
GND                      C4C12            2        CAPP_2626-270UF,16V,20%,OSCON,A
GND                      C4C14            2        CAP_A_0402V-1.0UF,6.3V,10%,X6SA
GND                      C4C18            2        CAP_0402-1.0UF,16V,10%,X6S,D97A
GND                      C4C19            2        CAP_A_0402V-0.1UF,16V,10%,X7R,A
GND                      C4D2             2        CAPP_2626-270UF,16V,20%,OSCON,A
GND                      C4D4             2        CAP_A_0603V-22.0UF,4V,20%,X6S,A
GND                      C4D5             2        CAP_0402-0.22UF,16V,10%,X7R,A3A
GND                      C4D6             2        CAP_A_0402V-1.0UF,6.3V,10%,X6SA
GND                      C4D7             2        CAP_0402-1.0UF,16V,10%,X6S,D97A
GND                      C4D10            2        CAP_0402-1.0UF,16V,10%,X6S,D97A
GND                      C4D11            2        CAP_A_0402V-0.1UF,16V,10%,X7R,A
GND                      C4D12            2        CAP_A_0603V-22.0UF,4V,20%,X6S,A
GND                      C4D13            2        CAP_0402-0.22UF,16V,10%,X7R,A3A
GND                      C4D14            2        CAP_A_0402V-1.0UF,6.3V,10%,X6SA
GND                      C4D15            2        CAP_A_0402V-1.0UF,6.3V,10%,X6SA
GND                      C4D16            2        CAP_0402-1.0UF,16V,10%,X6S,D97A
GND                      C4D17            2        CAP_0402LF-220PF,50V,10%,X7R,AA
GND                      C4D18            2        CAP_0402LF-220PF,50V,10%,X7R,AA
GND                      C4D19            2        CAP_A_0402V-0.1UF,16V,10%,X7R,A
GND                      C4D20            2        CAP_0402LF-1000PF,50V,10%,X7R,A
GND                      C4D22            2        CAP_A_0402V-0.1UF,16V,10%,X7R,A
GND                      C4D23            2        CAP_A_0402V-1.0UF,6.3V,10%,X6SA
GND                      C4D24            2        CAP_A_0402V-0.1UF,16V,10%,X7R,A
GND                      C4D25            2        CAP_A_0402V-1.0UF,6.3V,10%,X6SA
GND                      C4D26            2        CAP_A_0402V-0.1UF,16V,10%,X7R,A
GND                      C4D27            2        CAP_A_0402V-1.0UF,6.3V,10%,X6SA
GND                      C4D30            2        CAP_0402-1.0UF,16V,10%,X6S,D97A
GND                      C4D31            2        CAP_A_0402V-1.0UF,6.3V,10%,X6SA
GND                      C4D32            2        CAP_A_0402V-0.1UF,16V,10%,X7R,A
GND                      C4D33            2        CAP_0402LF-1000PF,50V,10%,X7R,A
GND                      C4D34            2        CAP_A_0603V-22.0UF,4V,20%,X6S,A
GND                      C4D35            2        CAP_A_0402V-0.1UF,16V,10%,X7R,A
GND                      C4D36            2        CAP_A_0402V-1.0UF,6.3V,10%,X6SA
GND                      C4D38            2        CAP_A_0402V-0.1UF,16V,10%,X7R,A
GND                      C4D40            2        CAP_0402LF-1000PF,50V,10%,X7R,A
GND                      C4D42            2        CAP_0402LF-1000PF,50V,10%,X7R,A
GND                      C4D46            2        CAP_0402-1.0UF,16V,10%,X6S,D97A
GND                      C4D47            2        CAP_0402-0.22UF,16V,10%,X7R,A3A
GND                      C4D48            2        CAP_0402-1.0UF,16V,10%,X6S,D97A
GND                      C4D49            2        CAP_A_0402V-0.1UF,16V,10%,X7R,A
GND                      C4E3             2        CAP_A_0603V-22.0UF,4V,20%,X6S,A
GND                      C4E5             2        CAP_0402-0.22UF,16V,10%,X7R,A3A
GND                      C4E6             2        CAP_A_0402V-1.0UF,6.3V,10%,X6SA
GND                      C4E7             2        CAPP_3018-470UF,2.5V,20%,ALUM,A
GND                      C4E8             2        CAP_1210-100UF,16V,20%,X5R,644A
GND                      C4E9             2        CAP_1210-100UF,16V,20%,X5R,644A
GND                      C4E10            2        CAP_0402-1.0UF,16V,10%,X6S,D97A
GND                      C4E11            2        CAP_A_0603V-22.0UF,4V,20%,X6S,A
GND                      C4E13            2        CAP_A_0402V-0.1UF,16V,10%,X7R,A
GND                      C4E14            2        CAP_1210-100UF,16V,20%,X5R,644A
GND                      C4E15            2        CAP_0402-1.0UF,16V,10%,X6S,D97A
GND                      C4E16            2        CAPP_2626-270UF,16V,20%,OSCON,A
GND                      C4E19            2        CAP_0402-1.0UF,16V,10%,X6S,D97A
GND                      C4E20            2        CAP_A_0402V-0.1UF,16V,10%,X7R,A
GND                      C4E22            2        CAP_0402-1.0UF,16V,10%,X6S,D97A
GND                      C4E23            2        CAP_0402-0.22UF,16V,10%,X7R,A3A
GND                      C4E24            2        CAPP_3018-470UF,2.5V,20%,ALUM,A
GND                      C4E25            2        CAP_A_0402V-1.0UF,6.3V,10%,X6SA
GND                      C4E26            2        CAP_0402-1.0UF,16V,10%,X6S,D97A
GND                      C4E27            2        CAP_0402-0.22UF,16V,10%,X7R,A3A
GND                      C4E28            2        CAP_A_0402V-1.0UF,6.3V,10%,X6SA
GND                      C4F1             2        CAP_A_0402V-1.0UF,6.3V,10%,X6SA
GND                      C4F2             2        CAP_A_0603V-47UF,4V,20%,X5R,60A
GND                      C4F3             2        CAP_A_0402V-1.0UF,6.3V,10%,X6SA
GND                      C4F4             2        CAPP_3018-68UF,16V,20%,TANT,72A
GND                      C4F5             2        CAPP_3018-68UF,16V,20%,TANT,72A
GND                      C4F6             2        CAPP_4040LF-470UF,16V,20%,ALUMA
GND                      C4F7             2        CAPP_7343LF-330UF,6.3V,20%,POSA
GND                      C4F9             2        CAP_A_0402V-0.01UF,25V,10%,X7RA
GND                      C4F10            2        CAP_A_0402V-0.01UF,25V,10%,X7RA
GND                      C4F11            2        CAPP_7343-220UF,4V,20%,POSCAP,A
GND                      C4G1             2        CAP_A_0402V-0.01UF,25V,10%,X7RA
GND                      C4G2             2        CAP_0805-10UF,16V,10%,X6S,C953A
GND                      C4G3             2        CAP_A_0402V-0.01UF,25V,10%,X7RA
GND                      C4G4             2        CAP_0402-1.0UF,16V,10%,X6S,D97A
GND                      C4G5             2        CAP_1210-47UF,16V,20%,X6S,D384A
GND                      C4G9             2        CAP_0402LF-1000PF,50V,10%,X7R,A
GND                      C4G12            2        CAP_0402LF-1000PF,50V,10%,EMPTA
GND                      C4G13            2        CAP_0402LF-1000PF,50V,10%,X7R,A
GND                      C4G14            2        CAP_0402LF-1000PF,50V,10%,X7R,A
GND                      C4G15            2        CAP_0402-1.0UF,16V,10%,X6S,D97A
GND                      C4G16            2        CAP_0402-1.0UF,16V,10%,X6S,D97A
GND                      C4G17            2        CAP_A_0402V-0.01UF,25V,10%,X7RA
GND                      C4G18            2        CAP_0402-1.0UF,16V,10%,X6S,D97A
GND                      C4G19            2        CAP_A_0402V-0.01UF,25V,10%,X7RA
GND                      C4G20            2        CAP_0805LF-22UF,4V,20%,X6S,C95A
GND                      C4G21            2        CAP_0402-1.0UF,16V,10%,X6S,D97A
GND                      C4G22            2        CAP_A_0402V-0.1UF,16V,10%,X7R,A
GND                      C4G23            2        CAP_0402LF-1000PF,50V,10%,EMPTA
GND                      C4G24            2        CAP_0805LF-22UF,4V,20%,X6S,C95A
GND                      C4G25            2        CAP_A_0402V-0.1UF,16V,10%,X7R,A
GND                      C4L1             2        CAP_0603LF-10UF,4V,20%,X6S,E15A
GND                      C4L2             2        CAP_0603LF-10UF,4V,20%,X6S,E15A
GND                      C4L3             2        CAP_0603LF-10UF,4V,20%,X6S,E15A
GND                      C4L4             2        CAP_0603LF-10UF,4V,20%,X6S,E15A
GND                      C4L5             2        CAPP_3018-470UF,2.5V,20%,ALUM,A
GND                      C4M1             2        CAPP_7343-220UF,4V,20%,POSCAP,A
GND                      C4M2             2        CAP_A_0603V-22.0UF,4V,20%,X6S,A
GND                      C4M3             2        CAP_0603LF-10UF,4V,20%,X6S,E15A
GND                      C4M4             2        CAP_0603LF-10UF,4V,20%,X6S,E15A
GND                      C4M5             2        CAP_A_0603V-47UF,4V,20%,X5R,60A
GND                      C4M6             2        CAPP_3018-68UF,16V,20%,TANT,72A
GND                      C4M7             2        CAPP_3018-68UF,16V,20%,TANT,72A
GND                      C4P1             2        CAP_0805-47UF,4V,20%,X6S,C9533A
GND                      C4P2             2        CAP_0805-47UF,4V,20%,X6S,C9533A
GND                      C4P3             2        CAP_0805-47UF,4V,20%,X6S,C9533A
GND                      C4P4             2        CAP_0805-47UF,4V,20%,X6S,C9533A
GND                      C4P5             2        CAP_0805-47UF,4V,20%,X6S,C9533A
GND                      C4P6             2        CAP_A_0603V-22.0UF,4V,20%,X6S,A
GND                      C4P7             2        CAP_0805-47UF,4V,20%,X6S,C9533A
GND                      C4P8             2        CAP_A_0603V-22.0UF,4V,20%,X6S,A
GND                      C4P9             2        CAP_0805-47UF,4V,20%,X6S,C9533A
GND                      C4P10            2        CAP_0805-47UF,4V,20%,X6S,C9533A
GND                      C4R1             2        CAPP_3018-470UF,2.5V,20%,ALUM,A
GND                      C4R2             2        CAP_A_0402V-0.1UF,16V,10%,X7R,A
GND                      C4T1             2        CAP_A_0402V-1.0UF,6.3V,10%,X6SA
GND                      C4T2             2        CAP_A_0402V-1.0UF,6.3V,10%,X6SA
GND                      C4T3             2        CAPP_7343-220UF,4V,20%,POSCAP,A
GND                      C4T4             2        CAP_0805-100UF,4V,20%,X5R,6024A
GND                      C4T5             2        CAP_0603LF-10UF,4V,20%,X6S,E15A
GND                      C4T6             2        CAP_0603LF-10UF,4V,20%,X6S,E15A
GND                      C4U1             2        CAP_0603LF-10UF,4V,20%,X6S,E15A
GND                      C4U2             2        CAP_0603LF-10UF,4V,20%,X6S,E15A
GND                      C4U3             2        CAP_0603LF-10UF,4V,20%,X6S,E15A
GND                      C4U4             2        CAP_0603LF-10UF,4V,20%,X6S,E15A
GND                      C5A1             2        CAP_A_0603V-22.0UF,4V,20%,X6S,A
GND                      C5A2             2        CAP_A_0603V-22.0UF,4V,20%,X6S,A
GND                      C5A3             2        CAP_A_0603V-22.0UF,4V,20%,X6S,A
GND                      C5A4             2        CAP_A_0603V-22.0UF,4V,20%,X6S,A
GND                      C5A5             2        CAP_A_0603V-47UF,4V,20%,X5R,60A
GND                      C5A6             2        CAP_A_0603V-22.0UF,4V,20%,X6S,A
GND                      C5A7             2        CAP_A_0603V-22.0UF,4V,20%,X6S,A
GND                      C5A8             2        CAP_A_0603V-22.0UF,4V,20%,X6S,A
GND                      C5A9             2        CAP_A_0603V-22.0UF,4V,20%,X6S,A
GND                      C5A10            2        CAP_0805-100UF,4V,20%,X5R,6024A
GND                      C5A11            2        CAP_A_0603V-22.0UF,4V,20%,X6S,A
GND                      C5A12            2        CAP_A_0603V-22.0UF,4V,20%,X6S,A
GND                      C5A13            2        CAP_A_0603V-22.0UF,4V,20%,X6S,A
GND                      C5A14            2        CAP_A_0603V-22.0UF,4V,20%,X6S,A
GND                      C5A15            2        CAP_A_0603V-22.0UF,4V,20%,X6S,A
GND                      C5A16            2        CAP_A_0603V-22.0UF,4V,20%,X6S,A
GND                      C5A17            2        CAP_A_0603V-22.0UF,4V,20%,X6S,A
GND                      C5A18            2        CAP_A_0603V-22.0UF,4V,20%,X6S,A
GND                      C5A19            2        CAP_A_0603V-22.0UF,4V,20%,X6S,A
GND                      C5A20            2        CAP_0805-100UF,4V,20%,X5R,6024A
GND                      C5B1             2        CAP_A_0603V-47UF,4V,20%,X5R,60A
GND                      C5B2             2        CAP_A_0603V-47UF,4V,20%,X5R,60A
GND                      C5D1             2        CAP_A_0603V-22.0UF,4V,20%,X6S,A
GND                      C5D2             2        CAP_A_0603V-22.0UF,4V,20%,X6S,A
GND                      C5D3             2        CAP_A_0603V-22.0UF,4V,20%,X6S,A
GND                      C5D4             2        CAP_A_0603V-22.0UF,4V,20%,X6S,A
GND                      C5D5             2        CAP_A_0603V-22.0UF,4V,20%,X6S,A
GND                      C5D6             2        CAP_0603LF-10UF,4V,20%,X6S,E15A
GND                      C5D7             2        CAP_0603LF-10UF,4V,20%,X6S,E15A
GND                      C5D8             2        CAP_0603LF-10UF,4V,20%,X6S,E15A
GND                      C5D9             2        CAP_0603LF-10UF,4V,20%,X6S,E15A
GND                      C5D10            2        CAP_0603LF-10UF,4V,20%,X6S,E15A
GND                      C5D11            2        CAP_0603LF-10UF,4V,20%,X6S,E15A
GND                      C5D12            2        CAP_0603LF-10UF,4V,20%,X6S,E15A
GND                      C5D13            2        CAP_0603LF-10UF,4V,20%,X6S,E15A
GND                      C5D14            2        CAP_A_0603V-22.0UF,4V,20%,X6S,A
GND                      C5D15            2        CAP_A_0603V-22.0UF,4V,20%,X6S,A
GND                      C5D16            2        CAP_A_0603V-22.0UF,4V,20%,X6S,A
GND                      C5D17            2        CAP_A_0603V-22.0UF,4V,20%,X6S,A
GND                      C5D18            2        CAP_A_0603V-22.0UF,4V,20%,X6S,A
GND                      C5D19            2        CAP_A_0603V-22.0UF,4V,20%,X6S,A
GND                      C5D20            2        CAP_A_0603V-22.0UF,4V,20%,X6S,A
GND                      C5D21            2        CAP_A_0603V-22.0UF,4V,20%,X6S,A
GND                      C5D22            2        CAP_A_0603V-22.0UF,4V,20%,X6S,A
GND                      C5D23            2        CAP_A_0603V-22.0UF,4V,20%,X6S,A
GND                      C5D24            2        CAP_A_0603V-22.0UF,4V,20%,X6S,A
GND                      C5D25            2        CAP_A_0603V-22.0UF,4V,20%,X6S,A
GND                      C5D26            2        CAP_A_0603V-22.0UF,4V,20%,X6S,A
GND                      C5D27            2        CAP_A_0603V-22.0UF,4V,20%,X6S,A
GND                      C5D28            2        CAP_A_0603V-22.0UF,4V,20%,X6S,A
GND                      C5D29            2        CAP_A_0603V-22.0UF,4V,20%,X6S,A
GND                      C5D30            2        CAP_A_0603V-22.0UF,4V,20%,X6S,A
GND                      C5D31            2        CAP_A_0603V-22.0UF,4V,20%,X6S,A
GND                      C5D32            2        CAP_A_0603V-22.0UF,4V,20%,X6S,A
GND                      C5D33            2        CAP_A_0603V-22.0UF,4V,20%,X6S,A
GND                      C5D34            2        CAP_A_0603V-22.0UF,4V,20%,X6S,A
GND                      C5D35            2        CAP_A_0603V-22.0UF,4V,20%,X6S,A
GND                      C5D36            2        CAP_A_0603V-22.0UF,4V,20%,X6S,A
GND                      C5D37            2        CAP_A_0603V-22.0UF,4V,20%,X6S,A
GND                      C5D38            2        CAP_A_0603V-22.0UF,4V,20%,X6S,A
GND                      C5D39            2        CAP_A_0603V-22.0UF,4V,20%,X6S,A
GND                      C5D40            2        CAP_A_0603V-22.0UF,4V,20%,X6S,A
GND                      C5D41            2        CAP_A_0603V-22.0UF,4V,20%,X6S,A
GND                      C5D42            2        CAP_A_0603V-22.0UF,4V,20%,X6S,A
GND                      C5D43            2        CAP_A_0603V-22.0UF,4V,20%,X6S,A
GND                      C5D44            2        CAP_A_0603V-22.0UF,4V,20%,X6S,A
GND                      C5D45            2        CAP_A_0603V-22.0UF,4V,20%,X6S,A
GND                      C5D46            2        CAP_A_0603V-22.0UF,4V,20%,X6S,A
GND                      C5D47            2        CAP_A_0603V-22.0UF,4V,20%,X6S,A
GND                      C5D48            2        CAP_A_0603V-22.0UF,4V,20%,X6S,A
GND                      C5D49            2        CAP_A_0603V-22.0UF,4V,20%,X6S,A
GND                      C5D50            2        CAP_A_0603V-22.0UF,4V,20%,X6S,A
GND                      C5D51            2        CAP_A_0603V-22.0UF,4V,20%,X6S,A
GND                      C5D52            2        CAP_A_0603V-22.0UF,4V,20%,X6S,A
GND                      C5D53            2        CAP_A_0603V-22.0UF,4V,20%,X6S,A
GND                      C5D54            2        CAP_0603LF-10UF,4V,20%,X6S,E15A
GND                      C5D55            2        CAP_0603LF-10UF,4V,20%,X6S,E15A
GND                      C5D56            2        CAP_0603LF-10UF,4V,20%,X6S,E15A
GND                      C5D57            2        CAP_0603LF-10UF,4V,20%,X6S,E15A
GND                      C5D58            2        CAP_A_0603V-22.0UF,4V,20%,X6S,A
GND                      C5D59            2        CAP_A_0603V-22.0UF,4V,20%,X6S,A
GND                      C5D60            2        CAP_A_0603V-22.0UF,4V,20%,X6S,A
GND                      C5D61            2        CAP_A_0603V-22.0UF,4V,20%,X6S,A
GND                      C5F1             2        CAP_A_0603V-47UF,4V,20%,X5R,60A
GND                      C5F2             2        CAP_A_0603V-47UF,4V,20%,X5R,60A
GND                      C5G1             2        CAP_A_0603V-22.0UF,4V,20%,X6S,A
GND                      C5G2             2        CAP_A_0603V-22.0UF,4V,20%,X6S,A
GND                      C5G3             2        CAP_A_0603V-22.0UF,4V,20%,X6S,A
GND                      C5G4             2        CAP_A_0603V-22.0UF,4V,20%,X6S,A
GND                      C5G5             2        CAP_A_0603V-22.0UF,4V,20%,X6S,A
GND                      C5G6             2        CAP_A_0603V-22.0UF,4V,20%,X6S,A
GND                      C5G7             2        CAP_A_0603V-22.0UF,4V,20%,X6S,A
GND                      C5G8             2        CAP_A_0603V-22.0UF,4V,20%,X6S,A
GND                      C5G9             2        CAP_0805-100UF,4V,20%,X5R,6024A
GND                      C5G10            2        CAP_A_0603V-47UF,4V,20%,X5R,60A
GND                      C5G11            2        CAP_A_0603V-22.0UF,4V,20%,X6S,A
GND                      C5G12            2        CAP_A_0603V-22.0UF,4V,20%,X6S,A
GND                      C5G13            2        CAP_A_0603V-22.0UF,4V,20%,X6S,A
GND                      C5G14            2        CAP_A_0603V-22.0UF,4V,20%,X6S,A
GND                      C5G15            2        CAP_A_0603V-22.0UF,4V,20%,X6S,A
GND                      C5G16            2        CAP_A_0603V-22.0UF,4V,20%,X6S,A
GND                      C5G17            2        CAP_A_0603V-22.0UF,4V,20%,X6S,A
GND                      C5G18            2        CAP_A_0603V-22.0UF,4V,20%,X6S,A
GND                      C5G19            2        CAP_A_0603V-47UF,4V,20%,X5R,60A
GND                      C5G20            2        CAP_0805-100UF,4V,20%,X5R,6024A
GND                      C5G21            2        CAP_0805-100UF,4V,20%,X5R,6024A
GND                      C5G22            2        CAP_0805-100UF,4V,20%,X5R,6024A
GND                      C5G41            2        CAP_A_0603V-22.0UF,4V,20%,X6S,A
GND                      C5G42            2        CAP_A_0603V-22.0UF,4V,20%,X6S,A
GND                      C5G43            2        CAP_A_0603V-22.0UF,4V,20%,X6S,A
GND                      C5G44            2        CAP_A_0603V-22.0UF,4V,20%,X6S,A
GND                      C5G45            2        CAP_A_0603V-22.0UF,4V,20%,X6S,A
GND                      C5G46            2        CAP_A_0603V-22.0UF,4V,20%,X6S,A
GND                      C5G47            2        CAP_A_0603V-22.0UF,4V,20%,X6S,A
GND                      C5G48            2        CAP_A_0603V-22.0UF,4V,20%,X6S,A
GND                      C5G49            2        CAP_A_0603V-22.0UF,4V,20%,X6S,A
GND                      C5G50            2        CAP_A_0603V-22.0UF,4V,20%,X6S,A
GND                      C5G51            2        CAP_A_0603V-22.0UF,4V,20%,X6S,A
GND                      C5G52            2        CAP_A_0603V-22.0UF,4V,20%,X6S,A
GND                      C5G53            2        CAP_A_0603V-22.0UF,4V,20%,X6S,A
GND                      C5G54            2        CAP_A_0603V-22.0UF,4V,20%,X6S,A
GND                      C5G55            2        CAP_A_0603V-22.0UF,4V,20%,X6S,A
GND                      C5G56            2        CAP_A_0603V-22.0UF,4V,20%,X6S,A
GND                      C5G57            2        CAP_A_0603V-22.0UF,4V,20%,X6S,A
GND                      C5G58            2        CAP_A_0603V-22.0UF,4V,20%,X6S,A
GND                      C5G59            2        CAP_A_0603V-22.0UF,4V,20%,X6S,A
GND                      C5G60            2        CAP_A_0603V-22.0UF,4V,20%,X6S,A
GND                      C5G61            2        CAP_A_0603V-22.0UF,4V,20%,X6S,A
GND                      C5G62            2        CAP_A_0603V-22.0UF,4V,20%,X6S,A
GND                      C5G63            2        CAP_A_0603V-22.0UF,4V,20%,X6S,A
GND                      C5G64            2        CAP_A_0603V-22.0UF,4V,20%,X6S,A
GND                      C5G65            2        CAP_A_0603V-22.0UF,4V,20%,X6S,A
GND                      C5G66            2        CAP_A_0603V-22.0UF,4V,20%,X6S,A
GND                      C5G67            2        CAP_A_0603V-22.0UF,4V,20%,X6S,A
GND                      C5G68            2        CAP_A_0603V-22.0UF,4V,20%,X6S,A
GND                      C5G69            2        CAP_A_0603V-22.0UF,4V,20%,X6S,A
GND                      C5G70            2        CAP_A_0603V-22.0UF,4V,20%,X6S,A
GND                      C5G71            2        CAP_A_0603V-22.0UF,4V,20%,X6S,A
GND                      C5G72            2        CAP_A_0603V-22.0UF,4V,20%,X6S,A
GND                      C5G73            2        CAP_A_0603V-22.0UF,4V,20%,X6S,A
GND                      C5G74            2        CAP_A_0603V-22.0UF,4V,20%,X6S,A
GND                      C5G75            2        CAP_A_0603V-22.0UF,4V,20%,X6S,A
GND                      C5G76            2        CAP_A_0603V-22.0UF,4V,20%,X6S,A
GND                      C5G77            2        CAP_0805-100UF,4V,20%,X5R,6024A
GND                      C5G78            2        CAP_0805-100UF,4V,20%,X5R,6024A
GND                      C5G79            2        CAP_A_0603V-22.0UF,4V,20%,X6S,A
GND                      C5G80            2        CAP_A_0603V-22.0UF,4V,20%,X6S,A
GND                      C5G81            2        CAP_A_0603V-22.0UF,4V,20%,X6S,A
GND                      C5G82            2        CAP_A_0603V-22.0UF,4V,20%,X6S,A
GND                      C5G83            2        CAP_A_0603V-22.0UF,4V,20%,X6S,A
GND                      C5G84            2        CAP_A_0603V-22.0UF,4V,20%,X6S,A
GND                      C5G85            2        CAP_A_0603V-22.0UF,4V,20%,X6S,A
GND                      C5G86            2        CAP_A_0603V-22.0UF,4V,20%,X6S,A
GND                      C5G87            2        CAP_A_0603V-22.0UF,4V,20%,X6S,A
GND                      C5G88            2        CAP_A_0603V-22.0UF,4V,20%,X6S,A
GND                      C5G89            2        CAP_A_0603V-22.0UF,4V,20%,X6S,A
GND                      C5G90            2        CAP_A_0603V-22.0UF,4V,20%,X6S,A
GND                      C5G91            2        CAP_A_0603V-22.0UF,4V,20%,X6S,A
GND                      C5G92            2        CAP_A_0603V-22.0UF,4V,20%,X6S,A
GND                      C5G93            2        CAP_A_0603V-22.0UF,4V,20%,X6S,A
GND                      C5G94            2        CAP_A_0603V-22.0UF,4V,20%,X6S,A
GND                      C5G95            2        CAP_A_0603V-22.0UF,4V,20%,X6S,A
GND                      C5G96            2        CAP_A_0603V-22.0UF,4V,20%,X6S,A
GND                      C5G97            2        CAP_A_0603V-22.0UF,4V,20%,X6S,A
GND                      C5G98            2        CAP_A_0603V-22.0UF,4V,20%,X6S,A
GND                      C5G99            2        CAP_A_0603V-22.0UF,4V,20%,X6S,A
GND                      C5G100           2        CAP_A_0603V-22.0UF,4V,20%,X6S,A
GND                      C5G101           2        CAP_A_0603V-22.0UF,4V,20%,X6S,A
GND                      C5G102           2        CAP_A_0603V-22.0UF,4V,20%,X6S,A
GND                      C5G103           2        CAP_A_0603V-22.0UF,4V,20%,X6S,A
GND                      C5G104           2        CAP_A_0603V-22.0UF,4V,20%,X6S,A
GND                      C5G105           2        CAP_A_0603V-22.0UF,4V,20%,X6S,A
GND                      C5G106           2        CAP_A_0603V-22.0UF,4V,20%,X6S,A
GND                      C5G107           2        CAP_A_0603V-22.0UF,4V,20%,X6S,A
GND                      C5G108           2        CAP_A_0603V-22.0UF,4V,20%,X6S,A
GND                      C5G109           2        CAP_A_0603V-22.0UF,4V,20%,X6S,A
GND                      C5G110           2        CAP_A_0603V-22.0UF,4V,20%,X6S,A
GND                      C5G111           2        CAP_A_0603V-22.0UF,4V,20%,X6S,A
GND                      C5G112           2        CAP_A_0603V-22.0UF,4V,20%,X6S,A
GND                      C5G113           2        CAP_A_0603V-22.0UF,4V,20%,X6S,A
GND                      C5G114           2        CAP_A_0603V-22.0UF,4V,20%,X6S,A
GND                      C5G115           2        CAP_0805-100UF,4V,20%,X5R,6024A
GND                      C5G116           2        CAP_0805-100UF,4V,20%,X5R,6024A
GND                      C5G117           2        CAP_0805-100UF,4V,20%,X5R,6024A
GND                      C5G118           2        CAP_0805-100UF,4V,20%,X5R,6024A
GND                      C5L1             2        CAP_0805-100UF,4V,20%,X5R,6024A
GND                      C5L2             2        CAP_0805-100UF,4V,20%,X5R,6024A
GND                      C5L3             2        CAP_0805-100UF,4V,20%,X5R,6024A
GND                      C5L4             2        CAP_A_0603V-47UF,4V,20%,X5R,60A
GND                      C5L5             2        CAP_A_0603V-47UF,4V,20%,X5R,60A
GND                      C5L6             2        CAP_A_0603V-22.0UF,4V,20%,X6S,A
GND                      C5L7             2        CAP_A_0603V-22.0UF,4V,20%,X6S,A
GND                      C5L8             2        CAP_A_0603V-22.0UF,4V,20%,X6S,A
GND                      C5L9             2        CAP_A_0603V-22.0UF,4V,20%,X6S,A
GND                      C5L10            2        CAP_A_0603V-22.0UF,4V,20%,X6S,A
GND                      C5L11            2        CAP_A_0603V-22.0UF,4V,20%,X6S,A
GND                      C5L12            2        CAP_A_0603V-22.0UF,4V,20%,X6S,A
GND                      C5L13            2        CAP_A_0603V-22.0UF,4V,20%,X6S,A
GND                      C5L14            2        CAP_0805-100UF,4V,20%,X5R,6024A
GND                      C5L15            2        CAP_A_0603V-47UF,4V,20%,X5R,60A
GND                      C5M1             2        CAP_A_0603V-22.0UF,4V,20%,X6S,A
GND                      C5M2             2        CAP_A_0603V-22.0UF,4V,20%,X6S,A
GND                      C5M3             2        CAP_A_0603V-47UF,4V,20%,X5R,60A
GND                      C5M4             2        CAP_A_0603V-22.0UF,4V,20%,X6S,A
GND                      C5M5             2        CAP_A_0603V-22.0UF,4V,20%,X6S,A
GND                      C5M6             2        CAP_A_0603V-22.0UF,4V,20%,X6S,A
GND                      C5M7             2        CAP_A_0603V-22.0UF,4V,20%,X6S,A
GND                      C5M8             2        CAP_0805-100UF,4V,20%,X5R,6024A
GND                      C5M9             2        CAP_A_0603V-47UF,4V,20%,X5R,60A
GND                      C5M10            2        CAP_A_0603V-47UF,4V,20%,X5R,60A
GND                      C5M11            2        CAP_A_0603V-47UF,4V,20%,X5R,60A
GND                      C5M12            2        CAP_0805-100UF,4V,20%,X5R,6024A
GND                      C5M13            2        CAP_A_0603V-47UF,4V,20%,X5R,60A
GND                      C5P1             2        CAP_0805LF-22UF,4V,20%,X6S,C95A
GND                      C5P2             2        CAP_0805LF-22UF,4V,20%,X6S,C95A
GND                      C5P3             2        CAP_0805-47UF,4V,20%,X6S,C9533A
GND                      C5P4             2        CAP_0805-47UF,4V,20%,X6S,C9533A
GND                      C5P5             2        CAP_0805-47UF,4V,20%,X6S,C9533A
GND                      C5P6             2        CAP_0805-47UF,4V,20%,X6S,C9533A
GND                      C5P7             2        CAP_0805LF-22UF,4V,20%,X6S,C95A
GND                      C5P8             2        CAP_0805LF-22UF,4V,20%,X6S,C95A
GND                      C5P9             2        CAP_0805LF-22UF,4V,20%,X6S,C95A
GND                      C5P10            2        CAP_0805-47UF,4V,20%,X6S,C9533A
GND                      C5P11            2        CAP_0805-47UF,4V,20%,X6S,C9533A
GND                      C5P12            2        CAP_0805-47UF,4V,20%,X6S,C9533A
GND                      C5P13            2        CAP_0805-47UF,4V,20%,X6S,C9533A
GND                      C5P14            2        CAP_0805-47UF,4V,20%,X6S,C9533A
GND                      C5P15            2        CAP_0805-47UF,4V,20%,X6S,C9533A
GND                      C5P16            2        CAP_0805-47UF,4V,20%,X6S,C9533A
GND                      C5P17            2        CAP_0805-47UF,4V,20%,X6S,C9533A
GND                      C5P18            2        CAP_0805-47UF,4V,20%,X6S,C9533A
GND                      C5P19            2        CAP_0805-47UF,4V,20%,X6S,C9533A
GND                      C5P20            2        CAP_0805-47UF,4V,20%,X6S,C9533A
GND                      C5P21            2        CAP_0805-47UF,4V,20%,X6S,C9533A
GND                      C5P22            2        CAP_0805-47UF,4V,20%,X6S,C9533A
GND                      C5P23            2        CAP_0805-47UF,4V,20%,X6S,C9533A
GND                      C5P24            2        CAP_0805-47UF,4V,20%,X6S,C9533A
GND                      C5P25            2        CAP_0805-47UF,4V,20%,X6S,C9533A
GND                      C5P26            2        CAP_0805-47UF,4V,20%,X6S,C9533A
GND                      C5P27            2        CAP_0805-47UF,4V,20%,X6S,C9533A
GND                      C5P28            2        CAP_0805-47UF,4V,20%,X6S,C9533A
GND                      C5P29            2        CAP_0805-47UF,4V,20%,X6S,C9533A
GND                      C5P30            2        CAP_0805-47UF,4V,20%,X6S,C9533A
GND                      C5P31            2        CAP_0805-47UF,4V,20%,X6S,C9533A
GND                      C5P32            2        CAP_0805-47UF,4V,20%,X6S,C9533A
GND                      C5P33            2        CAP_0805-47UF,4V,20%,X6S,C9533A
GND                      C5P34            2        CAP_0805-47UF,4V,20%,X6S,C9533A
GND                      C5P35            2        CAP_0805-47UF,4V,20%,X6S,C9533A
GND                      C5P36            2        CAP_0805-47UF,4V,20%,X6S,C9533A
GND                      C5P37            2        CAP_0805-47UF,4V,20%,X6S,C9533A
GND                      C5P38            2        CAP_0805LF-22UF,4V,20%,X6S,C95A
GND                      C5P39            2        CAP_0805LF-22UF,4V,20%,X6S,C95A
GND                      C5P40            2        CAP_0805-47UF,4V,20%,X6S,C9533A
GND                      C5P41            2        CAP_0805-47UF,4V,20%,X6S,C9533A
GND                      C5P42            2        CAP_0805-47UF,4V,20%,X6S,C9533A
GND                      C5P43            2        CAP_0805-47UF,4V,20%,X6S,C9533A
GND                      C5P44            2        CAP_0805-47UF,4V,20%,X6S,C9533A
GND                      C5T1             2        CAP_A_0603V-47UF,4V,20%,X5R,60A
GND                      C5T2             2        CAP_A_0603V-47UF,4V,20%,X5R,60A
GND                      C5T3             2        CAP_A_0603V-47UF,4V,20%,X5R,60A
GND                      C5T4             2        CAP_A_0603V-47UF,4V,20%,X5R,60A
GND                      C5T5             2        CAP_A_0603V-22.0UF,4V,20%,X6S,A
GND                      C5T6             2        CAP_A_0603V-22.0UF,4V,20%,X6S,A
GND                      C5T7             2        CAP_A_0603V-22.0UF,4V,20%,X6S,A
GND                      C5T8             2        CAP_A_0603V-22.0UF,4V,20%,X6S,A
GND                      C5T9             2        CAP_A_0603V-22.0UF,4V,20%,X6S,A
GND                      C5T10            2        CAP_A_0603V-22.0UF,4V,20%,X6S,A
GND                      C5T11            2        CAP_A_0603V-22.0UF,4V,20%,X6S,A
GND                      C5T12            2        CAP_A_0603V-22.0UF,4V,20%,X6S,A
GND                      C5T13            2        CAP_A_0603V-47UF,4V,20%,X5R,60A
GND                      C5U1             2        CAP_0805-100UF,4V,20%,X5R,6024A
GND                      C5U2             2        CAP_A_0603V-22.0UF,4V,20%,X6S,A
GND                      C5U3             2        CAP_A_0603V-22.0UF,4V,20%,X6S,A
GND                      C5U4             2        CAP_A_0603V-22.0UF,4V,20%,X6S,A
GND                      C5U5             2        CAP_A_0603V-22.0UF,4V,20%,X6S,A
GND                      C5U6             2        CAP_A_0603V-22.0UF,4V,20%,X6S,A
GND                      C5U7             2        CAP_A_0603V-22.0UF,4V,20%,X6S,A
GND                      C5U8             2        CAP_A_0603V-22.0UF,4V,20%,X6S,A
GND                      C5U9             2        CAP_A_0603V-22.0UF,4V,20%,X6S,A
GND                      C5U10            2        CAP_0805-100UF,4V,20%,X5R,6024A
GND                      C5U11            2        CAP_A_0603V-47UF,4V,20%,X5R,60A
GND                      C5U12            2        CAP_A_0603V-47UF,4V,20%,X5R,60A
GND                      C5U13            2        CAP_0805-100UF,4V,20%,X5R,6024A
GND                      C5U14            2        CAP_0805-100UF,4V,20%,X5R,6024A
GND                      C5U15            2        CAP_0805-100UF,4V,20%,X5R,6024A
GND                      C5U16            2        CAP_A_0603V-47UF,4V,20%,X5R,60A
GND                      C6A1             2        CAP_0805LF-22UF,4V,20%,X6S,C95A
GND                      C6A2             2        CAP_0603LF-10UF,4V,20%,X6S,E15A
GND                      C6A3             2        CAP_0603LF-10UF,4V,20%,X6S,E15A
GND                      C6A4             2        CAP_0805LF-22UF,4V,20%,X6S,C95A
GND                      C6A5             2        CAPP_3018-470UF,2.5V,20%,ALUM,A
GND                      C6A6             2        CAP_0603LF-10UF,4V,20%,X6S,E15A
GND                      C6A7             2        CAP_0603LF-10UF,4V,20%,X6S,E15A
GND                      C6B1             2        CAP_0603LF-10UF,4V,20%,X6S,E15A
GND                      C6B2             2        CAP_0603LF-10UF,4V,20%,X6S,E15A
GND                      C6B3             2        CAP_0805-47UF,4V,20%,X6S,C9533A
GND                      C6B7             2        CAPP_7343LF-330UF,6.3V,20%,POSA
GND                      C6D1             2        CAP_0603LF-10UF,4V,20%,X6S,E15A
GND                      C6D2             2        CAP_A_0603V-22.0UF,4V,20%,X6S,A
GND                      C6D3             2        CAP_A_0603V-22.0UF,4V,20%,X6S,A
GND                      C6D4             2        CAP_A_0603V-22.0UF,4V,20%,X6S,A
GND                      C6D5             2        CAP_A_0603V-22.0UF,4V,20%,X6S,A
GND                      C6D6             2        CAP_A_0603V-22.0UF,4V,20%,X6S,A
GND                      C6D7             2        CAP_A_0603V-22.0UF,4V,20%,X6S,A
GND                      C6D8             2        CAP_A_0603V-22.0UF,4V,20%,X6S,A
GND                      C6D9             2        CAP_A_0603V-22.0UF,4V,20%,X6S,A
GND                      C6D10            2        CAP_A_0603V-22.0UF,4V,20%,X6S,A
GND                      C6F1             2        CAP_A_0402V-0.1UF,16V,10%,X7R,A
GND                      C6F2             2        CAP_A_0402V-0.1UF,16V,10%,X7R,A
GND                      C6F3             2        CAP_A_0402V-0.1UF,16V,10%,X7R,A
GND                      C6F4             2        CAPP_7343LF-330UF,6.3V,20%,POSA
GND                      C6F5             2        CAP_0603LF-10UF,4V,20%,X6S,E15A
GND                      C6F6             2        CAP_0603LF-10UF,4V,20%,X6S,E15A
GND                      C6G1             2        CAP_0603LF-10UF,4V,20%,X6S,E15A
GND                      C6G2             2        CAP_0603LF-10UF,4V,20%,X6S,E15A
GND                      C6G3             2        CAP_0805LF-22UF,4V,20%,X6S,C95A
GND                      C6G4             2        CAP_0603LF-10UF,4V,20%,X6S,E15A
GND                      C6G5             2        CAP_0603LF-10UF,4V,20%,X6S,E15A
GND                      C6L1             2        CAP_A_0402V-0.01UF,25V,10%,X7RA
GND                      C6L2             2        CAP_A_0402V-0.01UF,25V,10%,X7RA
GND                      C6L3             2        CAP_0603LF-10UF,4V,20%,X6S,E15A
GND                      C6L4             2        CAP_0603LF-10UF,4V,20%,X6S,E15A
GND                      C6L5             2        CAP_0603LF-10UF,4V,20%,X6S,E15A
GND                      C6L6             2        CAP_A_0402V-0.01UF,25V,10%,X7RA
GND                      C6L7             2        CAP_A_0402V-0.01UF,25V,10%,X7RA
GND                      C6L8             2        CAPP_7343-220UF,4V,20%,POSCAP,A
GND                      C6L10            2        CAP_0805-10UF,16V,10%,X6S,C953A
GND                      C6L11            2        CAP_0402-1.0UF,16V,10%,X6S,D97A
GND                      C6M1             2        CAP_A_0402V-0.01UF,25V,10%,X7RA
GND                      C6M2             2        CAP_A_0402V-0.01UF,25V,10%,X7RA
GND                      C6M3             2        CAP_0805-10UF,16V,10%,X6S,C953A
GND                      C6M5             2        CAP_0805-10UF,16V,10%,X6S,C953A
GND                      C6M6             2        CAP_A_0402V-0.1UF,16V,10%,X7R,A
GND                      C6N1             2        CAPP_3018-470UF,2.5V,20%,ALUM,A
GND                      C6N2             2        CAP_0805-10UF,16V,10%,X6S,C953A
GND                      C6N3             2        CAP_0805-10UF,16V,10%,X6S,C953A
GND                      C6N4             2        CAPP_3018-470UF,2.5V,20%,ALUM,A
GND                      C6N5             2        CAPP_3018-68UF,16V,20%,TANT,72A
GND                      C6N6             2        CAP_0805-10UF,16V,10%,X6S,C953A
GND                      C6N7             2        CAP_A_0603V-22.0UF,4V,20%,X6S,A
GND                      C6N8             2        CAP_0805-10UF,16V,10%,X6S,C953A
GND                      C6N9             2        CAPP_3018-470UF,2.5V,20%,ALUM,A
GND                      C6N10            2        CAP_0805-10UF,16V,10%,X6S,C953A
GND                      C6N11            2        CAP_0805-10UF,16V,10%,X6S,C953A
GND                      C6P3             2        CAP_A_0603V-22.0UF,4V,20%,X6S,A
GND                      C6P4             2        CAP_A_0402V-0.1UF,16V,10%,X7R,A
GND                      C6P5             2        CAP_A_0402V-0.1UF,16V,10%,X7R,A
GND                      C6P6             2        CAP_A_0402V-0.1UF,16V,10%,X7R,A
GND                      C6P7             2        CAP_0805-10UF,16V,10%,X6S,C953A
GND                      C6P8             2        CAPP_3018-470UF,2.5V,20%,ALUM,A
GND                      C6P9             2        CAP_A_0402V-0.1UF,16V,10%,X7R,A
GND                      C6P10            2        CAP_A_0402V-0.1UF,16V,10%,X7R,A
GND                      C6P11            2        CAP_A_0402V-0.1UF,16V,10%,X7R,A
GND                      C6P12            2        CAP_A_0402V-0.1UF,16V,10%,X7R,A
GND                      C6P13            2        CAP_0805-10UF,16V,10%,X6S,C953A
GND                      C6P14            2        CAPP_3018-470UF,2.5V,20%,ALUM,A
GND                      C6P15            2        CAP_0805-10UF,16V,10%,X6S,C953A
GND                      C6P16            2        CAP_A_0603V-22.0UF,4V,20%,X6S,A
GND                      C6P17            2        CAP_0805-10UF,16V,10%,X6S,C953A
GND                      C6P18            2        CAPP_3018-470UF,2.5V,20%,ALUM,A
GND                      C6P19            2        CAP_0805-10UF,16V,10%,X6S,C953A
GND                      C6P20            2        CAP_0805-10UF,16V,10%,X6S,C953A
GND                      C6P21            2        CAP_A_0603V-22.0UF,4V,20%,X6S,A
GND                      C6P22            2        CAP_0805-10UF,16V,10%,X6S,C953A
GND                      C6P23            2        CAPP_3018-470UF,2.5V,20%,ALUM,A
GND                      C6P24            2        CAP_0805-10UF,16V,10%,X6S,C953A
GND                      C6R2             2        CAP_A_0603V-22.0UF,4V,20%,X6S,A
GND                      C6R3             2        CAPP_3018-470UF,2.5V,20%,ALUM,A
GND                      C6R4             2        CAP_0805-10UF,16V,10%,X6S,C953A
GND                      C6R5             2        CAPP_3018-470UF,2.5V,20%,ALUM,A
GND                      C6R6             2        CAP_0805-10UF,16V,10%,X6S,C953A
GND                      C6R7             2        CAP_A_0603V-22.0UF,4V,20%,X6S,A
GND                      C6R8             2        CAP_0805-10UF,16V,10%,X6S,C953A
GND                      C6R9             2        CAPP_3018-470UF,2.5V,20%,ALUM,A
GND                      C6R10            2        CAP_0805-10UF,16V,10%,X6S,C953A
GND                      C6R11            2        CAP_0805-10UF,16V,10%,X6S,C953A
GND                      C6R12            2        CAPP_3018-470UF,2.5V,20%,ALUM,A
GND                      C6R13            2        CAP_0805-10UF,16V,10%,X6S,C953A
GND                      C6R14            2        CAP_0805-10UF,16V,10%,X6S,C953A
GND                      C6R16            2        CAPP_3018-470UF,2.5V,20%,ALUM,A
GND                      C6T1             2        CAP_A_0402V-0.01UF,25V,10%,X7RA
GND                      C6T2             2        CAP_0805-10UF,16V,10%,X7R,G106A
GND                      C6U2             2        CAP_0805-47UF,4V,20%,X6S,C9533A
GND                      C6U3             2        CAP_0805-47UF,4V,20%,X6S,C9533A
GND                      C6U4             2        CAP_0805-10UF,16V,10%,X6S,C953A
GND                      C6U5             2        CAP_A_0402V-0.1UF,16V,10%,X7R,A
GND                      C6U7             2        CAP_0805-10UF,16V,10%,X6S,C953A
GND                      C6U8             2        CAP_0805-10UF,16V,10%,X6S,C953A
GND                      C6U9             2        CAP_A_0402V-0.01UF,25V,10%,X7RA
GND                      C6U10            2        CAP_0805-10UF,16V,10%,X7R,G106A
GND                      C6U11            2        CAP_0603-4.7UF,6.3V,10%,X6S,E1A
GND                      C6U12            2        CAP_0603-4.7UF,6.3V,10%,X6S,E1A
GND                      C6U13            2        CAP_0603LF-10UF,4V,20%,X6S,E15A
GND                      C6U14            2        CAP_0603LF-10UF,4V,20%,X6S,E15A
GND                      C6U15            2        CAP_0603LF-10UF,4V,20%,X6S,E15A
GND                      C6U16            2        CAP_0603LF-10UF,4V,20%,X6S,E15A
GND                      C6U17            2        CAP_A_0402V-0.01UF,25V,10%,X7RA
GND                      C6U18            2        CAP_0805-10UF,16V,10%,X7R,G106A
GND                      C7A5             2        CAP_A_0402V-0.1UF,16V,10%,X7R,A
GND                      C7A6             2        CAP_0402-1.0UF,16V,10%,X6S,D97A
GND                      C7A7             2        CAP_0402-1.0UF,16V,10%,X6S,D97A
GND                      C7A8             2        CAP_0402-0.22UF,16V,10%,X7R,A3A
GND                      C7A9             2        CAP_0402-1.0UF,16V,10%,X6S,D97A
GND                      C7A10            2        CAP_0402-1.0UF,16V,10%,X6S,D97A
GND                      C7A11            2        CAP_0402-1.0UF,16V,10%,X6S,D97A
GND                      C7A13            2        CAP_1210-100UF,16V,20%,X5R,644A
GND                      C7A14            2        CAP_1210-100UF,16V,20%,X5R,644A
GND                      C7A16            2        CAP_0402-1.0UF,16V,10%,X6S,D97A
GND                      C7A17            2        CAP_0402-0.22UF,16V,10%,X7R,A3A
GND                      C7A18            2        CAP_A_0402V-1.0UF,6.3V,10%,X6SA
GND                      C7A19            2        CAPP_2626-270UF,16V,20%,OSCON,A
GND                      C7A20            2        CAP_A_0402V-0.1UF,16V,10%,X7R,A
GND                      C7A21            2        CAP_0402-1.0UF,16V,10%,X6S,D97A
GND                      C7A24            2        CAP_0402-1.0UF,16V,10%,X6S,D97A
GND                      C7A25            2        CAP_0402-0.22UF,16V,10%,X7R,A3A
GND                      C7A26            2        CAP_A_0402V-1.0UF,6.3V,10%,X6SA
GND                      C7A27            2        CAPP_SM-470UF,2V,20%,ALUM,6990A
GND                      C7A29            2        CAP_0402LF-220PF,50V,10%,X7R,AA
GND                      C7A30            2        CAP_0805LF-22UF,4V,20%,X6S,C95A
GND                      C7A31            2        CAP_0805-47UF,4V,20%,X6S,C9533A
GND                      C7A32            2        CAP_0805-47UF,4V,20%,X6S,C9533A
GND                      C7A33            2        CAP_0805-47UF,4V,20%,X6S,C9533A
GND                      C7A35            2        CAP_0402LF-1000PF,50V,10%,X7R,A
GND                      C7A36            2        CAP_A_0603V-22.0UF,4V,20%,X6S,A
GND                      C7A37            2        CAP_A_0402V-1.0UF,6.3V,10%,X6SA
GND                      C7A38            2        CAP_A_0402V-0.1UF,16V,10%,X7R,A
GND                      C7A39            2        CAP_A_0402V-0.1UF,16V,10%,X7R,A
GND                      C7A40            2        CAP_A_0402V-0.1UF,16V,10%,X7R,A
GND                      C7A41            2        CAP_0402-0.22UF,16V,10%,X7R,A3A
GND                      C7A42            2        CAP_0805LF-22UF,4V,20%,X6S,C95A
GND                      C7B1             2        CAP_A_0402V-1.0UF,6.3V,10%,X6SA
GND                      C7B2             2        CAP_A_0402V-0.1UF,16V,10%,X7R,A
GND                      C7B3             2        CAP_0402LF-1000PF,50V,10%,X7R,A
GND                      C7B4             2        CAP_0805-47UF,4V,20%,X6S,C9533A
GND                      C7B5             2        CAP_0805-10UF,16V,10%,X6S,C953A
GND                      C7B6             2        CAP_A_0402V-0.1UF,16V,10%,X7R,A
GND                      C7B7             2        CAP_0805-47UF,4V,20%,X6S,C9533A
GND                      C7B8             2        CAP_1210-47UF,16V,20%,X6S,D384A
GND                      C7B12            2        CAP_0402LF-1000PF,50V,10%,X7R,A
GND                      C7B15            2        CAP_A_0603V-22.0UF,4V,20%,X6S,A
GND                      C7B16            2        CAP_A_0603V-22.0UF,4V,20%,X6S,A
GND                      C7B17            2        CAP_A_0603V-22.0UF,4V,20%,X6S,A
GND                      C7B18            2        CAP_A_0603V-22.0UF,4V,20%,X6S,A
GND                      C7B19            2        CAP_A_0603V-22.0UF,4V,20%,X6S,A
GND                      C7B20            2        CAP_A_0603V-22.0UF,4V,20%,X6S,A
GND                      C7B21            2        CAP_A_0603V-22.0UF,4V,20%,X6S,A
GND                      C7B22            2        CAP_A_0603V-22.0UF,4V,20%,X6S,A
GND                      C7B23            2        CAP_A_0603V-22.0UF,4V,20%,X6S,A
GND                      C7B24            2        CAP_A_0603V-22.0UF,4V,20%,X6S,A
GND                      C7C4             2        CAP_0402LF-15.0PF,50V,5%,COG,AA
GND                      C7C5             2        CAP_0402LF-15.0PF,50V,5%,COG,AA
GND                      C7C6             2        CAP_A_0603V-22.0UF,4V,20%,X6S,A
GND                      C7C7             2        CAP_1210-100UF,16V,20%,X5R,644A
GND                      C7C8             2        CAP_1210-100UF,16V,20%,X5R,644A
GND                      C7C9             2        CAP_A_0603V-22.0UF,4V,20%,X6S,A
GND                      C7C10            2        CAP_A_0603V-22.0UF,4V,20%,X6S,A
GND                      C7C11            2        CAP_A_0402V-0.1UF,16V,10%,X7R,A
GND                      C7C12            2        CAP_0402-1.0UF,16V,10%,X6S,D97A
GND                      C7C13            2        CAP_0402LF-18PF,50V,5%,C0G,A36A
GND                      C7C15            2        CAP_0402LF-18PF,50V,5%,C0G,A36A
GND                      C7C17            2        CAP_0402-1.0UF,16V,10%,X6S,D97A
GND                      C7C18            2        CAP_0402-0.22UF,16V,10%,X7R,A3A
GND                      C7C19            2        CAP_A_0402V-1.0UF,6.3V,10%,X6SA
GND                      C7C20            2        CAP_A_0402V-1.0UF,6.3V,10%,X6SA
GND                      C7D1             2        CAP_A_0402V-0.1UF,16V,10%,X7R,A
GND                      C7D2             2        CAP_0603-10UF,6.3V,20%,X6S,E15A
GND                      C7D3             2        CAP_A_0603V-22.0UF,4V,20%,X6S,A
GND                      C7D4             2        CAP_0402-1.0UF,16V,10%,X6S,D97A
GND                      C7D5             2        CAP_A_0402V-0.1UF,16V,10%,X7R,A
GND                      C7E1             2        CAP_A_0402V-0.1UF,16V,10%,X7R,A
GND                      C7E2             2        CAP_A_0402V-0.1UF,16V,10%,X7R,A
GND                      C7E3             2        CAP_A_0402V-0.1UF,16V,10%,X7R,A
GND                      C7E4             2        CAP_A_0402V-0.1UF,16V,10%,X7R,A
GND                      C7E5             2        CAP_A_0402V-0.1UF,16V,10%,X7R,A
GND                      C7E6             2        CAP_0805-10UF,16V,10%,X6S,C953A
GND                      C7E8             2        CAP_0805-10UF,16V,10%,X6S,C953A
GND                      C7E9             2        CAP_A_0402V-0.1UF,16V,10%,X7R,A
GND                      C7E10            2        CAP_0402LF-1000PF,50V,10%,X7R,A
GND                      C7E11            2        CAP_1206LF-22UF,16V,10%,X6S,D3A
GND                      C7E12            2        CAP_1210-47UF,16V,20%,X6S,D384A
GND                      C7E13            2        CAP_1210-47UF,16V,20%,X6S,D384A
GND                      C7E14            2        CAP_0402-1.0UF,16V,10%,X6S,D97A
GND                      C7F1             2        CAP_A_0402V-0.01UF,25V,10%,X7RA
GND                      C7F2             2        CAP_A_0402V-1.0UF,6.3V,10%,X6SA
GND                      C7F5             2        CAP_0805-10UF,16V,10%,X6S,C953A
GND                      C7F6             2        CAP_A_0402V-0.1UF,16V,10%,X7R,A
GND                      C7F7             2        CAP_1210-47UF,16V,20%,X6S,D384A
GND                      C7F11            2        CAP_0402LF-1000PF,50V,10%,X7R,A
GND                      C7F14            2        CAP_0402LF-1000PF,50V,10%,X7R,A
GND                      C7F15            2        CAP_A_0402V-0.1UF,16V,10%,X7R,A
GND                      C7F16            2        CAP_A_0402V-1.0UF,6.3V,10%,X6SA
GND                      C7F17            2        CAP_A_0402V-0.1UF,16V,10%,X7R,A
GND                      C7F18            2        CAP_A_0402V-1.0UF,6.3V,10%,X6SA
GND                      C7G1             2        CAP_0402LF-1000PF,50V,10%,X7R,A
GND                      C7G2             2        CAPP_2626-270UF,16V,20%,OSCON,A
GND                      C7G3             2        CAP_0402LF-220PF,50V,10%,X7R,AA
GND                      C7G27            2        CAP_0805LF-22UF,4V,20%,X6S,C95A
GND                      C7G28            2        CAPP_3018-470UF,2.5V,20%,ALUM,A
GND                      C7G29            2        CAP_A_0402V-0.1UF,16V,10%,X7R,A
GND                      C7G30            2        CAP_0402-1.0UF,16V,10%,X6S,D97A
GND                      C7G33            2        CAP_0402-1.0UF,16V,10%,X6S,D97A
GND                      C7G34            2        CAP_0402-0.22UF,16V,10%,X7R,A3A
GND                      C7G35            2        CAP_A_0402V-1.0UF,6.3V,10%,X6SA
GND                      C7G36            2        CAP_A_0402V-0.1UF,16V,10%,X7R,A
GND                      C7G37            2        CAP_0402-1.0UF,16V,10%,X6S,D97A
GND                      C7G40            2        CAP_0402-1.0UF,16V,10%,X6S,D97A
GND                      C7G41            2        CAP_0402-0.22UF,16V,10%,X7R,A3A
GND                      C7G42            2        CAP_A_0402V-1.0UF,6.3V,10%,X6SA
GND                      C7L1             2        CAP_0805-100UF,4V,20%,X5R,6024A
GND                      C7L2             2        CAP_0603LF-10UF,4V,20%,X6S,E15A
GND                      C7L3             2        CAP_0603LF-10UF,4V,20%,X6S,E15A
GND                      C7L4             2        CAP_A_0603V-22.0UF,4V,20%,X6S,A
GND                      C7L5             2        CAP_A_0603V-22.0UF,4V,20%,X6S,A
GND                      C7L6             2        CAP_0603LF-10UF,4V,20%,X6S,E15A
GND                      C7L7             2        CAP_0603LF-10UF,4V,20%,X6S,E15A
GND                      C7M1             2        CAP_A_0603V-22.0UF,4V,20%,X6S,A
GND                      C7M2             2        CAP_A_0603V-22.0UF,4V,20%,X6S,A
GND                      C7M3             2        CAP_0603LF-10UF,4V,20%,X6S,E15A
GND                      C7M4             2        CAP_0603LF-10UF,4V,20%,X6S,E15A
GND                      C7M5             2        CAP_A_0603V-47UF,4V,20%,X5R,60A
GND                      C7M6             2        CAPP_3018-68UF,16V,20%,TANT,72A
GND                      C7P1             2        CAP_0805-47UF,4V,20%,X6S,C9533A
GND                      C7P2             2        CAP_0805-47UF,4V,20%,X6S,C9533A
GND                      C7P3             2        CAP_0805-47UF,4V,20%,X6S,C9533A
GND                      C7P4             2        CAP_0805-47UF,4V,20%,X6S,C9533A
GND                      C7P5             2        CAP_0805-47UF,4V,20%,X6S,C9533A
GND                      C7P6             2        CAP_0805-47UF,4V,20%,X6S,C9533A
GND                      C7P7             2        CAP_0805-47UF,4V,20%,X6S,C9533A
GND                      C7P8             2        CAP_0805-47UF,4V,20%,X6S,C9533A
GND                      C7P9             2        CAP_0805-47UF,4V,20%,X6S,C9533A
GND                      C7P10            2        CAP_0805-47UF,4V,20%,X6S,C9533A
GND                      C7P11            2        CAP_0805-47UF,4V,20%,X6S,C9533A
GND                      C7P12            2        CAP_A_0603V-22.0UF,4V,20%,X6S,A
GND                      C7P13            2        CAP_0805-47UF,4V,20%,X6S,C9533A
GND                      C7P14            2        CAP_0805-47UF,4V,20%,X6S,C9533A
GND                      C7P15            2        CAP_0805-47UF,4V,20%,X6S,C9533A
GND                      C7P16            2        CAP_A_0603V-22.0UF,4V,20%,X6S,A
GND                      C7P17            2        CAP_0805-47UF,4V,20%,X6S,C9533A
GND                      C7P18            2        CAP_0805-47UF,4V,20%,X6S,C9533A
GND                      C7P19            2        CAP_0805-47UF,4V,20%,X6S,C9533A
GND                      C7P20            2        CAP_0805-47UF,4V,20%,X6S,C9533A
GND                      C7R1             2        CAP_A_0603V-22.0UF,4V,20%,X6S,A
GND                      C7T1             2        CAP_0805-100UF,4V,20%,X5R,6024A
GND                      C7T2             2        CAP_0603LF-10UF,4V,20%,X6S,E15A
GND                      C7T3             2        CAP_0603LF-10UF,4V,20%,X6S,E15A
GND                      C7T4             2        CAP_A_0603V-22.0UF,4V,20%,X6S,A
GND                      C7T5             2        CAP_A_0603V-22.0UF,4V,20%,X6S,A
GND                      C7U1             2        CAP_A_0603V-22.0UF,4V,20%,X6S,A
GND                      C7U2             2        CAP_A_0603V-22.0UF,4V,20%,X6S,A
GND                      C7U3             2        CAP_0603LF-10UF,4V,20%,X6S,E15A
GND                      C7U4             2        CAP_0603LF-10UF,4V,20%,X6S,E15A
GND                      C7U5             2        CAP_0603LF-10UF,4V,20%,X6S,E15A
GND                      C7U6             2        CAP_0603LF-10UF,4V,20%,X6S,E15A
GND                      C7U7             2        CAP_0805-100UF,4V,20%,X5R,6024A
GND                      C8A3             2        CAP_0402LF-1000PF,50V,10%,X7R,A
GND                      C8A4             2        CAP_0603LF-0.1UF,25V,10%,X7R,6A
GND                      C8A6             2        CAP_0603-10UF,6.3V,20%,X6S,E15A
GND                      C8A7             2        CAP_A_0402V-1.0UF,6.3V,10%,X6SA
GND                      C8A8             2        CAP_A_0402V-0.1UF,16V,10%,X7R,A
GND                      C8A9             2        CAP_0402LF-1000PF,50V,10%,X7R,A
GND                      C8A10            2        CAP_0402LF-1000PF,50V,10%,EMPTA
GND                      C8A11            2        CAP_0402LF-1000PF,50V,10%,X7R,A
GND                      C8A12            2        CAP_0805-47UF,4V,20%,X6S,C9533A
GND                      C8A13            2        CAP_0805-47UF,4V,20%,X6S,C9533A
GND                      C8A14            2        CAP_0805-22UF,6.3V,20%,X6S,C95A
GND                      C8A15            2        CAPP_SM-470UF,2V,20%,ALUM,6990A
GND                      C8B1             2        CAP_A_0603V-22.0UF,4V,20%,X6S,A
GND                      C8B2             2        CAP_A_0603V-22.0UF,4V,20%,X6S,A
GND                      C8B3             2        CAP_A_0603V-22.0UF,4V,20%,X6S,A
GND                      C8B4             2        CAP_A_0603V-22.0UF,4V,20%,X6S,A
GND                      C8B5             2        CAP_A_0402V-0.1UF,16V,10%,X7R,A
GND                      C8B6             2        CAP_0805-10UF,16V,10%,X6S,C953A
GND                      C8B7             2        CAP_A_0402V-0.1UF,16V,10%,X7R,A
GND                      C8B8             2        CAP_A_0402V-0.1UF,16V,10%,X7R,A
GND                      C8B9             2        CAP_A_0603V-22.0UF,4V,20%,X6S,A
GND                      C8B10            2        CAP_A_0603V-22.0UF,4V,20%,X6S,A
GND                      C8B11            2        CAP_A_0603V-22.0UF,4V,20%,X6S,A
GND                      C8B12            2        CAP_0805-10UF,16V,10%,X6S,C953A
GND                      C8B13            2        CAP_A_0603V-22.0UF,4V,20%,X6S,A
GND                      C8B14            2        CAP_A_0603V-22.0UF,4V,20%,X6S,A
GND                      C8B15            2        CAP_0805-47UF,4V,20%,X6S,C9533A
GND                      C8B16            2        CAP_0805-47UF,4V,20%,X6S,C9533A
GND                      C8C1             2        CAP_0402LF-33.0PF,50V,5%,COG,AA
GND                      C8C2             2        CAP_0402LF-33.0PF,50V,5%,COG,AA
GND                      C8C3             2        CAP_0603-10UF,6.3V,20%,X6S,E15A
GND                      C8C4             2        CAP_0603-10UF,6.3V,20%,X6S,E15A
GND                      C8C5             2        CAP_0603-10UF,6.3V,20%,X6S,E15A
GND                      C8C6             2        CAP_0603-10UF,6.3V,20%,X6S,E15A
GND                      C8D1             2        CAP_A_0402V-0.1UF,16V,10%,X7R,A
GND                      C8D2             2        CAP_A_0402V-0.1UF,16V,10%,X7R,A
GND                      C8D3             2        CAP_0402LF-470PF,50V,10%,EMPTYA
GND                      C8D4             2        CAP_A_0402V-0.1UF,16V,10%,X7R,A
GND                      C8E1             2        CAP_A_0402V-0.1UF,16V,10%,X7R,A
GND                      C8E2             2        CAP_A_0402V-0.1UF,16V,10%,X7R,A
GND                      C8E3             2        CAP_A_0402V-0.1UF,16V,10%,X7R,A
GND                      C8E4             2        CAPP_3018-470UF,6.3V,20%,POSCAA
GND                      C8E5             2        CAP_A_0402V-0.1UF,16V,10%,X7R,A
GND                      C8E7             2        CAP_0805-22UF,6.3V,20%,X6S,C95A
GND                      C8E8             2        CAP_A_0402V-0.1UF,16V,10%,X7R,A
GND                      C8E9             2        CAP_0805-22UF,6.3V,20%,X6S,C95A
GND                      C8E10            2        CAP_1206LF-22UF,16V,10%,X6S,D3A
GND                      C8E11            2        CAP_1210-47UF,16V,20%,X6S,D384A
GND                      C8E14            2        CAP_0402-1.0UF,16V,10%,X6S,D97A
GND                      C8E18            2        CAP_A_0402V-0.1UF,16V,10%,X7R,A
GND                      C8E19            2        CAP_A_0402V-0.1UF,16V,10%,X7R,A
GND                      C8F2             2        CAP_0402LF-1000PF,50V,10%,X7R,A
GND                      C8F4             2        CAP_A_0402V-1.0UF,6.3V,10%,X6SA
GND                      C8F5             2        CAP_A_0402V-0.01UF,25V,10%,X7RA
GND                      C8F8             2        CAPP_3018-470UF,6.3V,20%,POSCAA
GND                      C8F9             2        CAP_A_0402V-1.0UF,6.3V,10%,EMPA
GND                      C8F10            2        CAP_0603-10UF,6.3V,20%,EMPTY,EA
GND                      C8F14            2        CAPP_3018-470UF,6.3V,20%,POSCAA
GND                      C8F16            2        CAP_A_0402V-0.1UF,16V,10%,X7R,A
GND                      C8F17            2        CAP_A_0402V-0.1UF,16V,10%,X7R,A
GND                      C8F18            2        CAP_0402LF-27.0PF,50V,5%,COG,AA
GND                      C8F19            2        CAP_0402LF-27.0PF,50V,5%,COG,AA
GND                      C8L1             2        CAP_0805-100UF,4V,20%,X5R,6024A
GND                      C8L2             2        CAP_0805-100UF,4V,20%,X5R,6024A
GND                      C8L3             2        CAP_A_0603V-47UF,4V,20%,X5R,60A
GND                      C8L4             2        CAP_A_0603V-47UF,4V,20%,X5R,60A
GND                      C8L5             2        CAP_A_0603V-22.0UF,4V,20%,X6S,A
GND                      C8L6             2        CAP_A_0603V-22.0UF,4V,20%,X6S,A
GND                      C8L7             2        CAP_A_0603V-22.0UF,4V,20%,X6S,A
GND                      C8L8             2        CAP_A_0603V-22.0UF,4V,20%,X6S,A
GND                      C8L9             2        CAP_A_0603V-22.0UF,4V,20%,X6S,A
GND                      C8L10            2        CAP_A_0603V-22.0UF,4V,20%,X6S,A
GND                      C8L11            2        CAP_0805-100UF,4V,20%,X5R,6024A
GND                      C8L12            2        CAP_A_0603V-47UF,4V,20%,X5R,60A
GND                      C8M1             2        CAP_A_0603V-22.0UF,4V,20%,X6S,A
GND                      C8M2             2        CAP_A_0603V-47UF,4V,20%,X5R,60A
GND                      C8M3             2        CAP_A_0603V-22.0UF,4V,20%,X6S,A
GND                      C8M4             2        CAP_A_0603V-22.0UF,4V,20%,X6S,A
GND                      C8M5             2        CAP_A_0603V-22.0UF,4V,20%,X6S,A
GND                      C8M6             2        CAP_A_0603V-22.0UF,4V,20%,X6S,A
GND                      C8M7             2        CAP_0805-100UF,4V,20%,X5R,6024A
GND                      C8M8             2        CAP_A_0603V-47UF,4V,20%,X5R,60A
GND                      C8M9             2        CAP_A_0603V-47UF,4V,20%,X5R,60A
GND                      C8M10            2        CAP_A_0603V-47UF,4V,20%,X5R,60A
GND                      C8M11            2        CAP_0805-100UF,4V,20%,X5R,6024A
GND                      C8M12            2        CAP_A_0603V-47UF,4V,20%,X5R,60A
GND                      C8P1             2        CAP_0805LF-22UF,4V,20%,X6S,C95A
GND                      C8P2             2        CAP_0805LF-22UF,4V,20%,X6S,C95A
GND                      C8P3             2        CAP_0805-47UF,4V,20%,X6S,C9533A
GND                      C8P4             2        CAP_0805-47UF,4V,20%,X6S,C9533A
GND                      C8P5             2        CAP_0805LF-22UF,4V,20%,X6S,C95A
GND                      C8P6             2        CAP_0805LF-22UF,4V,20%,X6S,C95A
GND                      C8P7             2        CAP_0805LF-22UF,4V,20%,X6S,C95A
GND                      C8P8             2        CAP_0805-47UF,4V,20%,X6S,C9533A
GND                      C8P9             2        CAP_0805-47UF,4V,20%,X6S,C9533A
GND                      C8P10            2        CAP_0805-47UF,4V,20%,X6S,C9533A
GND                      C8P11            2        CAP_0805-47UF,4V,20%,X6S,C9533A
GND                      C8P12            2        CAP_0805-47UF,4V,20%,X6S,C9533A
GND                      C8P13            2        CAP_0805-47UF,4V,20%,X6S,C9533A
GND                      C8P14            2        CAP_0805-47UF,4V,20%,X6S,C9533A
GND                      C8P15            2        CAP_0805-47UF,4V,20%,X6S,C9533A
GND                      C8P16            2        CAP_0805-47UF,4V,20%,X6S,C9533A
GND                      C8P17            2        CAP_0805-47UF,4V,20%,X6S,C9533A
GND                      C8P18            2        CAP_0805-47UF,4V,20%,X6S,C9533A
GND                      C8P19            2        CAP_0805-47UF,4V,20%,X6S,C9533A
GND                      C8P20            2        CAP_0805-47UF,4V,20%,X6S,C9533A
GND                      C8P21            2        CAP_0805-47UF,4V,20%,X6S,C9533A
GND                      C8P22            2        CAP_0805-47UF,4V,20%,X6S,C9533A
GND                      C8P23            2        CAP_0805-47UF,4V,20%,X6S,C9533A
GND                      C8P24            2        CAP_0805-47UF,4V,20%,X6S,C9533A
GND                      C8P25            2        CAP_0805-47UF,4V,20%,X6S,C9533A
GND                      C8P26            2        CAP_0805-47UF,4V,20%,X6S,C9533A
GND                      C8P27            2        CAP_0805-47UF,4V,20%,X6S,C9533A
GND                      C8P28            2        CAP_0805-47UF,4V,20%,X6S,C9533A
GND                      C8P29            2        CAP_0805-47UF,4V,20%,X6S,C9533A
GND                      C8P30            2        CAP_0805LF-22UF,4V,20%,X6S,C95A
GND                      C8P31            2        CAP_0805LF-22UF,4V,20%,X6S,C95A
GND                      C8P32            2        CAP_0805-47UF,4V,20%,X6S,C9533A
GND                      C8P33            2        CAP_0805-47UF,4V,20%,X6S,C9533A
GND                      C8P34            2        CAP_0805-47UF,4V,20%,X6S,C9533A
GND                      C8T1             2        CAP_A_0603V-47UF,4V,20%,X5R,60A
GND                      C8T2             2        CAP_A_0603V-47UF,4V,20%,X5R,60A
GND                      C8T3             2        CAP_A_0603V-47UF,4V,20%,X5R,60A
GND                      C8T4             2        CAP_A_0603V-47UF,4V,20%,X5R,60A
GND                      C8T5             2        CAP_A_0603V-22.0UF,4V,20%,X6S,A
GND                      C8T6             2        CAP_A_0603V-22.0UF,4V,20%,X6S,A
GND                      C8T7             2        CAP_A_0603V-22.0UF,4V,20%,X6S,A
GND                      C8T8             2        CAP_A_0603V-22.0UF,4V,20%,X6S,A
GND                      C8T9             2        CAP_A_0603V-22.0UF,4V,20%,X6S,A
GND                      C8T10            2        CAP_A_0603V-22.0UF,4V,20%,X6S,A
GND                      C8T11            2        CAP_A_0603V-47UF,4V,20%,X5R,60A
GND                      C8U1             2        CAP_0805-100UF,4V,20%,X5R,6024A
GND                      C8U2             2        CAP_A_0603V-22.0UF,4V,20%,X6S,A
GND                      C8U3             2        CAP_A_0603V-22.0UF,4V,20%,X6S,A
GND                      C8U4             2        CAP_A_0603V-22.0UF,4V,20%,X6S,A
GND                      C8U5             2        CAP_A_0603V-22.0UF,4V,20%,X6S,A
GND                      C8U6             2        CAP_A_0603V-22.0UF,4V,20%,X6S,A
GND                      C8U7             2        CAP_A_0603V-22.0UF,4V,20%,X6S,A
GND                      C8U8             2        CAP_0805-100UF,4V,20%,X5R,6024A
GND                      C8U9             2        CAP_A_0603V-47UF,4V,20%,X5R,60A
GND                      C8U10            2        CAP_A_0603V-47UF,4V,20%,X5R,60A
GND                      C8U11            2        CAP_0805-100UF,4V,20%,X5R,6024A
GND                      C8U12            2        CAP_0805-100UF,4V,20%,X5R,6024A
GND                      C8U13            2        CAP_A_0603V-47UF,4V,20%,X5R,60A
GND                      C9A1             2        CAP_A_0402V-0.1UF,16V,10%,X7R,A
GND                      C9A2             2        CAP_A_0402V-0.1UF,16V,10%,X7R,A
GND                      C9A3             2        CAP_A_0402V-0.1UF,16V,10%,X7R,A
GND                      C9A4             2        CAP_A_0402V-0.1UF,16V,10%,X7R,A
GND                      C9A5             2        CAP_A_0402V-0.1UF,16V,10%,X7R,A
GND                      C9A6             2        CAP_A_0402V-1.0UF,6.3V,10%,X6SA
GND                      C9B1             2        CAP_0805-10UF,16V,10%,X6S,C953A
GND                      C9B2             2        CAP_0805-10UF,16V,10%,X6S,C953A
GND                      C9B7             2        CAP_A_0402V-0.1UF,16V,10%,X7R,A
GND                      C9B8             2        CAPP_7343HLF-330UF,10V,20%,POSA
GND                      C9B9             2        CAP_A_0402V-1.0UF,6.3V,10%,X6SA
GND                      C9B10            2        CAP_A_0402V-0.1UF,16V,10%,X7R,A
GND                      C9E1             2        CAP_A_0603V-22.0UF,4V,20%,EMPTA
GND                      C9E6             2        CAP_1210-47UF,16V,20%,EMPTY,D3A
GND                      C9E8             2        CAP_0402LF-22.0PF,50V,5%,COG,AA
GND                      C9E9             2        CAP_0402LF-22.0PF,50V,5%,COG,AA
GND                      C9E10            2        CAP_0603-10UF,6.3V,20%,X6S,E15A
GND                      C9E11            2        CAP_0402-1.0UF,16V,10%,X6S,D97A
GND                      C9E12            2        CAP_A_0603V-22.0UF,4V,20%,EMPTA
GND                      C9F1             2        CAP_1210-47UF,16V,20%,X6S,D384A
GND                      C9F2             2        CAP_1210-47UF,16V,20%,EMPTY,D3A
GND                      C9F3             2        CAP_0603-10UF,6.3V,20%,X6S,E15A
GND                      C9F4             2        CAP_0805LF-22UF,4V,20%,X6S,C95A
GND                      C9F5             2        CAP_A_0402V-0.1UF,16V,10%,X7R,A
GND                      C9F6             2        CAP_0402LF-1000PF,50V,10%,EMPTA
GND                      C9F8             2        CAP_0402LF-1000PF,50V,10%,X7R,A
GND                      C9F9             2        CAP_0402LF-1000PF,50V,10%,EMPTA
GND                      C9F10            2        CAP_0402LF-1000PF,50V,10%,X7R,A
GND                      C9F11            2        CAP_A_0402V-0.1UF,16V,10%,X7R,A
GND                      C9F12            2        CAP_A_0402V-1.0UF,6.3V,10%,X6SA
GND                      C9F13            2        CAP_0805LF-22UF,4V,20%,X6S,C95A
GND                      C9F14            2        CAP_A_0402V-0.1UF,16V,10%,X7R,A
GND                      C9F15            2        CAP_A_0402V-0.1UF,16V,10%,EMPTA
GND                      C9F18            2        CAP_0402LF-100.0PF,50V,5%,COG,A
GND                      C9F19            2        CAP_A_0402V-0.1UF,16V,10%,X7R,A
GND                      C9F20            2        CAP_0402LF-12.0PF,50V,5%,COG,AA
GND                      C9F21            2        CAP_0402LF-12.0PF,50V,5%,COG,AA
GND                      C9F22            2        CAP_0402LF-470PF,50V,10%,X7R,AA
GND                      C9F23            2        CAP_A_0402V-0.1UF,16V,10%,X7R,A
GND                      C9G1             2        CAP_0402LF-470PF,50V,10%,X7R,AA
GND                      C9G2             2        CAP_0402LF-470PF,50V,10%,X7R,AA
GND                      C9G3             2        CAP_0402LF-470PF,50V,10%,X7R,AA
GND                      C9G4             2        CAP_A_0402V-0.1UF,16V,10%,X7R,A
GND                      C9G5             2        CAP_0402-1.0UF,16V,10%,X7S,G71A
GND                      C9G6             2        CAP_A_0402V-0.1UF,16V,10%,X7R,A
GND                      C9G7             2        CAP_A_0402V-0.1UF,16V,10%,X7R,A
GND                      C9G10            1        CAP_A_0402V-0.1UF,16V,10%,EMPTA
GND                      C9G14            2        CAP_0402LF-47.0PF,50V,5%,COG,AA
GND                      C9G15            2        CAP_0402LF-47.0PF,50V,5%,COG,AA
GND                      C9G17            2        CAP_0402LF-47.0PF,50V,5%,COG,AA
GND                      C9G18            2        CAP_0402LF-47.0PF,50V,5%,COG,AA
GND                      C9G19            2        CAP_A_0402V-0.1UF,16V,10%,X7R,A
GND                      C9G20            2        CAP_0402LF-47.0PF,50V,5%,COG,AA
GND                      C9G21            2        CAP_0402LF-47.0PF,50V,5%,COG,AA
GND                      C9G22            2        CAP_0402LF-10.0PF,50V,5%,COG,AA
GND                      C9L1             2        CAP_A_0402V-0.01UF,25V,10%,X7RA
GND                      C9L2             2        CAPP_3018-470UF,2.5V,20%,ALUM,A
GND                      C9L3             2        CAP_A_0402V-0.01UF,25V,10%,X7RA
GND                      C9L4             2        CAPP_3018-470UF,2.5V,20%,ALUM,A
GND                      C9L5             2        CAP_0805-10UF,16V,10%,X6S,C953A
GND                      C9L6             2        CAP_0805-10UF,16V,10%,X6S,C953A
GND                      C9L7             2        CAP_A_0402V-0.01UF,25V,10%,X7RA
GND                      C9L8             2        CAP_A_0402V-0.01UF,25V,10%,X7RA
GND                      C9L9             2        CAPP_3018-470UF,2.5V,20%,ALUM,A
GND                      C9L10            2        CAP_0805-10UF,16V,10%,X6S,C953A
GND                      C9L11            2        CAP_0805-10UF,16V,10%,X6S,C953A
GND                      C9L12            2        CAPP_3018-470UF,2.5V,20%,ALUM,A
GND                      C9L13            2        CAP_0805-10UF,16V,10%,X6S,C953A
GND                      C9L14            2        CAP_0805-10UF,16V,10%,X6S,C953A
GND                      C9M1             2        CAP_A_0402V-0.01UF,25V,10%,X7RA
GND                      C9M2             2        CAP_A_0402V-0.01UF,25V,10%,X7RA
GND                      C9M3             2        CAPP_3018-68UF,16V,20%,TANT,72A
GND                      C9M4             2        CAP_0805-10UF,16V,10%,X6S,C953A
GND                      C9M5             2        CAP_A_0402V-0.1UF,16V,10%,X7R,A
GND                      C9M6             2        CAP_A_0402V-0.1UF,16V,10%,X7R,A
GND                      C9M7             2        CAP_A_0402V-0.1UF,16V,10%,X7R,A
GND                      C9M8             2        CAP_A_0402V-0.1UF,16V,10%,X7R,A
GND                      C9M9             2        CAP_A_0402V-0.1UF,16V,10%,X7R,A
GND                      C9M10            2        CAP_0805-10UF,16V,10%,X6S,C953A
GND                      C9M11            2        CAP_A_0402V-0.1UF,16V,10%,X7R,A
GND                      C9N11            2        CAPP_3018-470UF,2.5V,20%,ALUM,A
GND                      C9N13            2        CAP_0805-10UF,16V,10%,X6S,C953A
GND                      C9N19            2        CAP_0805-10UF,16V,10%,X6S,C953A
GND                      C9N20            2        CAPP_3018-470UF,2.5V,20%,ALUM,A
GND                      C9N21            2        CAP_0805-10UF,16V,10%,X6S,C953A
GND                      C9N22            2        CAP_A_0603V-22.0UF,4V,20%,X6S,A
GND                      C9N24            2        CAPP_3018-470UF,2.5V,20%,ALUM,A
GND                      C9N25            2        CAP_0805-10UF,16V,10%,X6S,C953A
GND                      C9N26            2        CAP_0805-10UF,16V,10%,X6S,C953A
GND                      C9N27            2        CAP_0805-10UF,16V,10%,X6S,C953A
GND                      C9P1             2        CAP_0805-10UF,16V,10%,X6S,C953A
GND                      C9P2             2        CAP_0805-10UF,16V,10%,X6S,C953A
GND                      C9P3             2        CAP_A_0603V-22.0UF,4V,20%,X6S,A
GND                      C9P4             2        CAP_0805-10UF,16V,10%,X6S,C953A
GND                      C9P5             2        CAPP_3018-470UF,2.5V,20%,ALUM,A
GND                      C9P7             2        CAP_0805-10UF,16V,10%,X6S,C953A
GND                      C9P8             2        CAPP_3018-470UF,2.5V,20%,ALUM,A
GND                      C9P9             2        CAP_0805-10UF,16V,10%,X6S,C953A
GND                      C9P10            2        CAP_A_0603V-22.0UF,4V,20%,X6S,A
GND                      C9P11            2        CAP_A_0402V-0.1UF,16V,10%,X7R,A
GND                      C9P18            2        CAPP_3018-470UF,2.5V,20%,ALUM,A
GND                      C9P20            2        CAP_A_0603V-22.0UF,4V,20%,X6S,A
GND                      C9P22            2        CAP_0805-10UF,16V,10%,X6S,C953A
GND                      C9P23            2        CAPP_3018-470UF,2.5V,20%,ALUM,A
GND                      C9P24            2        CAP_0805-10UF,16V,10%,X6S,C953A
GND                      C9P25            2        CAP_0805-10UF,16V,10%,X6S,C953A
GND                      C9P26            2        CAP_0805-10UF,16V,10%,X6S,C953A
GND                      C9R2             2        CAP_A_0603V-22.0UF,4V,20%,X6S,A
GND                      C9R3             2        CAPP_3018-470UF,2.5V,20%,ALUM,A
GND                      C9R5             2        CAP_0805-10UF,16V,10%,X6S,C953A
GND                      C9R6             2        CAP_A_0402V-0.1UF,16V,10%,X7R,A
GND                      C9R7             2        CAP_0805-10UF,16V,10%,X6S,C953A
GND                      C9R8             2        CAP_A_0603V-22.0UF,4V,20%,X6S,A
GND                      C9R9             2        CAPP_3018-470UF,2.5V,20%,ALUM,A
GND                      C9R10            2        CAP_0805-10UF,16V,10%,X6S,C953A
GND                      C9R11            2        CAP_0805-10UF,16V,10%,X6S,C953A
GND                      C9R12            2        CAP_A_0402V-0.1UF,16V,10%,X7R,A
GND                      C9R13            2        CAP_A_0402V-0.1UF,16V,10%,X7R,A
GND                      C9R14            2        CAP_A_0402V-0.1UF,16V,10%,X7R,A
GND                      C9T1             2        CAP_A_0402V-0.01UF,25V,10%,X7RA
GND                      C9T3             2        CAPP_3018-68UF,16V,20%,TANT,72A
GND                      C9T4             2        CAP_0805-10UF,16V,10%,X6S,C953A
GND                      C9T5             2        CAPP_3018-470UF,2.5V,20%,ALUM,A
GND                      C9T6             2        CAP_0805-10UF,16V,10%,X6S,C953A
GND                      C9T7             2        CAP_A_0402V-0.01UF,25V,10%,X7RA
GND                      C9T8             2        CAP_0805-10UF,16V,10%,X7R,G106A
GND                      C9T9             2        CAP_0805-10UF,16V,10%,X6S,C953A
GND                      C9U2             2        CAPP_3018-470UF,2.5V,20%,ALUM,A
GND                      C9U3             2        CAP_0805-10UF,16V,10%,X6S,C953A
GND                      C9U4             2        CAP_0805-10UF,16V,10%,X6S,C953A
GND                      C9U5             2        CAPP_3018-470UF,2.5V,20%,ALUM,A
GND                      C9U6             2        CAP_0805-10UF,16V,10%,X6S,C953A
GND                      C9U7             2        CAP_A_0402V-0.01UF,25V,10%,X7RA
GND                      C9U8             2        CAP_0805-10UF,16V,10%,X7R,G106A
GND                      C9U9             2        CAPP_3018-470UF,2.5V,20%,ALUM,A
GND                      C9U10            2        CAP_A_0402V-0.01UF,25V,10%,X7RA
GND                      C9U11            2        CAP_0805-10UF,16V,10%,X7R,G106A
GND                      C9U12            2        CAP_A_0402V-0.1UF,16V,10%,X7R,A
GND                      CR1F5            2        DIODE_SM-MBRS340T3G,EMPTY,C819A
GND                      CR1M1            3        DIODEAC_DUAL_ARRAY_SM9-ESD3V3UA
GND                      CR1M2            3        DIODEAC_DUAL_ARRAY_SM9-ESD3V3UA
GND                      CTI1             2        CAP_A_0402V-0.1UF,16V,10%,X7R,A
GND                      CTI2             2        CAP_0402LF-1000PF,50V,10%,X7R,A
GND                      CTI4             2        CAP_0402LF-1000PF,50V,10%,X7R,A
GND                      CTI6             2        CAP_A_0402V-0.1UF,16V,10%,X7R,A
GND                      CTI7             2        CAP_A_0402V-0.1UF,16V,10%,X7R,A
GND                      CTI8             2        CAP_0402LF-1000PF,50V,10%,X7R,A
GND                      CTI10            2        CAP_0402LF-1000PF,50V,10%,X7R,A
GND                      CTI12            2        CAP_A_0402V-0.1UF,16V,10%,X7R,A
GND                      CTI13            2        CAP_A_0402V-0.1UF,16V,10%,X7R,A
GND                      CTI15            2        CAP_0402LF-1000PF,50V,10%,X7R,A
GND                      CTI16            2        CAP_A_0402V-0.1UF,16V,10%,X7R,A
GND                      CTI17            2        CAP_0402LF-1000PF,50V,10%,X7R,A
GND                      CTI19            2        CAP_0402LF-1000PF,50V,10%,X7R,A
GND                      CTI21            2        CAP_A_0402V-0.1UF,16V,10%,X7R,A
GND                      CTI22            2        CAP_0402LF-1000PF,50V,10%,X7R,A
GND                      CTI24            2        CAP_A_0402V-0.1UF,16V,10%,X7R,A
GND                      CTI25            2        CAP_A_0402V-0.1UF,16V,10%,X7R,A
GND                      CTI26            2        CAP_0402LF-1000PF,50V,10%,X7R,A
GND                      CTI28            2        CAP_0402LF-1000PF,50V,10%,X7R,A
GND                      CTI30            2        CAP_A_0402V-0.1UF,16V,10%,X7R,A
GND                      CTI31            2        CAP_A_0402V-0.1UF,16V,10%,X7R,A
GND                      CTI32            2        CAP_0402LF-1000PF,50V,10%,X7R,A
GND                      CTI34            2        CAP_0402LF-1000PF,50V,10%,X7R,A
GND                      CTI36            2        CAP_A_0402V-0.1UF,16V,10%,X7R,A
GND                      CTI37            2        CAP_0402LF-1000PF,50V,10%,X7R,A
GND                      CTI39            2        CAP_A_0402V-0.1UF,16V,10%,X7R,A
GND                      CTI40            2        CAP_A_0402V-0.1UF,16V,10%,X7R,A
GND                      CTI42            2        CAP_0402LF-1000PF,50V,10%,X7R,A
GND                      CTI43            2        CAP_0402LF-1000PF,50V,10%,X7R,A
GND                      CTI45            2        CAP_A_0402V-0.1UF,16V,10%,X7R,A
GND                      CTI46            2        CAP_A_0402V-0.1UF,16V,10%,X7R,A
GND                      CTI48            2        CAP_0402LF-1000PF,50V,10%,X7R,A
GND                      CTI49            2        CAP_0402LF-1000PF,50V,10%,X7R,A
GND                      CTI51            2        CAP_A_0402V-0.1UF,16V,10%,X7R,A
GND                      CTI52            2        CAP_A_0402V-0.1UF,16V,10%,X7R,A
GND                      CTI54            2        CAP_0402LF-1000PF,50V,10%,X7R,A
GND                      CTI55            2        CAP_0402LF-1000PF,50V,10%,X7R,A
GND                      CTI57            2        CAP_A_0402V-0.1UF,16V,10%,X7R,A
GND                      CTI58            2        CAP_0402LF-1000PF,50V,10%,X7R,A
GND                      CTI60            2        CAP_A_0402V-0.1UF,16V,10%,X7R,A
GND                      CTI61            2        CAP_0402LF-1000PF,50V,10%,X7R,A
GND                      CTI63            2        CAP_A_0402V-0.1UF,16V,10%,X7R,A
GND                      CTI64            2        CAP_0402LF-1000PF,50V,10%,X7R,A
GND                      CTI66            2        CAP_A_0402V-0.1UF,16V,10%,X7R,A
GND                      CTI67            2        CAP_A_0402V-0.1UF,16V,10%,X7R,A
GND                      CTI69            2        CAP_0402LF-1000PF,50V,10%,X7R,A
GND                      CTI70            2        CAP_A_0402V-0.1UF,16V,10%,X7R,A
GND                      CTI71            2        CAP_0402LF-1000PF,50V,10%,X7R,A
GND                      DS9A6            2        LED_A1LF-GREEN,IC,C97278-010
GND                      EU1A1            2        IR354XX_SM-IR35411,IC,H73688-0A
GND                      EU1A1            5        IR354XX_SM-IR35411,IC,H73688-0A
GND                      EU1A1            7        IR354XX_SM-IR35411,IC,H73688-0A
GND                      EU1A1            40       IR354XX_SM-IR35411,IC,H73688-0A
GND                      EU1A2            2        IR354XX_SM-IR35411,IC,H73688-0A
GND                      EU1A2            5        IR354XX_SM-IR35411,IC,H73688-0A
GND                      EU1A2            7        IR354XX_SM-IR35411,IC,H73688-0A
GND                      EU1A2            40       IR354XX_SM-IR35411,IC,H73688-0A
GND                      EU1B1            27       PXM1310B_QFN-IC,H89186-001
GND                      EU1B1            32       PXM1310B_QFN-IC,H89186-001
GND                      EU1B1            41       PXM1310B_QFN-IC,H89186-001
GND                      EU1C1            2        IR354XX_SM-IR35412,IC,H73684-0A
GND                      EU1C1            5        IR354XX_SM-IR35412,IC,H73684-0A
GND                      EU1C1            7        IR354XX_SM-IR35412,IC,H73684-0A
GND                      EU1C1            40       IR354XX_SM-IR35412,IC,H73684-0A
GND                      EU1C2            49       PXE1610B_QFN-IC,H79206-001
GND                      EU1C3            2        IR354XX_SM-IR35411,IC,H73688-0A
GND                      EU1C3            5        IR354XX_SM-IR35411,IC,H73688-0A
GND                      EU1C3            7        IR354XX_SM-IR35411,IC,H73688-0A
GND                      EU1C3            40       IR354XX_SM-IR35411,IC,H73688-0A
GND                      EU1D1            2        IR354XX_SM-IR35411,IC,H73688-0A
GND                      EU1D1            5        IR354XX_SM-IR35411,IC,H73688-0A
GND                      EU1D1            7        IR354XX_SM-IR35411,IC,H73688-0A
GND                      EU1D1            40       IR354XX_SM-IR35411,IC,H73688-0A
GND                      EU1D2            23       ADM1278_SM-IC,G99251-001
GND                      EU1D3            2        IR354XX_SM-IR35411,IC,H73688-0A
GND                      EU1D3            5        IR354XX_SM-IR35411,IC,H73688-0A
GND                      EU1D3            7        IR354XX_SM-IR35411,IC,H73688-0A
GND                      EU1D3            40       IR354XX_SM-IR35411,IC,H73688-0A
GND                      EU1D4            2        IR354XX_SM-IR35411,IC,H73688-0A
GND                      EU1D4            5        IR354XX_SM-IR35411,IC,H73688-0A
GND                      EU1D4            7        IR354XX_SM-IR35411,IC,H73688-0A
GND                      EU1D4            40       IR354XX_SM-IR35411,IC,H73688-0A
GND                      EU1E2            2        IR354XX_SM-IR35411,IC,H73688-0A
GND                      EU1E2            5        IR354XX_SM-IR35411,IC,H73688-0A
GND                      EU1E2            7        IR354XX_SM-IR35411,IC,H73688-0A
GND                      EU1E2            40       IR354XX_SM-IR35411,IC,H73688-0A
GND                      EU1F1            2        IR354XX_SM-IR35411,IC,H73688-0A
GND                      EU1F1            5        IR354XX_SM-IR35411,IC,H73688-0A
GND                      EU1F1            7        IR354XX_SM-IR35411,IC,H73688-0A
GND                      EU1F1            40       IR354XX_SM-IR35411,IC,H73688-0A
GND                      EU1G1            2        IR354XX_SM-IR35411,IC,H73688-0A
GND                      EU1G1            5        IR354XX_SM-IR35411,IC,H73688-0A
GND                      EU1G1            7        IR354XX_SM-IR35411,IC,H73688-0A
GND                      EU1G1            40       IR354XX_SM-IR35411,IC,H73688-0A
GND                      EU1G2            27       PXM1310B_QFN-IC,H89186-001
GND                      EU1G2            32       PXM1310B_QFN-IC,H89186-001
GND                      EU1G2            41       PXM1310B_QFN-IC,H89186-001
GND                      EU2T1            4        SLG55021_SM-IC,G56246-001
GND                      EU2T1            9        SLG55021_SM-IC,G56246-001
GND                      EU3P1            23       PXE1110B_QFN-IC,H89187-001
GND                      EU3P1            26       PXE1110B_QFN-IC,H89187-001
GND                      EU3P1            27       PXE1110B_QFN-IC,H89187-001
GND                      EU3P1            41       PXE1110B_QFN-IC,H89187-001
GND                      EU4A1            3        MIC5166_DFN-IC,H55101-001
GND                      EU4A1            8        MIC5166_DFN-IC,H55101-001
GND                      EU4A1            11       MIC5166_DFN-IC,H55101-001
GND                      EU4A2            3        MIC5166_DFN-IC,H55101-001
GND                      EU4A2            8        MIC5166_DFN-IC,H55101-001
GND                      EU4A2            11       MIC5166_DFN-IC,H55101-001
GND                      EU4A3            16       NCP3232L_SM-IC,H86355-001
GND                      EU4A3            17       NCP3232L_SM-IC,H86355-001
GND                      EU4A3            18       NCP3232L_SM-IC,H86355-001
GND                      EU4A3            19       NCP3232L_SM-IC,H86355-001
GND                      EU4A3            20       NCP3232L_SM-IC,H86355-001
GND                      EU4A3            21       NCP3232L_SM-IC,H86355-001
GND                      EU4A3            22       NCP3232L_SM-IC,H86355-001
GND                      EU4A3            23       NCP3232L_SM-IC,H86355-001
GND                      EU4A3            24       NCP3232L_SM-IC,H86355-001
GND                      EU4A3            25       NCP3232L_SM-IC,H86355-001
GND                      EU4A3            26       NCP3232L_SM-IC,H86355-001
GND                      EU4A3            27       NCP3232L_SM-IC,H86355-001
GND                      EU4A3            28       NCP3232L_SM-IC,H86355-001
GND                      EU4A3            37       NCP3232L_SM-IC,H86355-001
GND                      EU4A3            41       NCP3232L_SM-IC,H86355-001
GND                      EU4C1            2        IR354XX_SM-IR35412,IC,H73684-0A
GND                      EU4C1            5        IR354XX_SM-IR35412,IC,H73684-0A
GND                      EU4C1            7        IR354XX_SM-IR35412,IC,H73684-0A
GND                      EU4C1            40       IR354XX_SM-IR35412,IC,H73684-0A
GND                      EU4C2            2        IR354XX_SM-IR35411,IC,H73688-0A
GND                      EU4C2            5        IR354XX_SM-IR35411,IC,H73688-0A
GND                      EU4C2            7        IR354XX_SM-IR35411,IC,H73688-0A
GND                      EU4C2            40       IR354XX_SM-IR35411,IC,H73688-0A
GND                      EU4D1            2        IR354XX_SM-IR35411,IC,H73688-0A
GND                      EU4D1            5        IR354XX_SM-IR35411,IC,H73688-0A
GND                      EU4D1            7        IR354XX_SM-IR35411,IC,H73688-0A
GND                      EU4D1            40       IR354XX_SM-IR35411,IC,H73688-0A
GND                      EU4D2            2        NB3W1200L_LCC-IC,H13585-001
GND                      EU4D2            7        NB3W1200L_LCC-IC,H13585-001
GND                      EU4D2            23       NB3W1200L_LCC-IC,H13585-001
GND                      EU4D2            33       NB3W1200L_LCC-IC,H13585-001
GND                      EU4D2            41       NB3W1200L_LCC-IC,H13585-001
GND                      EU4D2            48       NB3W1200L_LCC-IC,H13585-001
GND                      EU4D2            58       NB3W1200L_LCC-IC,H13585-001
GND                      EU4D2            65       NB3W1200L_LCC-IC,H13585-001
GND                      EU4D3            2        IR354XX_SM-IR35411,IC,H73688-0A
GND                      EU4D3            5        IR354XX_SM-IR35411,IC,H73688-0A
GND                      EU4D3            7        IR354XX_SM-IR35411,IC,H73688-0A
GND                      EU4D3            40       IR354XX_SM-IR35411,IC,H73688-0A
GND                      EU4D4            49       PXE1610B_QFN-IC,H79206-001
GND                      EU4D5            23       PXE1110B_QFN-IC,H89187-001
GND                      EU4D5            26       PXE1110B_QFN-IC,H89187-001
GND                      EU4D5            27       PXE1110B_QFN-IC,H89187-001
GND                      EU4D5            41       PXE1110B_QFN-IC,H89187-001
GND                      EU4D6            2        IR354XX_SM-IR35411,IC,H73688-0A
GND                      EU4D6            5        IR354XX_SM-IR35411,IC,H73688-0A
GND                      EU4D6            7        IR354XX_SM-IR35411,IC,H73688-0A
GND                      EU4D6            40       IR354XX_SM-IR35411,IC,H73688-0A
GND                      EU4E1            2        IR354XX_SM-IR35411,IC,H73688-0A
GND                      EU4E1            5        IR354XX_SM-IR35411,IC,H73688-0A
GND                      EU4E1            7        IR354XX_SM-IR35411,IC,H73688-0A
GND                      EU4E1            40       IR354XX_SM-IR35411,IC,H73688-0A
GND                      EU4E2            2        IR354XX_SM-IR35412,IC,H73684-0A
GND                      EU4E2            5        IR354XX_SM-IR35412,IC,H73684-0A
GND                      EU4E2            7        IR354XX_SM-IR35412,IC,H73684-0A
GND                      EU4E2            40       IR354XX_SM-IR35412,IC,H73684-0A
GND                      EU4G1            16       NCP3232L_SM-IC,H86355-001
GND                      EU4G1            17       NCP3232L_SM-IC,H86355-001
GND                      EU4G1            18       NCP3232L_SM-IC,H86355-001
GND                      EU4G1            19       NCP3232L_SM-IC,H86355-001
GND                      EU4G1            20       NCP3232L_SM-IC,H86355-001
GND                      EU4G1            21       NCP3232L_SM-IC,H86355-001
GND                      EU4G1            22       NCP3232L_SM-IC,H86355-001
GND                      EU4G1            23       NCP3232L_SM-IC,H86355-001
GND                      EU4G1            24       NCP3232L_SM-IC,H86355-001
GND                      EU4G1            25       NCP3232L_SM-IC,H86355-001
GND                      EU4G1            26       NCP3232L_SM-IC,H86355-001
GND                      EU4G1            27       NCP3232L_SM-IC,H86355-001
GND                      EU4G1            28       NCP3232L_SM-IC,H86355-001
GND                      EU4G1            37       NCP3232L_SM-IC,H86355-001
GND                      EU4G1            41       NCP3232L_SM-IC,H86355-001
GND                      EU4G2            3        MIC5166_DFN-IC,H55101-001
GND                      EU4G2            8        MIC5166_DFN-IC,H55101-001
GND                      EU4G2            11       MIC5166_DFN-IC,H55101-001
GND                      EU4G3            3        MIC5166_DFN-IC,H55101-001
GND                      EU4G3            8        MIC5166_DFN-IC,H55101-001
GND                      EU4G3            11       MIC5166_DFN-IC,H55101-001
GND                      EU7A1            2        IR354XX_SM-IR35411,IC,H73688-0A
GND                      EU7A1            5        IR354XX_SM-IR35411,IC,H73688-0A
GND                      EU7A1            7        IR354XX_SM-IR35411,IC,H73688-0A
GND                      EU7A1            40       IR354XX_SM-IR35411,IC,H73688-0A
GND                      EU7A2            2        IR354XX_SM-IR35412,IC,H73684-0A
GND                      EU7A2            5        IR354XX_SM-IR35412,IC,H73684-0A
GND                      EU7A2            7        IR354XX_SM-IR35412,IC,H73684-0A
GND                      EU7A2            40       IR354XX_SM-IR35412,IC,H73684-0A
GND                      EU7A3            2        IR354XX_SM-IR35412,IC,H73684-0A
GND                      EU7A3            5        IR354XX_SM-IR35412,IC,H73684-0A
GND                      EU7A3            7        IR354XX_SM-IR35412,IC,H73684-0A
GND                      EU7A3            40       IR354XX_SM-IR35412,IC,H73684-0A
GND                      EU7A4            2        IR354XX_SM-IR35411,IC,H73688-0A
GND                      EU7A4            5        IR354XX_SM-IR35411,IC,H73688-0A
GND                      EU7A4            7        IR354XX_SM-IR35411,IC,H73688-0A
GND                      EU7A4            40       IR354XX_SM-IR35411,IC,H73688-0A
GND                      EU7A5            27       PXM1310B_QFN-IC,H89186-001
GND                      EU7A5            32       PXM1310B_QFN-IC,H89186-001
GND                      EU7A5            41       PXM1310B_QFN-IC,H89186-001
GND                      EU7B1            16       NCP3232L_SM-IC,H86355-001
GND                      EU7B1            17       NCP3232L_SM-IC,H86355-001
GND                      EU7B1            18       NCP3232L_SM-IC,H86355-001
GND                      EU7B1            19       NCP3232L_SM-IC,H86355-001
GND                      EU7B1            20       NCP3232L_SM-IC,H86355-001
GND                      EU7B1            21       NCP3232L_SM-IC,H86355-001
GND                      EU7B1            22       NCP3232L_SM-IC,H86355-001
GND                      EU7B1            23       NCP3232L_SM-IC,H86355-001
GND                      EU7B1            24       NCP3232L_SM-IC,H86355-001
GND                      EU7B1            25       NCP3232L_SM-IC,H86355-001
GND                      EU7B1            26       NCP3232L_SM-IC,H86355-001
GND                      EU7B1            27       NCP3232L_SM-IC,H86355-001
GND                      EU7B1            28       NCP3232L_SM-IC,H86355-001
GND                      EU7B1            37       NCP3232L_SM-IC,H86355-001
GND                      EU7B1            41       NCP3232L_SM-IC,H86355-001
GND                      EU7C1            2        IR354XX_SM-IR35412,IC,H73684-0A
GND                      EU7C1            5        IR354XX_SM-IR35412,IC,H73684-0A
GND                      EU7C1            7        IR354XX_SM-IR35412,IC,H73684-0A
GND                      EU7C1            40       IR354XX_SM-IR35412,IC,H73684-0A
GND                      EU7E1            4        SLG55021_SM-IC,G56246-001
GND                      EU7E1            9        SLG55021_SM-IC,G56246-001
GND                      EU7E2            2        TPS54821_LCC-IC,H63269-001
GND                      EU7E2            3        TPS54821_LCC-IC,H63269-001
GND                      EU7E2            15       TPS54821_LCC-IC,H63269-001
GND                      EU7F1            16       NCP3232L_SM-IC,H86355-001
GND                      EU7F1            17       NCP3232L_SM-IC,H86355-001
GND                      EU7F1            18       NCP3232L_SM-IC,H86355-001
GND                      EU7F1            19       NCP3232L_SM-IC,H86355-001
GND                      EU7F1            20       NCP3232L_SM-IC,H86355-001
GND                      EU7F1            21       NCP3232L_SM-IC,H86355-001
GND                      EU7F1            22       NCP3232L_SM-IC,H86355-001
GND                      EU7F1            23       NCP3232L_SM-IC,H86355-001
GND                      EU7F1            24       NCP3232L_SM-IC,H86355-001
GND                      EU7F1            25       NCP3232L_SM-IC,H86355-001
GND                      EU7F1            26       NCP3232L_SM-IC,H86355-001
GND                      EU7F1            27       NCP3232L_SM-IC,H86355-001
GND                      EU7F1            28       NCP3232L_SM-IC,H86355-001
GND                      EU7F1            37       NCP3232L_SM-IC,H86355-001
GND                      EU7F1            41       NCP3232L_SM-IC,H86355-001
GND                      EU7G1            27       PXM1310B_QFN-IC,H89186-001
GND                      EU7G1            32       PXM1310B_QFN-IC,H89186-001
GND                      EU7G1            41       PXM1310B_QFN-IC,H89186-001
GND                      EU7G2            2        IR354XX_SM-IR35411,IC,H73688-0A
GND                      EU7G2            5        IR354XX_SM-IR35411,IC,H73688-0A
GND                      EU7G2            7        IR354XX_SM-IR35411,IC,H73688-0A
GND                      EU7G2            40       IR354XX_SM-IR35411,IC,H73688-0A
GND                      EU7G3            2        IR354XX_SM-IR35411,IC,H73688-0A
GND                      EU7G3            5        IR354XX_SM-IR35411,IC,H73688-0A
GND                      EU7G3            7        IR354XX_SM-IR35411,IC,H73688-0A
GND                      EU7G3            40       IR354XX_SM-IR35411,IC,H73688-0A
GND                      EU8A1            23       PXE1110B_QFN-IC,H89187-001
GND                      EU8A1            27       PXE1110B_QFN-IC,H89187-001
GND                      EU8A1            41       PXE1110B_QFN-IC,H89187-001
GND                      EU8A2            11       RT9059_DFN-IC,H65765-001
GND                      EU8B1            4        SLG55021_SM-IC,G56246-001
GND                      EU8B1            9        SLG55021_SM-IC,G56246-001
GND                      EU8E1            3        CSD87384M_SM-IC,H66258-001
GND                      EU8F2            1        ICS9FGP204_MLFP-IC,E95226-001
GND                      EU8F2            10       ICS9FGP204_MLFP-IC,E95226-001
GND                      EU8F2            14       ICS9FGP204_MLFP-IC,E95226-001
GND                      EU8F2            18       ICS9FGP204_MLFP-IC,E95226-001
GND                      EU8F2            21       ICS9FGP204_MLFP-IC,E95226-001
GND                      EU8F2            27       ICS9FGP204_MLFP-IC,E95226-001
GND                      EU8F2            30       ICS9FGP204_MLFP-IC,E95226-001
GND                      EU8F2            35       ICS9FGP204_MLFP-IC,E95226-001
GND                      EU8F2            41       ICS9FGP204_MLFP-IC,E95226-001
GND                      EU9E1            65       SPRINGVILLE_SM1-IC,G47144-004
GND                      EU9F1            11       RT9059_DFN-IC,H65765-001
GND                      EU9F2            11       RT9059_DFN-IC,H65765-001
GND                      EU9F3            12       PI7C9X1172_QFN-IC,H66899-001
GND                      EU9F3            16       PI7C9X1172_QFN-IC,H66899-001
GND                      EU9F3            25       PI7C9X1172_QFN-IC,H66899-001
GND                      EU9F3            33       PI7C9X1172_QFN-IC,H66899-001
GND                      EU9G1            4        ADC128D818_SM-IC,H63642-001
GND                      EU9M1            4        SLG55021_SM-IC,G56246-001
GND                      EU9M1            9        SLG55021_SM-IC,G56246-001
GND                      J1A1             2        SCONN288_H44441004_PIP-SCONN,HA
GND                      J1A1             4        SCONN288_H44441004_PIP-SCONN,HA
GND                      J1A1             6        SCONN288_H44441004_PIP-SCONN,HA
GND                      J1A1             9        SCONN288_H44441004_PIP-SCONN,HA
GND                      J1A1             11       SCONN288_H44441004_PIP-SCONN,HA
GND                      J1A1             13       SCONN288_H44441004_PIP-SCONN,HA
GND                      J1A1             15       SCONN288_H44441004_PIP-SCONN,HA
GND                      J1A1             17       SCONN288_H44441004_PIP-SCONN,HA
GND                      J1A1             20       SCONN288_H44441004_PIP-SCONN,HA
GND                      J1A1             22       SCONN288_H44441004_PIP-SCONN,HA
GND                      J1A1             24       SCONN288_H44441004_PIP-SCONN,HA
GND                      J1A1             26       SCONN288_H44441004_PIP-SCONN,HA
GND                      J1A1             28       SCONN288_H44441004_PIP-SCONN,HA
GND                      J1A1             31       SCONN288_H44441004_PIP-SCONN,HA
GND                      J1A1             33       SCONN288_H44441004_PIP-SCONN,HA
GND                      J1A1             35       SCONN288_H44441004_PIP-SCONN,HA
GND                      J1A1             37       SCONN288_H44441004_PIP-SCONN,HA
GND                      J1A1             39       SCONN288_H44441004_PIP-SCONN,HA
GND                      J1A1             42       SCONN288_H44441004_PIP-SCONN,HA
GND                      J1A1             44       SCONN288_H44441004_PIP-SCONN,HA
GND                      J1A1             46       SCONN288_H44441004_PIP-SCONN,HA
GND                      J1A1             48       SCONN288_H44441004_PIP-SCONN,HA
GND                      J1A1             50       SCONN288_H44441004_PIP-SCONN,HA
GND                      J1A1             53       SCONN288_H44441004_PIP-SCONN,HA
GND                      J1A1             55       SCONN288_H44441004_PIP-SCONN,HA
GND                      J1A1             57       SCONN288_H44441004_PIP-SCONN,HA
GND                      J1A1             94       SCONN288_H44441004_PIP-SCONN,HA
GND                      J1A1             96       SCONN288_H44441004_PIP-SCONN,HA
GND                      J1A1             98       SCONN288_H44441004_PIP-SCONN,HA
GND                      J1A1             101      SCONN288_H44441004_PIP-SCONN,HA
GND                      J1A1             103      SCONN288_H44441004_PIP-SCONN,HA
GND                      J1A1             105      SCONN288_H44441004_PIP-SCONN,HA
GND                      J1A1             107      SCONN288_H44441004_PIP-SCONN,HA
GND                      J1A1             109      SCONN288_H44441004_PIP-SCONN,HA
GND                      J1A1             112      SCONN288_H44441004_PIP-SCONN,HA
GND                      J1A1             114      SCONN288_H44441004_PIP-SCONN,HA
GND                      J1A1             116      SCONN288_H44441004_PIP-SCONN,HA
GND                      J1A1             118      SCONN288_H44441004_PIP-SCONN,HA
GND                      J1A1             120      SCONN288_H44441004_PIP-SCONN,HA
GND                      J1A1             123      SCONN288_H44441004_PIP-SCONN,HA
GND                      J1A1             125      SCONN288_H44441004_PIP-SCONN,HA
GND                      J1A1             127      SCONN288_H44441004_PIP-SCONN,HA
GND                      J1A1             129      SCONN288_H44441004_PIP-SCONN,HA
GND                      J1A1             131      SCONN288_H44441004_PIP-SCONN,HA
GND                      J1A1             134      SCONN288_H44441004_PIP-SCONN,HA
GND                      J1A1             136      SCONN288_H44441004_PIP-SCONN,HA
GND                      J1A1             138      SCONN288_H44441004_PIP-SCONN,HA
GND                      J1A1             139      SCONN288_H44441004_PIP-SCONN,HA
GND                      J1A1             140      SCONN288_H44441004_PIP-SCONN,HA
GND                      J1A1             147      SCONN288_H44441004_PIP-SCONN,HA
GND                      J1A1             149      SCONN288_H44441004_PIP-SCONN,HA
GND                      J1A1             151      SCONN288_H44441004_PIP-SCONN,HA
GND                      J1A1             154      SCONN288_H44441004_PIP-SCONN,HA
GND                      J1A1             156      SCONN288_H44441004_PIP-SCONN,HA
GND                      J1A1             158      SCONN288_H44441004_PIP-SCONN,HA
GND                      J1A1             160      SCONN288_H44441004_PIP-SCONN,HA
GND                      J1A1             162      SCONN288_H44441004_PIP-SCONN,HA
GND                      J1A1             165      SCONN288_H44441004_PIP-SCONN,HA
GND                      J1A1             167      SCONN288_H44441004_PIP-SCONN,HA
GND                      J1A1             169      SCONN288_H44441004_PIP-SCONN,HA
GND                      J1A1             171      SCONN288_H44441004_PIP-SCONN,HA
GND                      J1A1             173      SCONN288_H44441004_PIP-SCONN,HA
GND                      J1A1             176      SCONN288_H44441004_PIP-SCONN,HA
GND                      J1A1             178      SCONN288_H44441004_PIP-SCONN,HA
GND                      J1A1             180      SCONN288_H44441004_PIP-SCONN,HA
GND                      J1A1             182      SCONN288_H44441004_PIP-SCONN,HA
GND                      J1A1             184      SCONN288_H44441004_PIP-SCONN,HA
GND                      J1A1             187      SCONN288_H44441004_PIP-SCONN,HA
GND                      J1A1             189      SCONN288_H44441004_PIP-SCONN,HA
GND                      J1A1             191      SCONN288_H44441004_PIP-SCONN,HA
GND                      J1A1             193      SCONN288_H44441004_PIP-SCONN,HA
GND                      J1A1             195      SCONN288_H44441004_PIP-SCONN,HA
GND                      J1A1             198      SCONN288_H44441004_PIP-SCONN,HA
GND                      J1A1             200      SCONN288_H44441004_PIP-SCONN,HA
GND                      J1A1             202      SCONN288_H44441004_PIP-SCONN,HA
GND                      J1A1             239      SCONN288_H44441004_PIP-SCONN,HA
GND                      J1A1             241      SCONN288_H44441004_PIP-SCONN,HA
GND                      J1A1             243      SCONN288_H44441004_PIP-SCONN,HA
GND                      J1A1             246      SCONN288_H44441004_PIP-SCONN,HA
GND                      J1A1             248      SCONN288_H44441004_PIP-SCONN,HA
GND                      J1A1             250      SCONN288_H44441004_PIP-SCONN,HA
GND                      J1A1             252      SCONN288_H44441004_PIP-SCONN,HA
GND                      J1A1             254      SCONN288_H44441004_PIP-SCONN,HA
GND                      J1A1             257      SCONN288_H44441004_PIP-SCONN,HA
GND                      J1A1             259      SCONN288_H44441004_PIP-SCONN,HA
GND                      J1A1             261      SCONN288_H44441004_PIP-SCONN,HA
GND                      J1A1             263      SCONN288_H44441004_PIP-SCONN,HA
GND                      J1A1             265      SCONN288_H44441004_PIP-SCONN,HA
GND                      J1A1             268      SCONN288_H44441004_PIP-SCONN,HA
GND                      J1A1             270      SCONN288_H44441004_PIP-SCONN,HA
GND                      J1A1             272      SCONN288_H44441004_PIP-SCONN,HA
GND                      J1A1             274      SCONN288_H44441004_PIP-SCONN,HA
GND                      J1A1             276      SCONN288_H44441004_PIP-SCONN,HA
GND                      J1A1             279      SCONN288_H44441004_PIP-SCONN,HA
GND                      J1A1             281      SCONN288_H44441004_PIP-SCONN,HA
GND                      J1A1             283      SCONN288_H44441004_PIP-SCONN,HA
GND                      J1A2             2        SCONN288_H44441004_PIP-SCONN,HA
GND                      J1A2             4        SCONN288_H44441004_PIP-SCONN,HA
GND                      J1A2             6        SCONN288_H44441004_PIP-SCONN,HA
GND                      J1A2             9        SCONN288_H44441004_PIP-SCONN,HA
GND                      J1A2             11       SCONN288_H44441004_PIP-SCONN,HA
GND                      J1A2             13       SCONN288_H44441004_PIP-SCONN,HA
GND                      J1A2             15       SCONN288_H44441004_PIP-SCONN,HA
GND                      J1A2             17       SCONN288_H44441004_PIP-SCONN,HA
GND                      J1A2             20       SCONN288_H44441004_PIP-SCONN,HA
GND                      J1A2             22       SCONN288_H44441004_PIP-SCONN,HA
GND                      J1A2             24       SCONN288_H44441004_PIP-SCONN,HA
GND                      J1A2             26       SCONN288_H44441004_PIP-SCONN,HA
GND                      J1A2             28       SCONN288_H44441004_PIP-SCONN,HA
GND                      J1A2             31       SCONN288_H44441004_PIP-SCONN,HA
GND                      J1A2             33       SCONN288_H44441004_PIP-SCONN,HA
GND                      J1A2             35       SCONN288_H44441004_PIP-SCONN,HA
GND                      J1A2             37       SCONN288_H44441004_PIP-SCONN,HA
GND                      J1A2             39       SCONN288_H44441004_PIP-SCONN,HA
GND                      J1A2             42       SCONN288_H44441004_PIP-SCONN,HA
GND                      J1A2             44       SCONN288_H44441004_PIP-SCONN,HA
GND                      J1A2             46       SCONN288_H44441004_PIP-SCONN,HA
GND                      J1A2             48       SCONN288_H44441004_PIP-SCONN,HA
GND                      J1A2             50       SCONN288_H44441004_PIP-SCONN,HA
GND                      J1A2             53       SCONN288_H44441004_PIP-SCONN,HA
GND                      J1A2             55       SCONN288_H44441004_PIP-SCONN,HA
GND                      J1A2             57       SCONN288_H44441004_PIP-SCONN,HA
GND                      J1A2             94       SCONN288_H44441004_PIP-SCONN,HA
GND                      J1A2             96       SCONN288_H44441004_PIP-SCONN,HA
GND                      J1A2             98       SCONN288_H44441004_PIP-SCONN,HA
GND                      J1A2             101      SCONN288_H44441004_PIP-SCONN,HA
GND                      J1A2             103      SCONN288_H44441004_PIP-SCONN,HA
GND                      J1A2             105      SCONN288_H44441004_PIP-SCONN,HA
GND                      J1A2             107      SCONN288_H44441004_PIP-SCONN,HA
GND                      J1A2             109      SCONN288_H44441004_PIP-SCONN,HA
GND                      J1A2             112      SCONN288_H44441004_PIP-SCONN,HA
GND                      J1A2             114      SCONN288_H44441004_PIP-SCONN,HA
GND                      J1A2             116      SCONN288_H44441004_PIP-SCONN,HA
GND                      J1A2             118      SCONN288_H44441004_PIP-SCONN,HA
GND                      J1A2             120      SCONN288_H44441004_PIP-SCONN,HA
GND                      J1A2             123      SCONN288_H44441004_PIP-SCONN,HA
GND                      J1A2             125      SCONN288_H44441004_PIP-SCONN,HA
GND                      J1A2             127      SCONN288_H44441004_PIP-SCONN,HA
GND                      J1A2             129      SCONN288_H44441004_PIP-SCONN,HA
GND                      J1A2             131      SCONN288_H44441004_PIP-SCONN,HA
GND                      J1A2             134      SCONN288_H44441004_PIP-SCONN,HA
GND                      J1A2             136      SCONN288_H44441004_PIP-SCONN,HA
GND                      J1A2             138      SCONN288_H44441004_PIP-SCONN,HA
GND                      J1A2             139      SCONN288_H44441004_PIP-SCONN,HA
GND                      J1A2             147      SCONN288_H44441004_PIP-SCONN,HA
GND                      J1A2             149      SCONN288_H44441004_PIP-SCONN,HA
GND                      J1A2             151      SCONN288_H44441004_PIP-SCONN,HA
GND                      J1A2             154      SCONN288_H44441004_PIP-SCONN,HA
GND                      J1A2             156      SCONN288_H44441004_PIP-SCONN,HA
GND                      J1A2             158      SCONN288_H44441004_PIP-SCONN,HA
GND                      J1A2             160      SCONN288_H44441004_PIP-SCONN,HA
GND                      J1A2             162      SCONN288_H44441004_PIP-SCONN,HA
GND                      J1A2             165      SCONN288_H44441004_PIP-SCONN,HA
GND                      J1A2             167      SCONN288_H44441004_PIP-SCONN,HA
GND                      J1A2             169      SCONN288_H44441004_PIP-SCONN,HA
GND                      J1A2             171      SCONN288_H44441004_PIP-SCONN,HA
GND                      J1A2             173      SCONN288_H44441004_PIP-SCONN,HA
GND                      J1A2             176      SCONN288_H44441004_PIP-SCONN,HA
GND                      J1A2             178      SCONN288_H44441004_PIP-SCONN,HA
GND                      J1A2             180      SCONN288_H44441004_PIP-SCONN,HA
GND                      J1A2             182      SCONN288_H44441004_PIP-SCONN,HA
GND                      J1A2             184      SCONN288_H44441004_PIP-SCONN,HA
GND                      J1A2             187      SCONN288_H44441004_PIP-SCONN,HA
GND                      J1A2             189      SCONN288_H44441004_PIP-SCONN,HA
GND                      J1A2             191      SCONN288_H44441004_PIP-SCONN,HA
GND                      J1A2             193      SCONN288_H44441004_PIP-SCONN,HA
GND                      J1A2             195      SCONN288_H44441004_PIP-SCONN,HA
GND                      J1A2             198      SCONN288_H44441004_PIP-SCONN,HA
GND                      J1A2             200      SCONN288_H44441004_PIP-SCONN,HA
GND                      J1A2             202      SCONN288_H44441004_PIP-SCONN,HA
GND                      J1A2             238      SCONN288_H44441004_PIP-SCONN,HA
GND                      J1A2             239      SCONN288_H44441004_PIP-SCONN,HA
GND                      J1A2             241      SCONN288_H44441004_PIP-SCONN,HA
GND                      J1A2             243      SCONN288_H44441004_PIP-SCONN,HA
GND                      J1A2             246      SCONN288_H44441004_PIP-SCONN,HA
GND                      J1A2             248      SCONN288_H44441004_PIP-SCONN,HA
GND                      J1A2             250      SCONN288_H44441004_PIP-SCONN,HA
GND                      J1A2             252      SCONN288_H44441004_PIP-SCONN,HA
GND                      J1A2             254      SCONN288_H44441004_PIP-SCONN,HA
GND                      J1A2             257      SCONN288_H44441004_PIP-SCONN,HA
GND                      J1A2             259      SCONN288_H44441004_PIP-SCONN,HA
GND                      J1A2             261      SCONN288_H44441004_PIP-SCONN,HA
GND                      J1A2             263      SCONN288_H44441004_PIP-SCONN,HA
GND                      J1A2             265      SCONN288_H44441004_PIP-SCONN,HA
GND                      J1A2             268      SCONN288_H44441004_PIP-SCONN,HA
GND                      J1A2             270      SCONN288_H44441004_PIP-SCONN,HA
GND                      J1A2             272      SCONN288_H44441004_PIP-SCONN,HA
GND                      J1A2             274      SCONN288_H44441004_PIP-SCONN,HA
GND                      J1A2             276      SCONN288_H44441004_PIP-SCONN,HA
GND                      J1A2             279      SCONN288_H44441004_PIP-SCONN,HA
GND                      J1A2             281      SCONN288_H44441004_PIP-SCONN,HA
GND                      J1A2             283      SCONN288_H44441004_PIP-SCONN,HA
GND                      J1B1             2        SCONN288_H44441004_PIP-SCONN,HA
GND                      J1B1             4        SCONN288_H44441004_PIP-SCONN,HA
GND                      J1B1             6        SCONN288_H44441004_PIP-SCONN,HA
GND                      J1B1             9        SCONN288_H44441004_PIP-SCONN,HA
GND                      J1B1             11       SCONN288_H44441004_PIP-SCONN,HA
GND                      J1B1             13       SCONN288_H44441004_PIP-SCONN,HA
GND                      J1B1             15       SCONN288_H44441004_PIP-SCONN,HA
GND                      J1B1             17       SCONN288_H44441004_PIP-SCONN,HA
GND                      J1B1             20       SCONN288_H44441004_PIP-SCONN,HA
GND                      J1B1             22       SCONN288_H44441004_PIP-SCONN,HA
GND                      J1B1             24       SCONN288_H44441004_PIP-SCONN,HA
GND                      J1B1             26       SCONN288_H44441004_PIP-SCONN,HA
GND                      J1B1             28       SCONN288_H44441004_PIP-SCONN,HA
GND                      J1B1             31       SCONN288_H44441004_PIP-SCONN,HA
GND                      J1B1             33       SCONN288_H44441004_PIP-SCONN,HA
GND                      J1B1             35       SCONN288_H44441004_PIP-SCONN,HA
GND                      J1B1             37       SCONN288_H44441004_PIP-SCONN,HA
GND                      J1B1             39       SCONN288_H44441004_PIP-SCONN,HA
GND                      J1B1             42       SCONN288_H44441004_PIP-SCONN,HA
GND                      J1B1             44       SCONN288_H44441004_PIP-SCONN,HA
GND                      J1B1             46       SCONN288_H44441004_PIP-SCONN,HA
GND                      J1B1             48       SCONN288_H44441004_PIP-SCONN,HA
GND                      J1B1             50       SCONN288_H44441004_PIP-SCONN,HA
GND                      J1B1             53       SCONN288_H44441004_PIP-SCONN,HA
GND                      J1B1             55       SCONN288_H44441004_PIP-SCONN,HA
GND                      J1B1             57       SCONN288_H44441004_PIP-SCONN,HA
GND                      J1B1             94       SCONN288_H44441004_PIP-SCONN,HA
GND                      J1B1             96       SCONN288_H44441004_PIP-SCONN,HA
GND                      J1B1             98       SCONN288_H44441004_PIP-SCONN,HA
GND                      J1B1             101      SCONN288_H44441004_PIP-SCONN,HA
GND                      J1B1             103      SCONN288_H44441004_PIP-SCONN,HA
GND                      J1B1             105      SCONN288_H44441004_PIP-SCONN,HA
GND                      J1B1             107      SCONN288_H44441004_PIP-SCONN,HA
GND                      J1B1             109      SCONN288_H44441004_PIP-SCONN,HA
GND                      J1B1             112      SCONN288_H44441004_PIP-SCONN,HA
GND                      J1B1             114      SCONN288_H44441004_PIP-SCONN,HA
GND                      J1B1             116      SCONN288_H44441004_PIP-SCONN,HA
GND                      J1B1             118      SCONN288_H44441004_PIP-SCONN,HA
GND                      J1B1             120      SCONN288_H44441004_PIP-SCONN,HA
GND                      J1B1             123      SCONN288_H44441004_PIP-SCONN,HA
GND                      J1B1             125      SCONN288_H44441004_PIP-SCONN,HA
GND                      J1B1             127      SCONN288_H44441004_PIP-SCONN,HA
GND                      J1B1             129      SCONN288_H44441004_PIP-SCONN,HA
GND                      J1B1             131      SCONN288_H44441004_PIP-SCONN,HA
GND                      J1B1             134      SCONN288_H44441004_PIP-SCONN,HA
GND                      J1B1             136      SCONN288_H44441004_PIP-SCONN,HA
GND                      J1B1             138      SCONN288_H44441004_PIP-SCONN,HA
GND                      J1B1             139      SCONN288_H44441004_PIP-SCONN,HA
GND                      J1B1             140      SCONN288_H44441004_PIP-SCONN,HA
GND                      J1B1             147      SCONN288_H44441004_PIP-SCONN,HA
GND                      J1B1             149      SCONN288_H44441004_PIP-SCONN,HA
GND                      J1B1             151      SCONN288_H44441004_PIP-SCONN,HA
GND                      J1B1             154      SCONN288_H44441004_PIP-SCONN,HA
GND                      J1B1             156      SCONN288_H44441004_PIP-SCONN,HA
GND                      J1B1             158      SCONN288_H44441004_PIP-SCONN,HA
GND                      J1B1             160      SCONN288_H44441004_PIP-SCONN,HA
GND                      J1B1             162      SCONN288_H44441004_PIP-SCONN,HA
GND                      J1B1             165      SCONN288_H44441004_PIP-SCONN,HA
GND                      J1B1             167      SCONN288_H44441004_PIP-SCONN,HA
GND                      J1B1             169      SCONN288_H44441004_PIP-SCONN,HA
GND                      J1B1             171      SCONN288_H44441004_PIP-SCONN,HA
GND                      J1B1             173      SCONN288_H44441004_PIP-SCONN,HA
GND                      J1B1             176      SCONN288_H44441004_PIP-SCONN,HA
GND                      J1B1             178      SCONN288_H44441004_PIP-SCONN,HA
GND                      J1B1             180      SCONN288_H44441004_PIP-SCONN,HA
GND                      J1B1             182      SCONN288_H44441004_PIP-SCONN,HA
GND                      J1B1             184      SCONN288_H44441004_PIP-SCONN,HA
GND                      J1B1             187      SCONN288_H44441004_PIP-SCONN,HA
GND                      J1B1             189      SCONN288_H44441004_PIP-SCONN,HA
GND                      J1B1             191      SCONN288_H44441004_PIP-SCONN,HA
GND                      J1B1             193      SCONN288_H44441004_PIP-SCONN,HA
GND                      J1B1             195      SCONN288_H44441004_PIP-SCONN,HA
GND                      J1B1             198      SCONN288_H44441004_PIP-SCONN,HA
GND                      J1B1             200      SCONN288_H44441004_PIP-SCONN,HA
GND                      J1B1             202      SCONN288_H44441004_PIP-SCONN,HA
GND                      J1B1             238      SCONN288_H44441004_PIP-SCONN,HA
GND                      J1B1             239      SCONN288_H44441004_PIP-SCONN,HA
GND                      J1B1             241      SCONN288_H44441004_PIP-SCONN,HA
GND                      J1B1             243      SCONN288_H44441004_PIP-SCONN,HA
GND                      J1B1             246      SCONN288_H44441004_PIP-SCONN,HA
GND                      J1B1             248      SCONN288_H44441004_PIP-SCONN,HA
GND                      J1B1             250      SCONN288_H44441004_PIP-SCONN,HA
GND                      J1B1             252      SCONN288_H44441004_PIP-SCONN,HA
GND                      J1B1             254      SCONN288_H44441004_PIP-SCONN,HA
GND                      J1B1             257      SCONN288_H44441004_PIP-SCONN,HA
GND                      J1B1             259      SCONN288_H44441004_PIP-SCONN,HA
GND                      J1B1             261      SCONN288_H44441004_PIP-SCONN,HA
GND                      J1B1             263      SCONN288_H44441004_PIP-SCONN,HA
GND                      J1B1             265      SCONN288_H44441004_PIP-SCONN,HA
GND                      J1B1             268      SCONN288_H44441004_PIP-SCONN,HA
GND                      J1B1             270      SCONN288_H44441004_PIP-SCONN,HA
GND                      J1B1             272      SCONN288_H44441004_PIP-SCONN,HA
GND                      J1B1             274      SCONN288_H44441004_PIP-SCONN,HA
GND                      J1B1             276      SCONN288_H44441004_PIP-SCONN,HA
GND                      J1B1             279      SCONN288_H44441004_PIP-SCONN,HA
GND                      J1B1             281      SCONN288_H44441004_PIP-SCONN,HA
GND                      J1B1             283      SCONN288_H44441004_PIP-SCONN,HA
GND                      J1B2             1        CONN6_C74770005_PIP-HDR,C74770A
GND                      J1C1             A2       CONN76_H22707001_THMT1-CONN,H2A
GND                      J1C1             A4       CONN76_H22707001_THMT1-CONN,H2A
GND                      J1C1             A6       CONN76_H22707001_THMT1-CONN,H2A
GND                      J1C1             A8       CONN76_H22707001_THMT1-CONN,H2A
GND                      J1C1             C1       CONN76_H22707001_THMT1-CONN,H2A
GND                      J1C1             C3       CONN76_H22707001_THMT1-CONN,H2A
GND                      J1C1             C5       CONN76_H22707001_THMT1-CONN,H2A
GND                      J1C1             C7       CONN76_H22707001_THMT1-CONN,H2A
GND                      J1C1             D2       CONN76_H22707001_THMT1-CONN,H2A
GND                      J1C1             D4       CONN76_H22707001_THMT1-CONN,H2A
GND                      J1C1             D6       CONN76_H22707001_THMT1-CONN,H2A
GND                      J1C1             D8       CONN76_H22707001_THMT1-CONN,H2A
GND                      J1C1             F1       CONN76_H22707001_THMT1-CONN,H2A
GND                      J1C1             F3       CONN76_H22707001_THMT1-CONN,H2A
GND                      J1C1             F5       CONN76_H22707001_THMT1-CONN,H2A
GND                      J1C1             F7       CONN76_H22707001_THMT1-CONN,H2A
GND                      J1C1             G2       CONN76_H22707001_THMT1-CONN,H2A
GND                      J1C1             G4       CONN76_H22707001_THMT1-CONN,H2A
GND                      J1C1             G6       CONN76_H22707001_THMT1-CONN,H2A
GND                      J1C1             G8       CONN76_H22707001_THMT1-CONN,H2A
GND                      J1C1             I1       CONN76_H22707001_THMT1-CONN,H2A
GND                      J1C1             I3       CONN76_H22707001_THMT1-CONN,H2A
GND                      J1C1             I5       CONN76_H22707001_THMT1-CONN,H2A
GND                      J1C1             I7       CONN76_H22707001_THMT1-CONN,H2A
GND                      J1C1             J2       CONN76_H22707001_THMT1-CONN,H2A
GND                      J1C1             J4       CONN76_H22707001_THMT1-CONN,H2A
GND                      J1C1             J6       CONN76_H22707001_THMT1-CONN,H2A
GND                      J1C1             J8       CONN76_H22707001_THMT1-CONN,H2A
GND                      J1D1             C1       CONN12_G98257001_THMT-CONN,G98A
GND                      J1D1             C2       CONN12_G98257001_THMT-CONN,G98A
GND                      J1D1             C3       CONN12_G98257001_THMT-CONN,G98A
GND                      J1D1             D1       CONN12_G98257001_THMT-CONN,G98A
GND                      J1D1             D2       CONN12_G98257001_THMT-CONN,G98A
GND                      J1D1             D3       CONN12_G98257001_THMT-CONN,G98A
GND                      J1E1             C1       CONN12_G98257001_THMT-CONN,G98A
GND                      J1E1             C2       CONN12_G98257001_THMT-CONN,G98A
GND                      J1E1             C3       CONN12_G98257001_THMT-CONN,G98A
GND                      J1E1             D1       CONN12_G98257001_THMT-CONN,G98A
GND                      J1E1             D2       CONN12_G98257001_THMT-CONN,G98A
GND                      J1E1             D3       CONN12_G98257001_THMT-CONN,G98A
GND                      J1F1             A2       CONN76_H22707001_THMT1-CONN,H2A
GND                      J1F1             A8       CONN76_H22707001_THMT1-CONN,H2A
GND                      J1F1             C1       CONN76_H22707001_THMT1-CONN,H2A
GND                      J1F1             C3       CONN76_H22707001_THMT1-CONN,H2A
GND                      J1F1             C5       CONN76_H22707001_THMT1-CONN,H2A
GND                      J1F1             C7       CONN76_H22707001_THMT1-CONN,H2A
GND                      J1F1             D2       CONN76_H22707001_THMT1-CONN,H2A
GND                      J1F1             D6       CONN76_H22707001_THMT1-CONN,H2A
GND                      J1F1             D8       CONN76_H22707001_THMT1-CONN,H2A
GND                      J1F1             F1       CONN76_H22707001_THMT1-CONN,H2A
GND                      J1F1             F3       CONN76_H22707001_THMT1-CONN,H2A
GND                      J1F1             F7       CONN76_H22707001_THMT1-CONN,H2A
GND                      J1F1             G2       CONN76_H22707001_THMT1-CONN,H2A
GND                      J1F1             G4       CONN76_H22707001_THMT1-CONN,H2A
GND                      J1F1             G6       CONN76_H22707001_THMT1-CONN,H2A
GND                      J1F1             G8       CONN76_H22707001_THMT1-CONN,H2A
GND                      J1F1             I1       CONN76_H22707001_THMT1-CONN,H2A
GND                      J1F1             I7       CONN76_H22707001_THMT1-CONN,H2A
GND                      J1F1             J2       CONN76_H22707001_THMT1-CONN,H2A
GND                      J1F1             J4       CONN76_H22707001_THMT1-CONN,H2A
GND                      J1F1             J6       CONN76_H22707001_THMT1-CONN,H2A
GND                      J1F1             J8       CONN76_H22707001_THMT1-CONN,H2A
GND                      J1F2             1        CONN6_C74770005_PIP-HDR,C74770A
GND                      J1F3             8        CONN8_H62179001_PIP-CONN,H6217A
GND                      J1G1             2        SCONN288_H44441004_PIP-SCONN,HA
GND                      J1G1             4        SCONN288_H44441004_PIP-SCONN,HA
GND                      J1G1             6        SCONN288_H44441004_PIP-SCONN,HA
GND                      J1G1             9        SCONN288_H44441004_PIP-SCONN,HA
GND                      J1G1             11       SCONN288_H44441004_PIP-SCONN,HA
GND                      J1G1             13       SCONN288_H44441004_PIP-SCONN,HA
GND                      J1G1             15       SCONN288_H44441004_PIP-SCONN,HA
GND                      J1G1             17       SCONN288_H44441004_PIP-SCONN,HA
GND                      J1G1             20       SCONN288_H44441004_PIP-SCONN,HA
GND                      J1G1             22       SCONN288_H44441004_PIP-SCONN,HA
GND                      J1G1             24       SCONN288_H44441004_PIP-SCONN,HA
GND                      J1G1             26       SCONN288_H44441004_PIP-SCONN,HA
GND                      J1G1             28       SCONN288_H44441004_PIP-SCONN,HA
GND                      J1G1             31       SCONN288_H44441004_PIP-SCONN,HA
GND                      J1G1             33       SCONN288_H44441004_PIP-SCONN,HA
GND                      J1G1             35       SCONN288_H44441004_PIP-SCONN,HA
GND                      J1G1             37       SCONN288_H44441004_PIP-SCONN,HA
GND                      J1G1             39       SCONN288_H44441004_PIP-SCONN,HA
GND                      J1G1             42       SCONN288_H44441004_PIP-SCONN,HA
GND                      J1G1             44       SCONN288_H44441004_PIP-SCONN,HA
GND                      J1G1             46       SCONN288_H44441004_PIP-SCONN,HA
GND                      J1G1             48       SCONN288_H44441004_PIP-SCONN,HA
GND                      J1G1             50       SCONN288_H44441004_PIP-SCONN,HA
GND                      J1G1             53       SCONN288_H44441004_PIP-SCONN,HA
GND                      J1G1             55       SCONN288_H44441004_PIP-SCONN,HA
GND                      J1G1             57       SCONN288_H44441004_PIP-SCONN,HA
GND                      J1G1             94       SCONN288_H44441004_PIP-SCONN,HA
GND                      J1G1             96       SCONN288_H44441004_PIP-SCONN,HA
GND                      J1G1             98       SCONN288_H44441004_PIP-SCONN,HA
GND                      J1G1             101      SCONN288_H44441004_PIP-SCONN,HA
GND                      J1G1             103      SCONN288_H44441004_PIP-SCONN,HA
GND                      J1G1             105      SCONN288_H44441004_PIP-SCONN,HA
GND                      J1G1             107      SCONN288_H44441004_PIP-SCONN,HA
GND                      J1G1             109      SCONN288_H44441004_PIP-SCONN,HA
GND                      J1G1             112      SCONN288_H44441004_PIP-SCONN,HA
GND                      J1G1             114      SCONN288_H44441004_PIP-SCONN,HA
GND                      J1G1             116      SCONN288_H44441004_PIP-SCONN,HA
GND                      J1G1             118      SCONN288_H44441004_PIP-SCONN,HA
GND                      J1G1             120      SCONN288_H44441004_PIP-SCONN,HA
GND                      J1G1             123      SCONN288_H44441004_PIP-SCONN,HA
GND                      J1G1             125      SCONN288_H44441004_PIP-SCONN,HA
GND                      J1G1             127      SCONN288_H44441004_PIP-SCONN,HA
GND                      J1G1             129      SCONN288_H44441004_PIP-SCONN,HA
GND                      J1G1             131      SCONN288_H44441004_PIP-SCONN,HA
GND                      J1G1             134      SCONN288_H44441004_PIP-SCONN,HA
GND                      J1G1             136      SCONN288_H44441004_PIP-SCONN,HA
GND                      J1G1             138      SCONN288_H44441004_PIP-SCONN,HA
GND                      J1G1             139      SCONN288_H44441004_PIP-SCONN,HA
GND                      J1G1             140      SCONN288_H44441004_PIP-SCONN,HA
GND                      J1G1             147      SCONN288_H44441004_PIP-SCONN,HA
GND                      J1G1             149      SCONN288_H44441004_PIP-SCONN,HA
GND                      J1G1             151      SCONN288_H44441004_PIP-SCONN,HA
GND                      J1G1             154      SCONN288_H44441004_PIP-SCONN,HA
GND                      J1G1             156      SCONN288_H44441004_PIP-SCONN,HA
GND                      J1G1             158      SCONN288_H44441004_PIP-SCONN,HA
GND                      J1G1             160      SCONN288_H44441004_PIP-SCONN,HA
GND                      J1G1             162      SCONN288_H44441004_PIP-SCONN,HA
GND                      J1G1             165      SCONN288_H44441004_PIP-SCONN,HA
GND                      J1G1             167      SCONN288_H44441004_PIP-SCONN,HA
GND                      J1G1             169      SCONN288_H44441004_PIP-SCONN,HA
GND                      J1G1             171      SCONN288_H44441004_PIP-SCONN,HA
GND                      J1G1             173      SCONN288_H44441004_PIP-SCONN,HA
GND                      J1G1             176      SCONN288_H44441004_PIP-SCONN,HA
GND                      J1G1             178      SCONN288_H44441004_PIP-SCONN,HA
GND                      J1G1             180      SCONN288_H44441004_PIP-SCONN,HA
GND                      J1G1             182      SCONN288_H44441004_PIP-SCONN,HA
GND                      J1G1             184      SCONN288_H44441004_PIP-SCONN,HA
GND                      J1G1             187      SCONN288_H44441004_PIP-SCONN,HA
GND                      J1G1             189      SCONN288_H44441004_PIP-SCONN,HA
GND                      J1G1             191      SCONN288_H44441004_PIP-SCONN,HA
GND                      J1G1             193      SCONN288_H44441004_PIP-SCONN,HA
GND                      J1G1             195      SCONN288_H44441004_PIP-SCONN,HA
GND                      J1G1             198      SCONN288_H44441004_PIP-SCONN,HA
GND                      J1G1             200      SCONN288_H44441004_PIP-SCONN,HA
GND                      J1G1             202      SCONN288_H44441004_PIP-SCONN,HA
GND                      J1G1             238      SCONN288_H44441004_PIP-SCONN,HA
GND                      J1G1             239      SCONN288_H44441004_PIP-SCONN,HA
GND                      J1G1             241      SCONN288_H44441004_PIP-SCONN,HA
GND                      J1G1             243      SCONN288_H44441004_PIP-SCONN,HA
GND                      J1G1             246      SCONN288_H44441004_PIP-SCONN,HA
GND                      J1G1             248      SCONN288_H44441004_PIP-SCONN,HA
GND                      J1G1             250      SCONN288_H44441004_PIP-SCONN,HA
GND                      J1G1             252      SCONN288_H44441004_PIP-SCONN,HA
GND                      J1G1             254      SCONN288_H44441004_PIP-SCONN,HA
GND                      J1G1             257      SCONN288_H44441004_PIP-SCONN,HA
GND                      J1G1             259      SCONN288_H44441004_PIP-SCONN,HA
GND                      J1G1             261      SCONN288_H44441004_PIP-SCONN,HA
GND                      J1G1             263      SCONN288_H44441004_PIP-SCONN,HA
GND                      J1G1             265      SCONN288_H44441004_PIP-SCONN,HA
GND                      J1G1             268      SCONN288_H44441004_PIP-SCONN,HA
GND                      J1G1             270      SCONN288_H44441004_PIP-SCONN,HA
GND                      J1G1             272      SCONN288_H44441004_PIP-SCONN,HA
GND                      J1G1             274      SCONN288_H44441004_PIP-SCONN,HA
GND                      J1G1             276      SCONN288_H44441004_PIP-SCONN,HA
GND                      J1G1             279      SCONN288_H44441004_PIP-SCONN,HA
GND                      J1G1             281      SCONN288_H44441004_PIP-SCONN,HA
GND                      J1G1             283      SCONN288_H44441004_PIP-SCONN,HA
GND                      J1G2             2        SCONN288_H44441004_PIP-SCONN,HA
GND                      J1G2             4        SCONN288_H44441004_PIP-SCONN,HA
GND                      J1G2             6        SCONN288_H44441004_PIP-SCONN,HA
GND                      J1G2             9        SCONN288_H44441004_PIP-SCONN,HA
GND                      J1G2             11       SCONN288_H44441004_PIP-SCONN,HA
GND                      J1G2             13       SCONN288_H44441004_PIP-SCONN,HA
GND                      J1G2             15       SCONN288_H44441004_PIP-SCONN,HA
GND                      J1G2             17       SCONN288_H44441004_PIP-SCONN,HA
GND                      J1G2             20       SCONN288_H44441004_PIP-SCONN,HA
GND                      J1G2             22       SCONN288_H44441004_PIP-SCONN,HA
GND                      J1G2             24       SCONN288_H44441004_PIP-SCONN,HA
GND                      J1G2             26       SCONN288_H44441004_PIP-SCONN,HA
GND                      J1G2             28       SCONN288_H44441004_PIP-SCONN,HA
GND                      J1G2             31       SCONN288_H44441004_PIP-SCONN,HA
GND                      J1G2             33       SCONN288_H44441004_PIP-SCONN,HA
GND                      J1G2             35       SCONN288_H44441004_PIP-SCONN,HA
GND                      J1G2             37       SCONN288_H44441004_PIP-SCONN,HA
GND                      J1G2             39       SCONN288_H44441004_PIP-SCONN,HA
GND                      J1G2             42       SCONN288_H44441004_PIP-SCONN,HA
GND                      J1G2             44       SCONN288_H44441004_PIP-SCONN,HA
GND                      J1G2             46       SCONN288_H44441004_PIP-SCONN,HA
GND                      J1G2             48       SCONN288_H44441004_PIP-SCONN,HA
GND                      J1G2             50       SCONN288_H44441004_PIP-SCONN,HA
GND                      J1G2             53       SCONN288_H44441004_PIP-SCONN,HA
GND                      J1G2             55       SCONN288_H44441004_PIP-SCONN,HA
GND                      J1G2             57       SCONN288_H44441004_PIP-SCONN,HA
GND                      J1G2             94       SCONN288_H44441004_PIP-SCONN,HA
GND                      J1G2             96       SCONN288_H44441004_PIP-SCONN,HA
GND                      J1G2             98       SCONN288_H44441004_PIP-SCONN,HA
GND                      J1G2             101      SCONN288_H44441004_PIP-SCONN,HA
GND                      J1G2             103      SCONN288_H44441004_PIP-SCONN,HA
GND                      J1G2             105      SCONN288_H44441004_PIP-SCONN,HA
GND                      J1G2             107      SCONN288_H44441004_PIP-SCONN,HA
GND                      J1G2             109      SCONN288_H44441004_PIP-SCONN,HA
GND                      J1G2             112      SCONN288_H44441004_PIP-SCONN,HA
GND                      J1G2             114      SCONN288_H44441004_PIP-SCONN,HA
GND                      J1G2             116      SCONN288_H44441004_PIP-SCONN,HA
GND                      J1G2             118      SCONN288_H44441004_PIP-SCONN,HA
GND                      J1G2             120      SCONN288_H44441004_PIP-SCONN,HA
GND                      J1G2             123      SCONN288_H44441004_PIP-SCONN,HA
GND                      J1G2             125      SCONN288_H44441004_PIP-SCONN,HA
GND                      J1G2             127      SCONN288_H44441004_PIP-SCONN,HA
GND                      J1G2             129      SCONN288_H44441004_PIP-SCONN,HA
GND                      J1G2             131      SCONN288_H44441004_PIP-SCONN,HA
GND                      J1G2             134      SCONN288_H44441004_PIP-SCONN,HA
GND                      J1G2             136      SCONN288_H44441004_PIP-SCONN,HA
GND                      J1G2             138      SCONN288_H44441004_PIP-SCONN,HA
GND                      J1G2             139      SCONN288_H44441004_PIP-SCONN,HA
GND                      J1G2             147      SCONN288_H44441004_PIP-SCONN,HA
GND                      J1G2             149      SCONN288_H44441004_PIP-SCONN,HA
GND                      J1G2             151      SCONN288_H44441004_PIP-SCONN,HA
GND                      J1G2             154      SCONN288_H44441004_PIP-SCONN,HA
GND                      J1G2             156      SCONN288_H44441004_PIP-SCONN,HA
GND                      J1G2             158      SCONN288_H44441004_PIP-SCONN,HA
GND                      J1G2             160      SCONN288_H44441004_PIP-SCONN,HA
GND                      J1G2             162      SCONN288_H44441004_PIP-SCONN,HA
GND                      J1G2             165      SCONN288_H44441004_PIP-SCONN,HA
GND                      J1G2             167      SCONN288_H44441004_PIP-SCONN,HA
GND                      J1G2             169      SCONN288_H44441004_PIP-SCONN,HA
GND                      J1G2             171      SCONN288_H44441004_PIP-SCONN,HA
GND                      J1G2             173      SCONN288_H44441004_PIP-SCONN,HA
GND                      J1G2             176      SCONN288_H44441004_PIP-SCONN,HA
GND                      J1G2             178      SCONN288_H44441004_PIP-SCONN,HA
GND                      J1G2             180      SCONN288_H44441004_PIP-SCONN,HA
GND                      J1G2             182      SCONN288_H44441004_PIP-SCONN,HA
GND                      J1G2             184      SCONN288_H44441004_PIP-SCONN,HA
GND                      J1G2             187      SCONN288_H44441004_PIP-SCONN,HA
GND                      J1G2             189      SCONN288_H44441004_PIP-SCONN,HA
GND                      J1G2             191      SCONN288_H44441004_PIP-SCONN,HA
GND                      J1G2             193      SCONN288_H44441004_PIP-SCONN,HA
GND                      J1G2             195      SCONN288_H44441004_PIP-SCONN,HA
GND                      J1G2             198      SCONN288_H44441004_PIP-SCONN,HA
GND                      J1G2             200      SCONN288_H44441004_PIP-SCONN,HA
GND                      J1G2             202      SCONN288_H44441004_PIP-SCONN,HA
GND                      J1G2             238      SCONN288_H44441004_PIP-SCONN,HA
GND                      J1G2             239      SCONN288_H44441004_PIP-SCONN,HA
GND                      J1G2             241      SCONN288_H44441004_PIP-SCONN,HA
GND                      J1G2             243      SCONN288_H44441004_PIP-SCONN,HA
GND                      J1G2             246      SCONN288_H44441004_PIP-SCONN,HA
GND                      J1G2             248      SCONN288_H44441004_PIP-SCONN,HA
GND                      J1G2             250      SCONN288_H44441004_PIP-SCONN,HA
GND                      J1G2             252      SCONN288_H44441004_PIP-SCONN,HA
GND                      J1G2             254      SCONN288_H44441004_PIP-SCONN,HA
GND                      J1G2             257      SCONN288_H44441004_PIP-SCONN,HA
GND                      J1G2             259      SCONN288_H44441004_PIP-SCONN,HA
GND                      J1G2             261      SCONN288_H44441004_PIP-SCONN,HA
GND                      J1G2             263      SCONN288_H44441004_PIP-SCONN,HA
GND                      J1G2             265      SCONN288_H44441004_PIP-SCONN,HA
GND                      J1G2             268      SCONN288_H44441004_PIP-SCONN,HA
GND                      J1G2             270      SCONN288_H44441004_PIP-SCONN,HA
GND                      J1G2             272      SCONN288_H44441004_PIP-SCONN,HA
GND                      J1G2             274      SCONN288_H44441004_PIP-SCONN,HA
GND                      J1G2             276      SCONN288_H44441004_PIP-SCONN,HA
GND                      J1G2             279      SCONN288_H44441004_PIP-SCONN,HA
GND                      J1G2             281      SCONN288_H44441004_PIP-SCONN,HA
GND                      J1G2             283      SCONN288_H44441004_PIP-SCONN,HA
GND                      J1G3             2        SCONN288_H44441004_PIP-SCONN,HA
GND                      J1G3             4        SCONN288_H44441004_PIP-SCONN,HA
GND                      J1G3             6        SCONN288_H44441004_PIP-SCONN,HA
GND                      J1G3             9        SCONN288_H44441004_PIP-SCONN,HA
GND                      J1G3             11       SCONN288_H44441004_PIP-SCONN,HA
GND                      J1G3             13       SCONN288_H44441004_PIP-SCONN,HA
GND                      J1G3             15       SCONN288_H44441004_PIP-SCONN,HA
GND                      J1G3             17       SCONN288_H44441004_PIP-SCONN,HA
GND                      J1G3             20       SCONN288_H44441004_PIP-SCONN,HA
GND                      J1G3             22       SCONN288_H44441004_PIP-SCONN,HA
GND                      J1G3             24       SCONN288_H44441004_PIP-SCONN,HA
GND                      J1G3             26       SCONN288_H44441004_PIP-SCONN,HA
GND                      J1G3             28       SCONN288_H44441004_PIP-SCONN,HA
GND                      J1G3             31       SCONN288_H44441004_PIP-SCONN,HA
GND                      J1G3             33       SCONN288_H44441004_PIP-SCONN,HA
GND                      J1G3             35       SCONN288_H44441004_PIP-SCONN,HA
GND                      J1G3             37       SCONN288_H44441004_PIP-SCONN,HA
GND                      J1G3             39       SCONN288_H44441004_PIP-SCONN,HA
GND                      J1G3             42       SCONN288_H44441004_PIP-SCONN,HA
GND                      J1G3             44       SCONN288_H44441004_PIP-SCONN,HA
GND                      J1G3             46       SCONN288_H44441004_PIP-SCONN,HA
GND                      J1G3             48       SCONN288_H44441004_PIP-SCONN,HA
GND                      J1G3             50       SCONN288_H44441004_PIP-SCONN,HA
GND                      J1G3             53       SCONN288_H44441004_PIP-SCONN,HA
GND                      J1G3             55       SCONN288_H44441004_PIP-SCONN,HA
GND                      J1G3             57       SCONN288_H44441004_PIP-SCONN,HA
GND                      J1G3             94       SCONN288_H44441004_PIP-SCONN,HA
GND                      J1G3             96       SCONN288_H44441004_PIP-SCONN,HA
GND                      J1G3             98       SCONN288_H44441004_PIP-SCONN,HA
GND                      J1G3             101      SCONN288_H44441004_PIP-SCONN,HA
GND                      J1G3             103      SCONN288_H44441004_PIP-SCONN,HA
GND                      J1G3             105      SCONN288_H44441004_PIP-SCONN,HA
GND                      J1G3             107      SCONN288_H44441004_PIP-SCONN,HA
GND                      J1G3             109      SCONN288_H44441004_PIP-SCONN,HA
GND                      J1G3             112      SCONN288_H44441004_PIP-SCONN,HA
GND                      J1G3             114      SCONN288_H44441004_PIP-SCONN,HA
GND                      J1G3             116      SCONN288_H44441004_PIP-SCONN,HA
GND                      J1G3             118      SCONN288_H44441004_PIP-SCONN,HA
GND                      J1G3             120      SCONN288_H44441004_PIP-SCONN,HA
GND                      J1G3             123      SCONN288_H44441004_PIP-SCONN,HA
GND                      J1G3             125      SCONN288_H44441004_PIP-SCONN,HA
GND                      J1G3             127      SCONN288_H44441004_PIP-SCONN,HA
GND                      J1G3             129      SCONN288_H44441004_PIP-SCONN,HA
GND                      J1G3             131      SCONN288_H44441004_PIP-SCONN,HA
GND                      J1G3             134      SCONN288_H44441004_PIP-SCONN,HA
GND                      J1G3             136      SCONN288_H44441004_PIP-SCONN,HA
GND                      J1G3             138      SCONN288_H44441004_PIP-SCONN,HA
GND                      J1G3             139      SCONN288_H44441004_PIP-SCONN,HA
GND                      J1G3             140      SCONN288_H44441004_PIP-SCONN,HA
GND                      J1G3             147      SCONN288_H44441004_PIP-SCONN,HA
GND                      J1G3             149      SCONN288_H44441004_PIP-SCONN,HA
GND                      J1G3             151      SCONN288_H44441004_PIP-SCONN,HA
GND                      J1G3             154      SCONN288_H44441004_PIP-SCONN,HA
GND                      J1G3             156      SCONN288_H44441004_PIP-SCONN,HA
GND                      J1G3             158      SCONN288_H44441004_PIP-SCONN,HA
GND                      J1G3             160      SCONN288_H44441004_PIP-SCONN,HA
GND                      J1G3             162      SCONN288_H44441004_PIP-SCONN,HA
GND                      J1G3             165      SCONN288_H44441004_PIP-SCONN,HA
GND                      J1G3             167      SCONN288_H44441004_PIP-SCONN,HA
GND                      J1G3             169      SCONN288_H44441004_PIP-SCONN,HA
GND                      J1G3             171      SCONN288_H44441004_PIP-SCONN,HA
GND                      J1G3             173      SCONN288_H44441004_PIP-SCONN,HA
GND                      J1G3             176      SCONN288_H44441004_PIP-SCONN,HA
GND                      J1G3             178      SCONN288_H44441004_PIP-SCONN,HA
GND                      J1G3             180      SCONN288_H44441004_PIP-SCONN,HA
GND                      J1G3             182      SCONN288_H44441004_PIP-SCONN,HA
GND                      J1G3             184      SCONN288_H44441004_PIP-SCONN,HA
GND                      J1G3             187      SCONN288_H44441004_PIP-SCONN,HA
GND                      J1G3             189      SCONN288_H44441004_PIP-SCONN,HA
GND                      J1G3             191      SCONN288_H44441004_PIP-SCONN,HA
GND                      J1G3             193      SCONN288_H44441004_PIP-SCONN,HA
GND                      J1G3             195      SCONN288_H44441004_PIP-SCONN,HA
GND                      J1G3             198      SCONN288_H44441004_PIP-SCONN,HA
GND                      J1G3             200      SCONN288_H44441004_PIP-SCONN,HA
GND                      J1G3             202      SCONN288_H44441004_PIP-SCONN,HA
GND                      J1G3             239      SCONN288_H44441004_PIP-SCONN,HA
GND                      J1G3             241      SCONN288_H44441004_PIP-SCONN,HA
GND                      J1G3             243      SCONN288_H44441004_PIP-SCONN,HA
GND                      J1G3             246      SCONN288_H44441004_PIP-SCONN,HA
GND                      J1G3             248      SCONN288_H44441004_PIP-SCONN,HA
GND                      J1G3             250      SCONN288_H44441004_PIP-SCONN,HA
GND                      J1G3             252      SCONN288_H44441004_PIP-SCONN,HA
GND                      J1G3             254      SCONN288_H44441004_PIP-SCONN,HA
GND                      J1G3             257      SCONN288_H44441004_PIP-SCONN,HA
GND                      J1G3             259      SCONN288_H44441004_PIP-SCONN,HA
GND                      J1G3             261      SCONN288_H44441004_PIP-SCONN,HA
GND                      J1G3             263      SCONN288_H44441004_PIP-SCONN,HA
GND                      J1G3             265      SCONN288_H44441004_PIP-SCONN,HA
GND                      J1G3             268      SCONN288_H44441004_PIP-SCONN,HA
GND                      J1G3             270      SCONN288_H44441004_PIP-SCONN,HA
GND                      J1G3             272      SCONN288_H44441004_PIP-SCONN,HA
GND                      J1G3             274      SCONN288_H44441004_PIP-SCONN,HA
GND                      J1G3             276      SCONN288_H44441004_PIP-SCONN,HA
GND                      J1G3             279      SCONN288_H44441004_PIP-SCONN,HA
GND                      J1G3             281      SCONN288_H44441004_PIP-SCONN,HA
GND                      J1G3             283      SCONN288_H44441004_PIP-SCONN,HA
GND                      J2L1             2        CONN4_H73295001_PIP-CONN,H7329A
GND                      J2L1             3        CONN4_H73295001_PIP-CONN,H7329A
GND                      J2M1             1        CONN7_E82125014_PIP_TH-CONN,E8A
GND                      J2M1             4        CONN7_E82125014_PIP_TH-CONN,E8A
GND                      J2M1             7        CONN7_E82125014_PIP_TH-CONN,E8A
GND                      J2M1             MH1      CONN7_E82125014_PIP_TH-CONN,E8A
GND                      J2M1             MH2      CONN7_E82125014_PIP_TH-CONN,E8A
GND                      J4A1             2        SCONN288_H44441004_PIP-SCONN,HA
GND                      J4A1             4        SCONN288_H44441004_PIP-SCONN,HA
GND                      J4A1             6        SCONN288_H44441004_PIP-SCONN,HA
GND                      J4A1             9        SCONN288_H44441004_PIP-SCONN,HA
GND                      J4A1             11       SCONN288_H44441004_PIP-SCONN,HA
GND                      J4A1             13       SCONN288_H44441004_PIP-SCONN,HA
GND                      J4A1             15       SCONN288_H44441004_PIP-SCONN,HA
GND                      J4A1             17       SCONN288_H44441004_PIP-SCONN,HA
GND                      J4A1             20       SCONN288_H44441004_PIP-SCONN,HA
GND                      J4A1             22       SCONN288_H44441004_PIP-SCONN,HA
GND                      J4A1             24       SCONN288_H44441004_PIP-SCONN,HA
GND                      J4A1             26       SCONN288_H44441004_PIP-SCONN,HA
GND                      J4A1             28       SCONN288_H44441004_PIP-SCONN,HA
GND                      J4A1             31       SCONN288_H44441004_PIP-SCONN,HA
GND                      J4A1             33       SCONN288_H44441004_PIP-SCONN,HA
GND                      J4A1             35       SCONN288_H44441004_PIP-SCONN,HA
GND                      J4A1             37       SCONN288_H44441004_PIP-SCONN,HA
GND                      J4A1             39       SCONN288_H44441004_PIP-SCONN,HA
GND                      J4A1             42       SCONN288_H44441004_PIP-SCONN,HA
GND                      J4A1             44       SCONN288_H44441004_PIP-SCONN,HA
GND                      J4A1             46       SCONN288_H44441004_PIP-SCONN,HA
GND                      J4A1             48       SCONN288_H44441004_PIP-SCONN,HA
GND                      J4A1             50       SCONN288_H44441004_PIP-SCONN,HA
GND                      J4A1             53       SCONN288_H44441004_PIP-SCONN,HA
GND                      J4A1             55       SCONN288_H44441004_PIP-SCONN,HA
GND                      J4A1             57       SCONN288_H44441004_PIP-SCONN,HA
GND                      J4A1             94       SCONN288_H44441004_PIP-SCONN,HA
GND                      J4A1             96       SCONN288_H44441004_PIP-SCONN,HA
GND                      J4A1             98       SCONN288_H44441004_PIP-SCONN,HA
GND                      J4A1             101      SCONN288_H44441004_PIP-SCONN,HA
GND                      J4A1             103      SCONN288_H44441004_PIP-SCONN,HA
GND                      J4A1             105      SCONN288_H44441004_PIP-SCONN,HA
GND                      J4A1             107      SCONN288_H44441004_PIP-SCONN,HA
GND                      J4A1             109      SCONN288_H44441004_PIP-SCONN,HA
GND                      J4A1             112      SCONN288_H44441004_PIP-SCONN,HA
GND                      J4A1             114      SCONN288_H44441004_PIP-SCONN,HA
GND                      J4A1             116      SCONN288_H44441004_PIP-SCONN,HA
GND                      J4A1             118      SCONN288_H44441004_PIP-SCONN,HA
GND                      J4A1             120      SCONN288_H44441004_PIP-SCONN,HA
GND                      J4A1             123      SCONN288_H44441004_PIP-SCONN,HA
GND                      J4A1             125      SCONN288_H44441004_PIP-SCONN,HA
GND                      J4A1             127      SCONN288_H44441004_PIP-SCONN,HA
GND                      J4A1             129      SCONN288_H44441004_PIP-SCONN,HA
GND                      J4A1             131      SCONN288_H44441004_PIP-SCONN,HA
GND                      J4A1             134      SCONN288_H44441004_PIP-SCONN,HA
GND                      J4A1             136      SCONN288_H44441004_PIP-SCONN,HA
GND                      J4A1             138      SCONN288_H44441004_PIP-SCONN,HA
GND                      J4A1             139      SCONN288_H44441004_PIP-SCONN,HA
GND                      J4A1             140      SCONN288_H44441004_PIP-SCONN,HA
GND                      J4A1             147      SCONN288_H44441004_PIP-SCONN,HA
GND                      J4A1             149      SCONN288_H44441004_PIP-SCONN,HA
GND                      J4A1             151      SCONN288_H44441004_PIP-SCONN,HA
GND                      J4A1             154      SCONN288_H44441004_PIP-SCONN,HA
GND                      J4A1             156      SCONN288_H44441004_PIP-SCONN,HA
GND                      J4A1             158      SCONN288_H44441004_PIP-SCONN,HA
GND                      J4A1             160      SCONN288_H44441004_PIP-SCONN,HA
GND                      J4A1             162      SCONN288_H44441004_PIP-SCONN,HA
GND                      J4A1             165      SCONN288_H44441004_PIP-SCONN,HA
GND                      J4A1             167      SCONN288_H44441004_PIP-SCONN,HA
GND                      J4A1             169      SCONN288_H44441004_PIP-SCONN,HA
GND                      J4A1             171      SCONN288_H44441004_PIP-SCONN,HA
GND                      J4A1             173      SCONN288_H44441004_PIP-SCONN,HA
GND                      J4A1             176      SCONN288_H44441004_PIP-SCONN,HA
GND                      J4A1             178      SCONN288_H44441004_PIP-SCONN,HA
GND                      J4A1             180      SCONN288_H44441004_PIP-SCONN,HA
GND                      J4A1             182      SCONN288_H44441004_PIP-SCONN,HA
GND                      J4A1             184      SCONN288_H44441004_PIP-SCONN,HA
GND                      J4A1             187      SCONN288_H44441004_PIP-SCONN,HA
GND                      J4A1             189      SCONN288_H44441004_PIP-SCONN,HA
GND                      J4A1             191      SCONN288_H44441004_PIP-SCONN,HA
GND                      J4A1             193      SCONN288_H44441004_PIP-SCONN,HA
GND                      J4A1             195      SCONN288_H44441004_PIP-SCONN,HA
GND                      J4A1             198      SCONN288_H44441004_PIP-SCONN,HA
GND                      J4A1             200      SCONN288_H44441004_PIP-SCONN,HA
GND                      J4A1             202      SCONN288_H44441004_PIP-SCONN,HA
GND                      J4A1             239      SCONN288_H44441004_PIP-SCONN,HA
GND                      J4A1             241      SCONN288_H44441004_PIP-SCONN,HA
GND                      J4A1             243      SCONN288_H44441004_PIP-SCONN,HA
GND                      J4A1             246      SCONN288_H44441004_PIP-SCONN,HA
GND                      J4A1             248      SCONN288_H44441004_PIP-SCONN,HA
GND                      J4A1             250      SCONN288_H44441004_PIP-SCONN,HA
GND                      J4A1             252      SCONN288_H44441004_PIP-SCONN,HA
GND                      J4A1             254      SCONN288_H44441004_PIP-SCONN,HA
GND                      J4A1             257      SCONN288_H44441004_PIP-SCONN,HA
GND                      J4A1             259      SCONN288_H44441004_PIP-SCONN,HA
GND                      J4A1             261      SCONN288_H44441004_PIP-SCONN,HA
GND                      J4A1             263      SCONN288_H44441004_PIP-SCONN,HA
GND                      J4A1             265      SCONN288_H44441004_PIP-SCONN,HA
GND                      J4A1             268      SCONN288_H44441004_PIP-SCONN,HA
GND                      J4A1             270      SCONN288_H44441004_PIP-SCONN,HA
GND                      J4A1             272      SCONN288_H44441004_PIP-SCONN,HA
GND                      J4A1             274      SCONN288_H44441004_PIP-SCONN,HA
GND                      J4A1             276      SCONN288_H44441004_PIP-SCONN,HA
GND                      J4A1             279      SCONN288_H44441004_PIP-SCONN,HA
GND                      J4A1             281      SCONN288_H44441004_PIP-SCONN,HA
GND                      J4A1             283      SCONN288_H44441004_PIP-SCONN,HA
GND                      J4A2             2        SCONN288_H44441004_PIP-SCONN,HA
GND                      J4A2             4        SCONN288_H44441004_PIP-SCONN,HA
GND                      J4A2             6        SCONN288_H44441004_PIP-SCONN,HA
GND                      J4A2             9        SCONN288_H44441004_PIP-SCONN,HA
GND                      J4A2             11       SCONN288_H44441004_PIP-SCONN,HA
GND                      J4A2             13       SCONN288_H44441004_PIP-SCONN,HA
GND                      J4A2             15       SCONN288_H44441004_PIP-SCONN,HA
GND                      J4A2             17       SCONN288_H44441004_PIP-SCONN,HA
GND                      J4A2             20       SCONN288_H44441004_PIP-SCONN,HA
GND                      J4A2             22       SCONN288_H44441004_PIP-SCONN,HA
GND                      J4A2             24       SCONN288_H44441004_PIP-SCONN,HA
GND                      J4A2             26       SCONN288_H44441004_PIP-SCONN,HA
GND                      J4A2             28       SCONN288_H44441004_PIP-SCONN,HA
GND                      J4A2             31       SCONN288_H44441004_PIP-SCONN,HA
GND                      J4A2             33       SCONN288_H44441004_PIP-SCONN,HA
GND                      J4A2             35       SCONN288_H44441004_PIP-SCONN,HA
GND                      J4A2             37       SCONN288_H44441004_PIP-SCONN,HA
GND                      J4A2             39       SCONN288_H44441004_PIP-SCONN,HA
GND                      J4A2             42       SCONN288_H44441004_PIP-SCONN,HA
GND                      J4A2             44       SCONN288_H44441004_PIP-SCONN,HA
GND                      J4A2             46       SCONN288_H44441004_PIP-SCONN,HA
GND                      J4A2             48       SCONN288_H44441004_PIP-SCONN,HA
GND                      J4A2             50       SCONN288_H44441004_PIP-SCONN,HA
GND                      J4A2             53       SCONN288_H44441004_PIP-SCONN,HA
GND                      J4A2             55       SCONN288_H44441004_PIP-SCONN,HA
GND                      J4A2             57       SCONN288_H44441004_PIP-SCONN,HA
GND                      J4A2             94       SCONN288_H44441004_PIP-SCONN,HA
GND                      J4A2             96       SCONN288_H44441004_PIP-SCONN,HA
GND                      J4A2             98       SCONN288_H44441004_PIP-SCONN,HA
GND                      J4A2             101      SCONN288_H44441004_PIP-SCONN,HA
GND                      J4A2             103      SCONN288_H44441004_PIP-SCONN,HA
GND                      J4A2             105      SCONN288_H44441004_PIP-SCONN,HA
GND                      J4A2             107      SCONN288_H44441004_PIP-SCONN,HA
GND                      J4A2             109      SCONN288_H44441004_PIP-SCONN,HA
GND                      J4A2             112      SCONN288_H44441004_PIP-SCONN,HA
GND                      J4A2             114      SCONN288_H44441004_PIP-SCONN,HA
GND                      J4A2             116      SCONN288_H44441004_PIP-SCONN,HA
GND                      J4A2             118      SCONN288_H44441004_PIP-SCONN,HA
GND                      J4A2             120      SCONN288_H44441004_PIP-SCONN,HA
GND                      J4A2             123      SCONN288_H44441004_PIP-SCONN,HA
GND                      J4A2             125      SCONN288_H44441004_PIP-SCONN,HA
GND                      J4A2             127      SCONN288_H44441004_PIP-SCONN,HA
GND                      J4A2             129      SCONN288_H44441004_PIP-SCONN,HA
GND                      J4A2             131      SCONN288_H44441004_PIP-SCONN,HA
GND                      J4A2             134      SCONN288_H44441004_PIP-SCONN,HA
GND                      J4A2             136      SCONN288_H44441004_PIP-SCONN,HA
GND                      J4A2             138      SCONN288_H44441004_PIP-SCONN,HA
GND                      J4A2             139      SCONN288_H44441004_PIP-SCONN,HA
GND                      J4A2             147      SCONN288_H44441004_PIP-SCONN,HA
GND                      J4A2             149      SCONN288_H44441004_PIP-SCONN,HA
GND                      J4A2             151      SCONN288_H44441004_PIP-SCONN,HA
GND                      J4A2             154      SCONN288_H44441004_PIP-SCONN,HA
GND                      J4A2             156      SCONN288_H44441004_PIP-SCONN,HA
GND                      J4A2             158      SCONN288_H44441004_PIP-SCONN,HA
GND                      J4A2             160      SCONN288_H44441004_PIP-SCONN,HA
GND                      J4A2             162      SCONN288_H44441004_PIP-SCONN,HA
GND                      J4A2             165      SCONN288_H44441004_PIP-SCONN,HA
GND                      J4A2             167      SCONN288_H44441004_PIP-SCONN,HA
GND                      J4A2             169      SCONN288_H44441004_PIP-SCONN,HA
GND                      J4A2             171      SCONN288_H44441004_PIP-SCONN,HA
GND                      J4A2             173      SCONN288_H44441004_PIP-SCONN,HA
GND                      J4A2             176      SCONN288_H44441004_PIP-SCONN,HA
GND                      J4A2             178      SCONN288_H44441004_PIP-SCONN,HA
GND                      J4A2             180      SCONN288_H44441004_PIP-SCONN,HA
GND                      J4A2             182      SCONN288_H44441004_PIP-SCONN,HA
GND                      J4A2             184      SCONN288_H44441004_PIP-SCONN,HA
GND                      J4A2             187      SCONN288_H44441004_PIP-SCONN,HA
GND                      J4A2             189      SCONN288_H44441004_PIP-SCONN,HA
GND                      J4A2             191      SCONN288_H44441004_PIP-SCONN,HA
GND                      J4A2             193      SCONN288_H44441004_PIP-SCONN,HA
GND                      J4A2             195      SCONN288_H44441004_PIP-SCONN,HA
GND                      J4A2             198      SCONN288_H44441004_PIP-SCONN,HA
GND                      J4A2             200      SCONN288_H44441004_PIP-SCONN,HA
GND                      J4A2             202      SCONN288_H44441004_PIP-SCONN,HA
GND                      J4A2             238      SCONN288_H44441004_PIP-SCONN,HA
GND                      J4A2             239      SCONN288_H44441004_PIP-SCONN,HA
GND                      J4A2             241      SCONN288_H44441004_PIP-SCONN,HA
GND                      J4A2             243      SCONN288_H44441004_PIP-SCONN,HA
GND                      J4A2             246      SCONN288_H44441004_PIP-SCONN,HA
GND                      J4A2             248      SCONN288_H44441004_PIP-SCONN,HA
GND                      J4A2             250      SCONN288_H44441004_PIP-SCONN,HA
GND                      J4A2             252      SCONN288_H44441004_PIP-SCONN,HA
GND                      J4A2             254      SCONN288_H44441004_PIP-SCONN,HA
GND                      J4A2             257      SCONN288_H44441004_PIP-SCONN,HA
GND                      J4A2             259      SCONN288_H44441004_PIP-SCONN,HA
GND                      J4A2             261      SCONN288_H44441004_PIP-SCONN,HA
GND                      J4A2             263      SCONN288_H44441004_PIP-SCONN,HA
GND                      J4A2             265      SCONN288_H44441004_PIP-SCONN,HA
GND                      J4A2             268      SCONN288_H44441004_PIP-SCONN,HA
GND                      J4A2             270      SCONN288_H44441004_PIP-SCONN,HA
GND                      J4A2             272      SCONN288_H44441004_PIP-SCONN,HA
GND                      J4A2             274      SCONN288_H44441004_PIP-SCONN,HA
GND                      J4A2             276      SCONN288_H44441004_PIP-SCONN,HA
GND                      J4A2             279      SCONN288_H44441004_PIP-SCONN,HA
GND                      J4A2             281      SCONN288_H44441004_PIP-SCONN,HA
GND                      J4A2             283      SCONN288_H44441004_PIP-SCONN,HA
GND                      J4B1             2        SCONN288_H44441004_PIP-SCONN,HA
GND                      J4B1             4        SCONN288_H44441004_PIP-SCONN,HA
GND                      J4B1             6        SCONN288_H44441004_PIP-SCONN,HA
GND                      J4B1             9        SCONN288_H44441004_PIP-SCONN,HA
GND                      J4B1             11       SCONN288_H44441004_PIP-SCONN,HA
GND                      J4B1             13       SCONN288_H44441004_PIP-SCONN,HA
GND                      J4B1             15       SCONN288_H44441004_PIP-SCONN,HA
GND                      J4B1             17       SCONN288_H44441004_PIP-SCONN,HA
GND                      J4B1             20       SCONN288_H44441004_PIP-SCONN,HA
GND                      J4B1             22       SCONN288_H44441004_PIP-SCONN,HA
GND                      J4B1             24       SCONN288_H44441004_PIP-SCONN,HA
GND                      J4B1             26       SCONN288_H44441004_PIP-SCONN,HA
GND                      J4B1             28       SCONN288_H44441004_PIP-SCONN,HA
GND                      J4B1             31       SCONN288_H44441004_PIP-SCONN,HA
GND                      J4B1             33       SCONN288_H44441004_PIP-SCONN,HA
GND                      J4B1             35       SCONN288_H44441004_PIP-SCONN,HA
GND                      J4B1             37       SCONN288_H44441004_PIP-SCONN,HA
GND                      J4B1             39       SCONN288_H44441004_PIP-SCONN,HA
GND                      J4B1             42       SCONN288_H44441004_PIP-SCONN,HA
GND                      J4B1             44       SCONN288_H44441004_PIP-SCONN,HA
GND                      J4B1             46       SCONN288_H44441004_PIP-SCONN,HA
GND                      J4B1             48       SCONN288_H44441004_PIP-SCONN,HA
GND                      J4B1             50       SCONN288_H44441004_PIP-SCONN,HA
GND                      J4B1             53       SCONN288_H44441004_PIP-SCONN,HA
GND                      J4B1             55       SCONN288_H44441004_PIP-SCONN,HA
GND                      J4B1             57       SCONN288_H44441004_PIP-SCONN,HA
GND                      J4B1             94       SCONN288_H44441004_PIP-SCONN,HA
GND                      J4B1             96       SCONN288_H44441004_PIP-SCONN,HA
GND                      J4B1             98       SCONN288_H44441004_PIP-SCONN,HA
GND                      J4B1             101      SCONN288_H44441004_PIP-SCONN,HA
GND                      J4B1             103      SCONN288_H44441004_PIP-SCONN,HA
GND                      J4B1             105      SCONN288_H44441004_PIP-SCONN,HA
GND                      J4B1             107      SCONN288_H44441004_PIP-SCONN,HA
GND                      J4B1             109      SCONN288_H44441004_PIP-SCONN,HA
GND                      J4B1             112      SCONN288_H44441004_PIP-SCONN,HA
GND                      J4B1             114      SCONN288_H44441004_PIP-SCONN,HA
GND                      J4B1             116      SCONN288_H44441004_PIP-SCONN,HA
GND                      J4B1             118      SCONN288_H44441004_PIP-SCONN,HA
GND                      J4B1             120      SCONN288_H44441004_PIP-SCONN,HA
GND                      J4B1             123      SCONN288_H44441004_PIP-SCONN,HA
GND                      J4B1             125      SCONN288_H44441004_PIP-SCONN,HA
GND                      J4B1             127      SCONN288_H44441004_PIP-SCONN,HA
GND                      J4B1             129      SCONN288_H44441004_PIP-SCONN,HA
GND                      J4B1             131      SCONN288_H44441004_PIP-SCONN,HA
GND                      J4B1             134      SCONN288_H44441004_PIP-SCONN,HA
GND                      J4B1             136      SCONN288_H44441004_PIP-SCONN,HA
GND                      J4B1             138      SCONN288_H44441004_PIP-SCONN,HA
GND                      J4B1             139      SCONN288_H44441004_PIP-SCONN,HA
GND                      J4B1             140      SCONN288_H44441004_PIP-SCONN,HA
GND                      J4B1             147      SCONN288_H44441004_PIP-SCONN,HA
GND                      J4B1             149      SCONN288_H44441004_PIP-SCONN,HA
GND                      J4B1             151      SCONN288_H44441004_PIP-SCONN,HA
GND                      J4B1             154      SCONN288_H44441004_PIP-SCONN,HA
GND                      J4B1             156      SCONN288_H44441004_PIP-SCONN,HA
GND                      J4B1             158      SCONN288_H44441004_PIP-SCONN,HA
GND                      J4B1             160      SCONN288_H44441004_PIP-SCONN,HA
GND                      J4B1             162      SCONN288_H44441004_PIP-SCONN,HA
GND                      J4B1             165      SCONN288_H44441004_PIP-SCONN,HA
GND                      J4B1             167      SCONN288_H44441004_PIP-SCONN,HA
GND                      J4B1             169      SCONN288_H44441004_PIP-SCONN,HA
GND                      J4B1             171      SCONN288_H44441004_PIP-SCONN,HA
GND                      J4B1             173      SCONN288_H44441004_PIP-SCONN,HA
GND                      J4B1             176      SCONN288_H44441004_PIP-SCONN,HA
GND                      J4B1             178      SCONN288_H44441004_PIP-SCONN,HA
GND                      J4B1             180      SCONN288_H44441004_PIP-SCONN,HA
GND                      J4B1             182      SCONN288_H44441004_PIP-SCONN,HA
GND                      J4B1             184      SCONN288_H44441004_PIP-SCONN,HA
GND                      J4B1             187      SCONN288_H44441004_PIP-SCONN,HA
GND                      J4B1             189      SCONN288_H44441004_PIP-SCONN,HA
GND                      J4B1             191      SCONN288_H44441004_PIP-SCONN,HA
GND                      J4B1             193      SCONN288_H44441004_PIP-SCONN,HA
GND                      J4B1             195      SCONN288_H44441004_PIP-SCONN,HA
GND                      J4B1             198      SCONN288_H44441004_PIP-SCONN,HA
GND                      J4B1             200      SCONN288_H44441004_PIP-SCONN,HA
GND                      J4B1             202      SCONN288_H44441004_PIP-SCONN,HA
GND                      J4B1             238      SCONN288_H44441004_PIP-SCONN,HA
GND                      J4B1             239      SCONN288_H44441004_PIP-SCONN,HA
GND                      J4B1             241      SCONN288_H44441004_PIP-SCONN,HA
GND                      J4B1             243      SCONN288_H44441004_PIP-SCONN,HA
GND                      J4B1             246      SCONN288_H44441004_PIP-SCONN,HA
GND                      J4B1             248      SCONN288_H44441004_PIP-SCONN,HA
GND                      J4B1             250      SCONN288_H44441004_PIP-SCONN,HA
GND                      J4B1             252      SCONN288_H44441004_PIP-SCONN,HA
GND                      J4B1             254      SCONN288_H44441004_PIP-SCONN,HA
GND                      J4B1             257      SCONN288_H44441004_PIP-SCONN,HA
GND                      J4B1             259      SCONN288_H44441004_PIP-SCONN,HA
GND                      J4B1             261      SCONN288_H44441004_PIP-SCONN,HA
GND                      J4B1             263      SCONN288_H44441004_PIP-SCONN,HA
GND                      J4B1             265      SCONN288_H44441004_PIP-SCONN,HA
GND                      J4B1             268      SCONN288_H44441004_PIP-SCONN,HA
GND                      J4B1             270      SCONN288_H44441004_PIP-SCONN,HA
GND                      J4B1             272      SCONN288_H44441004_PIP-SCONN,HA
GND                      J4B1             274      SCONN288_H44441004_PIP-SCONN,HA
GND                      J4B1             276      SCONN288_H44441004_PIP-SCONN,HA
GND                      J4B1             279      SCONN288_H44441004_PIP-SCONN,HA
GND                      J4B1             281      SCONN288_H44441004_PIP-SCONN,HA
GND                      J4B1             283      SCONN288_H44441004_PIP-SCONN,HA
GND                      J4B2             A9       SCONN120_H61426002_SM-CONN,H61A
GND                      J4B2             A10      SCONN120_H61426002_SM-CONN,H61A
GND                      J4B2             A12      SCONN120_H61426002_SM-CONN,H61A
GND                      J4B2             A14      SCONN120_H61426002_SM-CONN,H61A
GND                      J4B2             A17      SCONN120_H61426002_SM-CONN,H61A
GND                      J4B2             B9       SCONN120_H61426002_SM-CONN,H61A
GND                      J4B2             B10      SCONN120_H61426002_SM-CONN,H61A
GND                      J4B2             B12      SCONN120_H61426002_SM-CONN,H61A
GND                      J4B2             B14      SCONN120_H61426002_SM-CONN,H61A
GND                      J4B2             B17      SCONN120_H61426002_SM-CONN,H61A
GND                      J4B2             C1       SCONN120_H61426002_SM-CONN,H61A
GND                      J4B2             C2       SCONN120_H61426002_SM-CONN,H61A
GND                      J4B2             C3       SCONN120_H61426002_SM-CONN,H61A
GND                      J4B2             C4       SCONN120_H61426002_SM-CONN,H61A
GND                      J4B2             C5       SCONN120_H61426002_SM-CONN,H61A
GND                      J4B2             C6       SCONN120_H61426002_SM-CONN,H61A
GND                      J4B2             C7       SCONN120_H61426002_SM-CONN,H61A
GND                      J4B2             C8       SCONN120_H61426002_SM-CONN,H61A
GND                      J4B2             C9       SCONN120_H61426002_SM-CONN,H61A
GND                      J4B2             C10      SCONN120_H61426002_SM-CONN,H61A
GND                      J4B2             C12      SCONN120_H61426002_SM-CONN,H61A
GND                      J4B2             C14      SCONN120_H61426002_SM-CONN,H61A
GND                      J4B2             C15      SCONN120_H61426002_SM-CONN,H61A
GND                      J4B2             C16      SCONN120_H61426002_SM-CONN,H61A
GND                      J4B2             D2       SCONN120_H61426002_SM-CONN,H61A
GND                      J4B2             D3       SCONN120_H61426002_SM-CONN,H61A
GND                      J4B2             D4       SCONN120_H61426002_SM-CONN,H61A
GND                      J4B2             D5       SCONN120_H61426002_SM-CONN,H61A
GND                      J4B2             D6       SCONN120_H61426002_SM-CONN,H61A
GND                      J4B2             D7       SCONN120_H61426002_SM-CONN,H61A
GND                      J4B2             D8       SCONN120_H61426002_SM-CONN,H61A
GND                      J4B2             D9       SCONN120_H61426002_SM-CONN,H61A
GND                      J4B2             D10      SCONN120_H61426002_SM-CONN,H61A
GND                      J4B2             D11      SCONN120_H61426002_SM-CONN,H61A
GND                      J4B2             D12      SCONN120_H61426002_SM-CONN,H61A
GND                      J4B2             D13      SCONN120_H61426002_SM-CONN,H61A
GND                      J4B2             D14      SCONN120_H61426002_SM-CONN,H61A
GND                      J4B2             E2       SCONN120_H61426002_SM-CONN,H61A
GND                      J4B2             E3       SCONN120_H61426002_SM-CONN,H61A
GND                      J4B2             E4       SCONN120_H61426002_SM-CONN,H61A
GND                      J4B2             E5       SCONN120_H61426002_SM-CONN,H61A
GND                      J4B2             E6       SCONN120_H61426002_SM-CONN,H61A
GND                      J4B2             E7       SCONN120_H61426002_SM-CONN,H61A
GND                      J4B2             E9       SCONN120_H61426002_SM-CONN,H61A
GND                      J4B2             E11      SCONN120_H61426002_SM-CONN,H61A
GND                      J4B2             E12      SCONN120_H61426002_SM-CONN,H61A
GND                      J4B2             E13      SCONN120_H61426002_SM-CONN,H61A
GND                      J4B2             E14      SCONN120_H61426002_SM-CONN,H61A
GND                      J4B2             F2       SCONN120_H61426002_SM-CONN,H61A
GND                      J4B2             F3       SCONN120_H61426002_SM-CONN,H61A
GND                      J4B2             F4       SCONN120_H61426002_SM-CONN,H61A
GND                      J4B2             F5       SCONN120_H61426002_SM-CONN,H61A
GND                      J4B2             F6       SCONN120_H61426002_SM-CONN,H61A
GND                      J4B2             F7       SCONN120_H61426002_SM-CONN,H61A
GND                      J4B2             F9       SCONN120_H61426002_SM-CONN,H61A
GND                      J4B2             F11      SCONN120_H61426002_SM-CONN,H61A
GND                      J4B2             F12      SCONN120_H61426002_SM-CONN,H61A
GND                      J4B2             F13      SCONN120_H61426002_SM-CONN,H61A
GND                      J4B2             F14      SCONN120_H61426002_SM-CONN,H61A
GND                      J4E1             A19      SCONN120_H61426002_SM-CONN,H61A
GND                      J4E1             A20      SCONN120_H61426002_SM-CONN,H61A
GND                      J4E1             B19      SCONN120_H61426002_SM-CONN,H61A
GND                      J4E1             B20      SCONN120_H61426002_SM-CONN,H61A
GND                      J4E1             C19      SCONN120_H61426002_SM-CONN,H61A
GND                      J4E1             C20      SCONN120_H61426002_SM-CONN,H61A
GND                      J4E1             D3       SCONN120_H61426002_SM-CONN,H61A
GND                      J4E1             D4       SCONN120_H61426002_SM-CONN,H61A
GND                      J4E1             D5       SCONN120_H61426002_SM-CONN,H61A
GND                      J4E1             D6       SCONN120_H61426002_SM-CONN,H61A
GND                      J4E1             D7       SCONN120_H61426002_SM-CONN,H61A
GND                      J4E1             D8       SCONN120_H61426002_SM-CONN,H61A
GND                      J4E1             D9       SCONN120_H61426002_SM-CONN,H61A
GND                      J4E1             D10      SCONN120_H61426002_SM-CONN,H61A
GND                      J4E1             D11      SCONN120_H61426002_SM-CONN,H61A
GND                      J4E1             D12      SCONN120_H61426002_SM-CONN,H61A
GND                      J4E1             D13      SCONN120_H61426002_SM-CONN,H61A
GND                      J4E1             D14      SCONN120_H61426002_SM-CONN,H61A
GND                      J4E1             D15      SCONN120_H61426002_SM-CONN,H61A
GND                      J4E1             D16      SCONN120_H61426002_SM-CONN,H61A
GND                      J4E1             D17      SCONN120_H61426002_SM-CONN,H61A
GND                      J4E1             D18      SCONN120_H61426002_SM-CONN,H61A
GND                      J4E1             D19      SCONN120_H61426002_SM-CONN,H61A
GND                      J4E1             D20      SCONN120_H61426002_SM-CONN,H61A
GND                      J4E1             E3       SCONN120_H61426002_SM-CONN,H61A
GND                      J4E1             E4       SCONN120_H61426002_SM-CONN,H61A
GND                      J4E1             E6       SCONN120_H61426002_SM-CONN,H61A
GND                      J4E1             E7       SCONN120_H61426002_SM-CONN,H61A
GND                      J4E1             E8       SCONN120_H61426002_SM-CONN,H61A
GND                      J4E1             E9       SCONN120_H61426002_SM-CONN,H61A
GND                      J4E1             E10      SCONN120_H61426002_SM-CONN,H61A
GND                      J4E1             E11      SCONN120_H61426002_SM-CONN,H61A
GND                      J4E1             E12      SCONN120_H61426002_SM-CONN,H61A
GND                      J4E1             E13      SCONN120_H61426002_SM-CONN,H61A
GND                      J4E1             E14      SCONN120_H61426002_SM-CONN,H61A
GND                      J4E1             E15      SCONN120_H61426002_SM-CONN,H61A
GND                      J4E1             E16      SCONN120_H61426002_SM-CONN,H61A
GND                      J4E1             E17      SCONN120_H61426002_SM-CONN,H61A
GND                      J4E1             E18      SCONN120_H61426002_SM-CONN,H61A
GND                      J4E1             E19      SCONN120_H61426002_SM-CONN,H61A
GND                      J4E1             E20      SCONN120_H61426002_SM-CONN,H61A
GND                      J4E1             F3       SCONN120_H61426002_SM-CONN,H61A
GND                      J4E1             F4       SCONN120_H61426002_SM-CONN,H61A
GND                      J4E1             F6       SCONN120_H61426002_SM-CONN,H61A
GND                      J4E1             F7       SCONN120_H61426002_SM-CONN,H61A
GND                      J4E1             F8       SCONN120_H61426002_SM-CONN,H61A
GND                      J4E1             F9       SCONN120_H61426002_SM-CONN,H61A
GND                      J4E1             F10      SCONN120_H61426002_SM-CONN,H61A
GND                      J4E1             F11      SCONN120_H61426002_SM-CONN,H61A
GND                      J4E1             F12      SCONN120_H61426002_SM-CONN,H61A
GND                      J4E1             F13      SCONN120_H61426002_SM-CONN,H61A
GND                      J4E1             F14      SCONN120_H61426002_SM-CONN,H61A
GND                      J4E1             F15      SCONN120_H61426002_SM-CONN,H61A
GND                      J4E1             F16      SCONN120_H61426002_SM-CONN,H61A
GND                      J4E1             F17      SCONN120_H61426002_SM-CONN,H61A
GND                      J4E1             F18      SCONN120_H61426002_SM-CONN,H61A
GND                      J4E1             F19      SCONN120_H61426002_SM-CONN,H61A
GND                      J4E1             F20      SCONN120_H61426002_SM-CONN,H61A
GND                      J4G1             2        SCONN288_H44441004_PIP-SCONN,HA
GND                      J4G1             4        SCONN288_H44441004_PIP-SCONN,HA
GND                      J4G1             6        SCONN288_H44441004_PIP-SCONN,HA
GND                      J4G1             9        SCONN288_H44441004_PIP-SCONN,HA
GND                      J4G1             11       SCONN288_H44441004_PIP-SCONN,HA
GND                      J4G1             13       SCONN288_H44441004_PIP-SCONN,HA
GND                      J4G1             15       SCONN288_H44441004_PIP-SCONN,HA
GND                      J4G1             17       SCONN288_H44441004_PIP-SCONN,HA
GND                      J4G1             20       SCONN288_H44441004_PIP-SCONN,HA
GND                      J4G1             22       SCONN288_H44441004_PIP-SCONN,HA
GND                      J4G1             24       SCONN288_H44441004_PIP-SCONN,HA
GND                      J4G1             26       SCONN288_H44441004_PIP-SCONN,HA
GND                      J4G1             28       SCONN288_H44441004_PIP-SCONN,HA
GND                      J4G1             31       SCONN288_H44441004_PIP-SCONN,HA
GND                      J4G1             33       SCONN288_H44441004_PIP-SCONN,HA
GND                      J4G1             35       SCONN288_H44441004_PIP-SCONN,HA
GND                      J4G1             37       SCONN288_H44441004_PIP-SCONN,HA
GND                      J4G1             39       SCONN288_H44441004_PIP-SCONN,HA
GND                      J4G1             42       SCONN288_H44441004_PIP-SCONN,HA
GND                      J4G1             44       SCONN288_H44441004_PIP-SCONN,HA
GND                      J4G1             46       SCONN288_H44441004_PIP-SCONN,HA
GND                      J4G1             48       SCONN288_H44441004_PIP-SCONN,HA
GND                      J4G1             50       SCONN288_H44441004_PIP-SCONN,HA
GND                      J4G1             53       SCONN288_H44441004_PIP-SCONN,HA
GND                      J4G1             55       SCONN288_H44441004_PIP-SCONN,HA
GND                      J4G1             57       SCONN288_H44441004_PIP-SCONN,HA
GND                      J4G1             94       SCONN288_H44441004_PIP-SCONN,HA
GND                      J4G1             96       SCONN288_H44441004_PIP-SCONN,HA
GND                      J4G1             98       SCONN288_H44441004_PIP-SCONN,HA
GND                      J4G1             101      SCONN288_H44441004_PIP-SCONN,HA
GND                      J4G1             103      SCONN288_H44441004_PIP-SCONN,HA
GND                      J4G1             105      SCONN288_H44441004_PIP-SCONN,HA
GND                      J4G1             107      SCONN288_H44441004_PIP-SCONN,HA
GND                      J4G1             109      SCONN288_H44441004_PIP-SCONN,HA
GND                      J4G1             112      SCONN288_H44441004_PIP-SCONN,HA
GND                      J4G1             114      SCONN288_H44441004_PIP-SCONN,HA
GND                      J4G1             116      SCONN288_H44441004_PIP-SCONN,HA
GND                      J4G1             118      SCONN288_H44441004_PIP-SCONN,HA
GND                      J4G1             120      SCONN288_H44441004_PIP-SCONN,HA
GND                      J4G1             123      SCONN288_H44441004_PIP-SCONN,HA
GND                      J4G1             125      SCONN288_H44441004_PIP-SCONN,HA
GND                      J4G1             127      SCONN288_H44441004_PIP-SCONN,HA
GND                      J4G1             129      SCONN288_H44441004_PIP-SCONN,HA
GND                      J4G1             131      SCONN288_H44441004_PIP-SCONN,HA
GND                      J4G1             134      SCONN288_H44441004_PIP-SCONN,HA
GND                      J4G1             136      SCONN288_H44441004_PIP-SCONN,HA
GND                      J4G1             138      SCONN288_H44441004_PIP-SCONN,HA
GND                      J4G1             139      SCONN288_H44441004_PIP-SCONN,HA
GND                      J4G1             140      SCONN288_H44441004_PIP-SCONN,HA
GND                      J4G1             147      SCONN288_H44441004_PIP-SCONN,HA
GND                      J4G1             149      SCONN288_H44441004_PIP-SCONN,HA
GND                      J4G1             151      SCONN288_H44441004_PIP-SCONN,HA
GND                      J4G1             154      SCONN288_H44441004_PIP-SCONN,HA
GND                      J4G1             156      SCONN288_H44441004_PIP-SCONN,HA
GND                      J4G1             158      SCONN288_H44441004_PIP-SCONN,HA
GND                      J4G1             160      SCONN288_H44441004_PIP-SCONN,HA
GND                      J4G1             162      SCONN288_H44441004_PIP-SCONN,HA
GND                      J4G1             165      SCONN288_H44441004_PIP-SCONN,HA
GND                      J4G1             167      SCONN288_H44441004_PIP-SCONN,HA
GND                      J4G1             169      SCONN288_H44441004_PIP-SCONN,HA
GND                      J4G1             171      SCONN288_H44441004_PIP-SCONN,HA
GND                      J4G1             173      SCONN288_H44441004_PIP-SCONN,HA
GND                      J4G1             176      SCONN288_H44441004_PIP-SCONN,HA
GND                      J4G1             178      SCONN288_H44441004_PIP-SCONN,HA
GND                      J4G1             180      SCONN288_H44441004_PIP-SCONN,HA
GND                      J4G1             182      SCONN288_H44441004_PIP-SCONN,HA
GND                      J4G1             184      SCONN288_H44441004_PIP-SCONN,HA
GND                      J4G1             187      SCONN288_H44441004_PIP-SCONN,HA
GND                      J4G1             189      SCONN288_H44441004_PIP-SCONN,HA
GND                      J4G1             191      SCONN288_H44441004_PIP-SCONN,HA
GND                      J4G1             193      SCONN288_H44441004_PIP-SCONN,HA
GND                      J4G1             195      SCONN288_H44441004_PIP-SCONN,HA
GND                      J4G1             198      SCONN288_H44441004_PIP-SCONN,HA
GND                      J4G1             200      SCONN288_H44441004_PIP-SCONN,HA
GND                      J4G1             202      SCONN288_H44441004_PIP-SCONN,HA
GND                      J4G1             238      SCONN288_H44441004_PIP-SCONN,HA
GND                      J4G1             239      SCONN288_H44441004_PIP-SCONN,HA
GND                      J4G1             241      SCONN288_H44441004_PIP-SCONN,HA
GND                      J4G1             243      SCONN288_H44441004_PIP-SCONN,HA
GND                      J4G1             246      SCONN288_H44441004_PIP-SCONN,HA
GND                      J4G1             248      SCONN288_H44441004_PIP-SCONN,HA
GND                      J4G1             250      SCONN288_H44441004_PIP-SCONN,HA
GND                      J4G1             252      SCONN288_H44441004_PIP-SCONN,HA
GND                      J4G1             254      SCONN288_H44441004_PIP-SCONN,HA
GND                      J4G1             257      SCONN288_H44441004_PIP-SCONN,HA
GND                      J4G1             259      SCONN288_H44441004_PIP-SCONN,HA
GND                      J4G1             261      SCONN288_H44441004_PIP-SCONN,HA
GND                      J4G1             263      SCONN288_H44441004_PIP-SCONN,HA
GND                      J4G1             265      SCONN288_H44441004_PIP-SCONN,HA
GND                      J4G1             268      SCONN288_H44441004_PIP-SCONN,HA
GND                      J4G1             270      SCONN288_H44441004_PIP-SCONN,HA
GND                      J4G1             272      SCONN288_H44441004_PIP-SCONN,HA
GND                      J4G1             274      SCONN288_H44441004_PIP-SCONN,HA
GND                      J4G1             276      SCONN288_H44441004_PIP-SCONN,HA
GND                      J4G1             279      SCONN288_H44441004_PIP-SCONN,HA
GND                      J4G1             281      SCONN288_H44441004_PIP-SCONN,HA
GND                      J4G1             283      SCONN288_H44441004_PIP-SCONN,HA
GND                      J4G2             2        SCONN288_H44441004_PIP-SCONN,HA
GND                      J4G2             4        SCONN288_H44441004_PIP-SCONN,HA
GND                      J4G2             6        SCONN288_H44441004_PIP-SCONN,HA
GND                      J4G2             9        SCONN288_H44441004_PIP-SCONN,HA
GND                      J4G2             11       SCONN288_H44441004_PIP-SCONN,HA
GND                      J4G2             13       SCONN288_H44441004_PIP-SCONN,HA
GND                      J4G2             15       SCONN288_H44441004_PIP-SCONN,HA
GND                      J4G2             17       SCONN288_H44441004_PIP-SCONN,HA
GND                      J4G2             20       SCONN288_H44441004_PIP-SCONN,HA
GND                      J4G2             22       SCONN288_H44441004_PIP-SCONN,HA
GND                      J4G2             24       SCONN288_H44441004_PIP-SCONN,HA
GND                      J4G2             26       SCONN288_H44441004_PIP-SCONN,HA
GND                      J4G2             28       SCONN288_H44441004_PIP-SCONN,HA
GND                      J4G2             31       SCONN288_H44441004_PIP-SCONN,HA
GND                      J4G2             33       SCONN288_H44441004_PIP-SCONN,HA
GND                      J4G2             35       SCONN288_H44441004_PIP-SCONN,HA
GND                      J4G2             37       SCONN288_H44441004_PIP-SCONN,HA
GND                      J4G2             39       SCONN288_H44441004_PIP-SCONN,HA
GND                      J4G2             42       SCONN288_H44441004_PIP-SCONN,HA
GND                      J4G2             44       SCONN288_H44441004_PIP-SCONN,HA
GND                      J4G2             46       SCONN288_H44441004_PIP-SCONN,HA
GND                      J4G2             48       SCONN288_H44441004_PIP-SCONN,HA
GND                      J4G2             50       SCONN288_H44441004_PIP-SCONN,HA
GND                      J4G2             53       SCONN288_H44441004_PIP-SCONN,HA
GND                      J4G2             55       SCONN288_H44441004_PIP-SCONN,HA
GND                      J4G2             57       SCONN288_H44441004_PIP-SCONN,HA
GND                      J4G2             94       SCONN288_H44441004_PIP-SCONN,HA
GND                      J4G2             96       SCONN288_H44441004_PIP-SCONN,HA
GND                      J4G2             98       SCONN288_H44441004_PIP-SCONN,HA
GND                      J4G2             101      SCONN288_H44441004_PIP-SCONN,HA
GND                      J4G2             103      SCONN288_H44441004_PIP-SCONN,HA
GND                      J4G2             105      SCONN288_H44441004_PIP-SCONN,HA
GND                      J4G2             107      SCONN288_H44441004_PIP-SCONN,HA
GND                      J4G2             109      SCONN288_H44441004_PIP-SCONN,HA
GND                      J4G2             112      SCONN288_H44441004_PIP-SCONN,HA
GND                      J4G2             114      SCONN288_H44441004_PIP-SCONN,HA
GND                      J4G2             116      SCONN288_H44441004_PIP-SCONN,HA
GND                      J4G2             118      SCONN288_H44441004_PIP-SCONN,HA
GND                      J4G2             120      SCONN288_H44441004_PIP-SCONN,HA
GND                      J4G2             123      SCONN288_H44441004_PIP-SCONN,HA
GND                      J4G2             125      SCONN288_H44441004_PIP-SCONN,HA
GND                      J4G2             127      SCONN288_H44441004_PIP-SCONN,HA
GND                      J4G2             129      SCONN288_H44441004_PIP-SCONN,HA
GND                      J4G2             131      SCONN288_H44441004_PIP-SCONN,HA
GND                      J4G2             134      SCONN288_H44441004_PIP-SCONN,HA
GND                      J4G2             136      SCONN288_H44441004_PIP-SCONN,HA
GND                      J4G2             138      SCONN288_H44441004_PIP-SCONN,HA
GND                      J4G2             139      SCONN288_H44441004_PIP-SCONN,HA
GND                      J4G2             147      SCONN288_H44441004_PIP-SCONN,HA
GND                      J4G2             149      SCONN288_H44441004_PIP-SCONN,HA
GND                      J4G2             151      SCONN288_H44441004_PIP-SCONN,HA
GND                      J4G2             154      SCONN288_H44441004_PIP-SCONN,HA
GND                      J4G2             156      SCONN288_H44441004_PIP-SCONN,HA
GND                      J4G2             158      SCONN288_H44441004_PIP-SCONN,HA
GND                      J4G2             160      SCONN288_H44441004_PIP-SCONN,HA
GND                      J4G2             162      SCONN288_H44441004_PIP-SCONN,HA
GND                      J4G2             165      SCONN288_H44441004_PIP-SCONN,HA
GND                      J4G2             167      SCONN288_H44441004_PIP-SCONN,HA
GND                      J4G2             169      SCONN288_H44441004_PIP-SCONN,HA
GND                      J4G2             171      SCONN288_H44441004_PIP-SCONN,HA
GND                      J4G2             173      SCONN288_H44441004_PIP-SCONN,HA
GND                      J4G2             176      SCONN288_H44441004_PIP-SCONN,HA
GND                      J4G2             178      SCONN288_H44441004_PIP-SCONN,HA
GND                      J4G2             180      SCONN288_H44441004_PIP-SCONN,HA
GND                      J4G2             182      SCONN288_H44441004_PIP-SCONN,HA
GND                      J4G2             184      SCONN288_H44441004_PIP-SCONN,HA
GND                      J4G2             187      SCONN288_H44441004_PIP-SCONN,HA
GND                      J4G2             189      SCONN288_H44441004_PIP-SCONN,HA
GND                      J4G2             191      SCONN288_H44441004_PIP-SCONN,HA
GND                      J4G2             193      SCONN288_H44441004_PIP-SCONN,HA
GND                      J4G2             195      SCONN288_H44441004_PIP-SCONN,HA
GND                      J4G2             198      SCONN288_H44441004_PIP-SCONN,HA
GND                      J4G2             200      SCONN288_H44441004_PIP-SCONN,HA
GND                      J4G2             202      SCONN288_H44441004_PIP-SCONN,HA
GND                      J4G2             238      SCONN288_H44441004_PIP-SCONN,HA
GND                      J4G2             239      SCONN288_H44441004_PIP-SCONN,HA
GND                      J4G2             241      SCONN288_H44441004_PIP-SCONN,HA
GND                      J4G2             243      SCONN288_H44441004_PIP-SCONN,HA
GND                      J4G2             246      SCONN288_H44441004_PIP-SCONN,HA
GND                      J4G2             248      SCONN288_H44441004_PIP-SCONN,HA
GND                      J4G2             250      SCONN288_H44441004_PIP-SCONN,HA
GND                      J4G2             252      SCONN288_H44441004_PIP-SCONN,HA
GND                      J4G2             254      SCONN288_H44441004_PIP-SCONN,HA
GND                      J4G2             257      SCONN288_H44441004_PIP-SCONN,HA
GND                      J4G2             259      SCONN288_H44441004_PIP-SCONN,HA
GND                      J4G2             261      SCONN288_H44441004_PIP-SCONN,HA
GND                      J4G2             263      SCONN288_H44441004_PIP-SCONN,HA
GND                      J4G2             265      SCONN288_H44441004_PIP-SCONN,HA
GND                      J4G2             268      SCONN288_H44441004_PIP-SCONN,HA
GND                      J4G2             270      SCONN288_H44441004_PIP-SCONN,HA
GND                      J4G2             272      SCONN288_H44441004_PIP-SCONN,HA
GND                      J4G2             274      SCONN288_H44441004_PIP-SCONN,HA
GND                      J4G2             276      SCONN288_H44441004_PIP-SCONN,HA
GND                      J4G2             279      SCONN288_H44441004_PIP-SCONN,HA
GND                      J4G2             281      SCONN288_H44441004_PIP-SCONN,HA
GND                      J4G2             283      SCONN288_H44441004_PIP-SCONN,HA
GND                      J4G3             2        SCONN288_H44441004_PIP-SCONN,HA
GND                      J4G3             4        SCONN288_H44441004_PIP-SCONN,HA
GND                      J4G3             6        SCONN288_H44441004_PIP-SCONN,HA
GND                      J4G3             9        SCONN288_H44441004_PIP-SCONN,HA
GND                      J4G3             11       SCONN288_H44441004_PIP-SCONN,HA
GND                      J4G3             13       SCONN288_H44441004_PIP-SCONN,HA
GND                      J4G3             15       SCONN288_H44441004_PIP-SCONN,HA
GND                      J4G3             17       SCONN288_H44441004_PIP-SCONN,HA
GND                      J4G3             20       SCONN288_H44441004_PIP-SCONN,HA
GND                      J4G3             22       SCONN288_H44441004_PIP-SCONN,HA
GND                      J4G3             24       SCONN288_H44441004_PIP-SCONN,HA
GND                      J4G3             26       SCONN288_H44441004_PIP-SCONN,HA
GND                      J4G3             28       SCONN288_H44441004_PIP-SCONN,HA
GND                      J4G3             31       SCONN288_H44441004_PIP-SCONN,HA
GND                      J4G3             33       SCONN288_H44441004_PIP-SCONN,HA
GND                      J4G3             35       SCONN288_H44441004_PIP-SCONN,HA
GND                      J4G3             37       SCONN288_H44441004_PIP-SCONN,HA
GND                      J4G3             39       SCONN288_H44441004_PIP-SCONN,HA
GND                      J4G3             42       SCONN288_H44441004_PIP-SCONN,HA
GND                      J4G3             44       SCONN288_H44441004_PIP-SCONN,HA
GND                      J4G3             46       SCONN288_H44441004_PIP-SCONN,HA
GND                      J4G3             48       SCONN288_H44441004_PIP-SCONN,HA
GND                      J4G3             50       SCONN288_H44441004_PIP-SCONN,HA
GND                      J4G3             53       SCONN288_H44441004_PIP-SCONN,HA
GND                      J4G3             55       SCONN288_H44441004_PIP-SCONN,HA
GND                      J4G3             57       SCONN288_H44441004_PIP-SCONN,HA
GND                      J4G3             94       SCONN288_H44441004_PIP-SCONN,HA
GND                      J4G3             96       SCONN288_H44441004_PIP-SCONN,HA
GND                      J4G3             98       SCONN288_H44441004_PIP-SCONN,HA
GND                      J4G3             101      SCONN288_H44441004_PIP-SCONN,HA
GND                      J4G3             103      SCONN288_H44441004_PIP-SCONN,HA
GND                      J4G3             105      SCONN288_H44441004_PIP-SCONN,HA
GND                      J4G3             107      SCONN288_H44441004_PIP-SCONN,HA
GND                      J4G3             109      SCONN288_H44441004_PIP-SCONN,HA
GND                      J4G3             112      SCONN288_H44441004_PIP-SCONN,HA
GND                      J4G3             114      SCONN288_H44441004_PIP-SCONN,HA
GND                      J4G3             116      SCONN288_H44441004_PIP-SCONN,HA
GND                      J4G3             118      SCONN288_H44441004_PIP-SCONN,HA
GND                      J4G3             120      SCONN288_H44441004_PIP-SCONN,HA
GND                      J4G3             123      SCONN288_H44441004_PIP-SCONN,HA
GND                      J4G3             125      SCONN288_H44441004_PIP-SCONN,HA
GND                      J4G3             127      SCONN288_H44441004_PIP-SCONN,HA
GND                      J4G3             129      SCONN288_H44441004_PIP-SCONN,HA
GND                      J4G3             131      SCONN288_H44441004_PIP-SCONN,HA
GND                      J4G3             134      SCONN288_H44441004_PIP-SCONN,HA
GND                      J4G3             136      SCONN288_H44441004_PIP-SCONN,HA
GND                      J4G3             138      SCONN288_H44441004_PIP-SCONN,HA
GND                      J4G3             139      SCONN288_H44441004_PIP-SCONN,HA
GND                      J4G3             140      SCONN288_H44441004_PIP-SCONN,HA
GND                      J4G3             147      SCONN288_H44441004_PIP-SCONN,HA
GND                      J4G3             149      SCONN288_H44441004_PIP-SCONN,HA
GND                      J4G3             151      SCONN288_H44441004_PIP-SCONN,HA
GND                      J4G3             154      SCONN288_H44441004_PIP-SCONN,HA
GND                      J4G3             156      SCONN288_H44441004_PIP-SCONN,HA
GND                      J4G3             158      SCONN288_H44441004_PIP-SCONN,HA
GND                      J4G3             160      SCONN288_H44441004_PIP-SCONN,HA
GND                      J4G3             162      SCONN288_H44441004_PIP-SCONN,HA
GND                      J4G3             165      SCONN288_H44441004_PIP-SCONN,HA
GND                      J4G3             167      SCONN288_H44441004_PIP-SCONN,HA
GND                      J4G3             169      SCONN288_H44441004_PIP-SCONN,HA
GND                      J4G3             171      SCONN288_H44441004_PIP-SCONN,HA
GND                      J4G3             173      SCONN288_H44441004_PIP-SCONN,HA
GND                      J4G3             176      SCONN288_H44441004_PIP-SCONN,HA
GND                      J4G3             178      SCONN288_H44441004_PIP-SCONN,HA
GND                      J4G3             180      SCONN288_H44441004_PIP-SCONN,HA
GND                      J4G3             182      SCONN288_H44441004_PIP-SCONN,HA
GND                      J4G3             184      SCONN288_H44441004_PIP-SCONN,HA
GND                      J4G3             187      SCONN288_H44441004_PIP-SCONN,HA
GND                      J4G3             189      SCONN288_H44441004_PIP-SCONN,HA
GND                      J4G3             191      SCONN288_H44441004_PIP-SCONN,HA
GND                      J4G3             193      SCONN288_H44441004_PIP-SCONN,HA
GND                      J4G3             195      SCONN288_H44441004_PIP-SCONN,HA
GND                      J4G3             198      SCONN288_H44441004_PIP-SCONN,HA
GND                      J4G3             200      SCONN288_H44441004_PIP-SCONN,HA
GND                      J4G3             202      SCONN288_H44441004_PIP-SCONN,HA
GND                      J4G3             239      SCONN288_H44441004_PIP-SCONN,HA
GND                      J4G3             241      SCONN288_H44441004_PIP-SCONN,HA
GND                      J4G3             243      SCONN288_H44441004_PIP-SCONN,HA
GND                      J4G3             246      SCONN288_H44441004_PIP-SCONN,HA
GND                      J4G3             248      SCONN288_H44441004_PIP-SCONN,HA
GND                      J4G3             250      SCONN288_H44441004_PIP-SCONN,HA
GND                      J4G3             252      SCONN288_H44441004_PIP-SCONN,HA
GND                      J4G3             254      SCONN288_H44441004_PIP-SCONN,HA
GND                      J4G3             257      SCONN288_H44441004_PIP-SCONN,HA
GND                      J4G3             259      SCONN288_H44441004_PIP-SCONN,HA
GND                      J4G3             261      SCONN288_H44441004_PIP-SCONN,HA
GND                      J4G3             263      SCONN288_H44441004_PIP-SCONN,HA
GND                      J4G3             265      SCONN288_H44441004_PIP-SCONN,HA
GND                      J4G3             268      SCONN288_H44441004_PIP-SCONN,HA
GND                      J4G3             270      SCONN288_H44441004_PIP-SCONN,HA
GND                      J4G3             272      SCONN288_H44441004_PIP-SCONN,HA
GND                      J4G3             274      SCONN288_H44441004_PIP-SCONN,HA
GND                      J4G3             276      SCONN288_H44441004_PIP-SCONN,HA
GND                      J4G3             279      SCONN288_H44441004_PIP-SCONN,HA
GND                      J4G3             281      SCONN288_H44441004_PIP-SCONN,HA
GND                      J4G3             283      SCONN288_H44441004_PIP-SCONN,HA
GND                      J6B1             A9       SCONN120_H61426002_SM-CONN,H61A
GND                      J6B1             A10      SCONN120_H61426002_SM-CONN,H61A
GND                      J6B1             A12      SCONN120_H61426002_SM-CONN,H61A
GND                      J6B1             A14      SCONN120_H61426002_SM-CONN,H61A
GND                      J6B1             A17      SCONN120_H61426002_SM-CONN,H61A
GND                      J6B1             B9       SCONN120_H61426002_SM-CONN,H61A
GND                      J6B1             B10      SCONN120_H61426002_SM-CONN,H61A
GND                      J6B1             B12      SCONN120_H61426002_SM-CONN,H61A
GND                      J6B1             B14      SCONN120_H61426002_SM-CONN,H61A
GND                      J6B1             B17      SCONN120_H61426002_SM-CONN,H61A
GND                      J6B1             C1       SCONN120_H61426002_SM-CONN,H61A
GND                      J6B1             C2       SCONN120_H61426002_SM-CONN,H61A
GND                      J6B1             C3       SCONN120_H61426002_SM-CONN,H61A
GND                      J6B1             C4       SCONN120_H61426002_SM-CONN,H61A
GND                      J6B1             C5       SCONN120_H61426002_SM-CONN,H61A
GND                      J6B1             C6       SCONN120_H61426002_SM-CONN,H61A
GND                      J6B1             C7       SCONN120_H61426002_SM-CONN,H61A
GND                      J6B1             C8       SCONN120_H61426002_SM-CONN,H61A
GND                      J6B1             C9       SCONN120_H61426002_SM-CONN,H61A
GND                      J6B1             C10      SCONN120_H61426002_SM-CONN,H61A
GND                      J6B1             C12      SCONN120_H61426002_SM-CONN,H61A
GND                      J6B1             C14      SCONN120_H61426002_SM-CONN,H61A
GND                      J6B1             C15      SCONN120_H61426002_SM-CONN,H61A
GND                      J6B1             C16      SCONN120_H61426002_SM-CONN,H61A
GND                      J6B1             D2       SCONN120_H61426002_SM-CONN,H61A
GND                      J6B1             D3       SCONN120_H61426002_SM-CONN,H61A
GND                      J6B1             D4       SCONN120_H61426002_SM-CONN,H61A
GND                      J6B1             D5       SCONN120_H61426002_SM-CONN,H61A
GND                      J6B1             D6       SCONN120_H61426002_SM-CONN,H61A
GND                      J6B1             D7       SCONN120_H61426002_SM-CONN,H61A
GND                      J6B1             D8       SCONN120_H61426002_SM-CONN,H61A
GND                      J6B1             D9       SCONN120_H61426002_SM-CONN,H61A
GND                      J6B1             D10      SCONN120_H61426002_SM-CONN,H61A
GND                      J6B1             D11      SCONN120_H61426002_SM-CONN,H61A
GND                      J6B1             D12      SCONN120_H61426002_SM-CONN,H61A
GND                      J6B1             D13      SCONN120_H61426002_SM-CONN,H61A
GND                      J6B1             D14      SCONN120_H61426002_SM-CONN,H61A
GND                      J6B1             E2       SCONN120_H61426002_SM-CONN,H61A
GND                      J6B1             E3       SCONN120_H61426002_SM-CONN,H61A
GND                      J6B1             E4       SCONN120_H61426002_SM-CONN,H61A
GND                      J6B1             E5       SCONN120_H61426002_SM-CONN,H61A
GND                      J6B1             E6       SCONN120_H61426002_SM-CONN,H61A
GND                      J6B1             E7       SCONN120_H61426002_SM-CONN,H61A
GND                      J6B1             E9       SCONN120_H61426002_SM-CONN,H61A
GND                      J6B1             E11      SCONN120_H61426002_SM-CONN,H61A
GND                      J6B1             E12      SCONN120_H61426002_SM-CONN,H61A
GND                      J6B1             E13      SCONN120_H61426002_SM-CONN,H61A
GND                      J6B1             E14      SCONN120_H61426002_SM-CONN,H61A
GND                      J6B1             F2       SCONN120_H61426002_SM-CONN,H61A
GND                      J6B1             F3       SCONN120_H61426002_SM-CONN,H61A
GND                      J6B1             F4       SCONN120_H61426002_SM-CONN,H61A
GND                      J6B1             F5       SCONN120_H61426002_SM-CONN,H61A
GND                      J6B1             F6       SCONN120_H61426002_SM-CONN,H61A
GND                      J6B1             F7       SCONN120_H61426002_SM-CONN,H61A
GND                      J6B1             F9       SCONN120_H61426002_SM-CONN,H61A
GND                      J6B1             F11      SCONN120_H61426002_SM-CONN,H61A
GND                      J6B1             F12      SCONN120_H61426002_SM-CONN,H61A
GND                      J6B1             F13      SCONN120_H61426002_SM-CONN,H61A
GND                      J6B1             F14      SCONN120_H61426002_SM-CONN,H61A
GND                      J6E1             A19      SCONN120_H61426002_SM-CONN,H61A
GND                      J6E1             A20      SCONN120_H61426002_SM-CONN,H61A
GND                      J6E1             B19      SCONN120_H61426002_SM-CONN,H61A
GND                      J6E1             B20      SCONN120_H61426002_SM-CONN,H61A
GND                      J6E1             C19      SCONN120_H61426002_SM-CONN,H61A
GND                      J6E1             C20      SCONN120_H61426002_SM-CONN,H61A
GND                      J6E1             D3       SCONN120_H61426002_SM-CONN,H61A
GND                      J6E1             D4       SCONN120_H61426002_SM-CONN,H61A
GND                      J6E1             D5       SCONN120_H61426002_SM-CONN,H61A
GND                      J6E1             D6       SCONN120_H61426002_SM-CONN,H61A
GND                      J6E1             D7       SCONN120_H61426002_SM-CONN,H61A
GND                      J6E1             D8       SCONN120_H61426002_SM-CONN,H61A
GND                      J6E1             D9       SCONN120_H61426002_SM-CONN,H61A
GND                      J6E1             D10      SCONN120_H61426002_SM-CONN,H61A
GND                      J6E1             D11      SCONN120_H61426002_SM-CONN,H61A
GND                      J6E1             D12      SCONN120_H61426002_SM-CONN,H61A
GND                      J6E1             D13      SCONN120_H61426002_SM-CONN,H61A
GND                      J6E1             D14      SCONN120_H61426002_SM-CONN,H61A
GND                      J6E1             D15      SCONN120_H61426002_SM-CONN,H61A
GND                      J6E1             D16      SCONN120_H61426002_SM-CONN,H61A
GND                      J6E1             D17      SCONN120_H61426002_SM-CONN,H61A
GND                      J6E1             D18      SCONN120_H61426002_SM-CONN,H61A
GND                      J6E1             D19      SCONN120_H61426002_SM-CONN,H61A
GND                      J6E1             D20      SCONN120_H61426002_SM-CONN,H61A
GND                      J6E1             E3       SCONN120_H61426002_SM-CONN,H61A
GND                      J6E1             E4       SCONN120_H61426002_SM-CONN,H61A
GND                      J6E1             E6       SCONN120_H61426002_SM-CONN,H61A
GND                      J6E1             E7       SCONN120_H61426002_SM-CONN,H61A
GND                      J6E1             E8       SCONN120_H61426002_SM-CONN,H61A
GND                      J6E1             E9       SCONN120_H61426002_SM-CONN,H61A
GND                      J6E1             E10      SCONN120_H61426002_SM-CONN,H61A
GND                      J6E1             E11      SCONN120_H61426002_SM-CONN,H61A
GND                      J6E1             E12      SCONN120_H61426002_SM-CONN,H61A
GND                      J6E1             E13      SCONN120_H61426002_SM-CONN,H61A
GND                      J6E1             E14      SCONN120_H61426002_SM-CONN,H61A
GND                      J6E1             E15      SCONN120_H61426002_SM-CONN,H61A
GND                      J6E1             E16      SCONN120_H61426002_SM-CONN,H61A
GND                      J6E1             E17      SCONN120_H61426002_SM-CONN,H61A
GND                      J6E1             E18      SCONN120_H61426002_SM-CONN,H61A
GND                      J6E1             E19      SCONN120_H61426002_SM-CONN,H61A
GND                      J6E1             E20      SCONN120_H61426002_SM-CONN,H61A
GND                      J6E1             F3       SCONN120_H61426002_SM-CONN,H61A
GND                      J6E1             F4       SCONN120_H61426002_SM-CONN,H61A
GND                      J6E1             F6       SCONN120_H61426002_SM-CONN,H61A
GND                      J6E1             F7       SCONN120_H61426002_SM-CONN,H61A
GND                      J6E1             F8       SCONN120_H61426002_SM-CONN,H61A
GND                      J6E1             F9       SCONN120_H61426002_SM-CONN,H61A
GND                      J6E1             F10      SCONN120_H61426002_SM-CONN,H61A
GND                      J6E1             F11      SCONN120_H61426002_SM-CONN,H61A
GND                      J6E1             F12      SCONN120_H61426002_SM-CONN,H61A
GND                      J6E1             F13      SCONN120_H61426002_SM-CONN,H61A
GND                      J6E1             F14      SCONN120_H61426002_SM-CONN,H61A
GND                      J6E1             F15      SCONN120_H61426002_SM-CONN,H61A
GND                      J6E1             F16      SCONN120_H61426002_SM-CONN,H61A
GND                      J6E1             F17      SCONN120_H61426002_SM-CONN,H61A
GND                      J6E1             F18      SCONN120_H61426002_SM-CONN,H61A
GND                      J6E1             F19      SCONN120_H61426002_SM-CONN,H61A
GND                      J6E1             F20      SCONN120_H61426002_SM-CONN,H61A
GND                      J6L1             2        SCONN288_H44441003_PIP-SCONN,HA
GND                      J6L1             4        SCONN288_H44441003_PIP-SCONN,HA
GND                      J6L1             6        SCONN288_H44441003_PIP-SCONN,HA
GND                      J6L1             9        SCONN288_H44441003_PIP-SCONN,HA
GND                      J6L1             11       SCONN288_H44441003_PIP-SCONN,HA
GND                      J6L1             13       SCONN288_H44441003_PIP-SCONN,HA
GND                      J6L1             15       SCONN288_H44441003_PIP-SCONN,HA
GND                      J6L1             17       SCONN288_H44441003_PIP-SCONN,HA
GND                      J6L1             20       SCONN288_H44441003_PIP-SCONN,HA
GND                      J6L1             22       SCONN288_H44441003_PIP-SCONN,HA
GND                      J6L1             24       SCONN288_H44441003_PIP-SCONN,HA
GND                      J6L1             26       SCONN288_H44441003_PIP-SCONN,HA
GND                      J6L1             28       SCONN288_H44441003_PIP-SCONN,HA
GND                      J6L1             31       SCONN288_H44441003_PIP-SCONN,HA
GND                      J6L1             33       SCONN288_H44441003_PIP-SCONN,HA
GND                      J6L1             35       SCONN288_H44441003_PIP-SCONN,HA
GND                      J6L1             37       SCONN288_H44441003_PIP-SCONN,HA
GND                      J6L1             39       SCONN288_H44441003_PIP-SCONN,HA
GND                      J6L1             42       SCONN288_H44441003_PIP-SCONN,HA
GND                      J6L1             44       SCONN288_H44441003_PIP-SCONN,HA
GND                      J6L1             46       SCONN288_H44441003_PIP-SCONN,HA
GND                      J6L1             48       SCONN288_H44441003_PIP-SCONN,HA
GND                      J6L1             50       SCONN288_H44441003_PIP-SCONN,HA
GND                      J6L1             53       SCONN288_H44441003_PIP-SCONN,HA
GND                      J6L1             55       SCONN288_H44441003_PIP-SCONN,HA
GND                      J6L1             57       SCONN288_H44441003_PIP-SCONN,HA
GND                      J6L1             94       SCONN288_H44441003_PIP-SCONN,HA
GND                      J6L1             96       SCONN288_H44441003_PIP-SCONN,HA
GND                      J6L1             98       SCONN288_H44441003_PIP-SCONN,HA
GND                      J6L1             101      SCONN288_H44441003_PIP-SCONN,HA
GND                      J6L1             103      SCONN288_H44441003_PIP-SCONN,HA
GND                      J6L1             105      SCONN288_H44441003_PIP-SCONN,HA
GND                      J6L1             107      SCONN288_H44441003_PIP-SCONN,HA
GND                      J6L1             109      SCONN288_H44441003_PIP-SCONN,HA
GND                      J6L1             112      SCONN288_H44441003_PIP-SCONN,HA
GND                      J6L1             114      SCONN288_H44441003_PIP-SCONN,HA
GND                      J6L1             116      SCONN288_H44441003_PIP-SCONN,HA
GND                      J6L1             118      SCONN288_H44441003_PIP-SCONN,HA
GND                      J6L1             120      SCONN288_H44441003_PIP-SCONN,HA
GND                      J6L1             123      SCONN288_H44441003_PIP-SCONN,HA
GND                      J6L1             125      SCONN288_H44441003_PIP-SCONN,HA
GND                      J6L1             127      SCONN288_H44441003_PIP-SCONN,HA
GND                      J6L1             129      SCONN288_H44441003_PIP-SCONN,HA
GND                      J6L1             131      SCONN288_H44441003_PIP-SCONN,HA
GND                      J6L1             134      SCONN288_H44441003_PIP-SCONN,HA
GND                      J6L1             136      SCONN288_H44441003_PIP-SCONN,HA
GND                      J6L1             138      SCONN288_H44441003_PIP-SCONN,HA
GND                      J6L1             140      SCONN288_H44441003_PIP-SCONN,HA
GND                      J6L1             147      SCONN288_H44441003_PIP-SCONN,HA
GND                      J6L1             149      SCONN288_H44441003_PIP-SCONN,HA
GND                      J6L1             151      SCONN288_H44441003_PIP-SCONN,HA
GND                      J6L1             154      SCONN288_H44441003_PIP-SCONN,HA
GND                      J6L1             156      SCONN288_H44441003_PIP-SCONN,HA
GND                      J6L1             158      SCONN288_H44441003_PIP-SCONN,HA
GND                      J6L1             160      SCONN288_H44441003_PIP-SCONN,HA
GND                      J6L1             162      SCONN288_H44441003_PIP-SCONN,HA
GND                      J6L1             165      SCONN288_H44441003_PIP-SCONN,HA
GND                      J6L1             167      SCONN288_H44441003_PIP-SCONN,HA
GND                      J6L1             169      SCONN288_H44441003_PIP-SCONN,HA
GND                      J6L1             171      SCONN288_H44441003_PIP-SCONN,HA
GND                      J6L1             173      SCONN288_H44441003_PIP-SCONN,HA
GND                      J6L1             176      SCONN288_H44441003_PIP-SCONN,HA
GND                      J6L1             178      SCONN288_H44441003_PIP-SCONN,HA
GND                      J6L1             180      SCONN288_H44441003_PIP-SCONN,HA
GND                      J6L1             182      SCONN288_H44441003_PIP-SCONN,HA
GND                      J6L1             184      SCONN288_H44441003_PIP-SCONN,HA
GND                      J6L1             187      SCONN288_H44441003_PIP-SCONN,HA
GND                      J6L1             189      SCONN288_H44441003_PIP-SCONN,HA
GND                      J6L1             191      SCONN288_H44441003_PIP-SCONN,HA
GND                      J6L1             193      SCONN288_H44441003_PIP-SCONN,HA
GND                      J6L1             195      SCONN288_H44441003_PIP-SCONN,HA
GND                      J6L1             198      SCONN288_H44441003_PIP-SCONN,HA
GND                      J6L1             200      SCONN288_H44441003_PIP-SCONN,HA
GND                      J6L1             202      SCONN288_H44441003_PIP-SCONN,HA
GND                      J6L1             239      SCONN288_H44441003_PIP-SCONN,HA
GND                      J6L1             241      SCONN288_H44441003_PIP-SCONN,HA
GND                      J6L1             243      SCONN288_H44441003_PIP-SCONN,HA
GND                      J6L1             246      SCONN288_H44441003_PIP-SCONN,HA
GND                      J6L1             248      SCONN288_H44441003_PIP-SCONN,HA
GND                      J6L1             250      SCONN288_H44441003_PIP-SCONN,HA
GND                      J6L1             252      SCONN288_H44441003_PIP-SCONN,HA
GND                      J6L1             254      SCONN288_H44441003_PIP-SCONN,HA
GND                      J6L1             257      SCONN288_H44441003_PIP-SCONN,HA
GND                      J6L1             259      SCONN288_H44441003_PIP-SCONN,HA
GND                      J6L1             261      SCONN288_H44441003_PIP-SCONN,HA
GND                      J6L1             263      SCONN288_H44441003_PIP-SCONN,HA
GND                      J6L1             265      SCONN288_H44441003_PIP-SCONN,HA
GND                      J6L1             268      SCONN288_H44441003_PIP-SCONN,HA
GND                      J6L1             270      SCONN288_H44441003_PIP-SCONN,HA
GND                      J6L1             272      SCONN288_H44441003_PIP-SCONN,HA
GND                      J6L1             274      SCONN288_H44441003_PIP-SCONN,HA
GND                      J6L1             276      SCONN288_H44441003_PIP-SCONN,HA
GND                      J6L1             279      SCONN288_H44441003_PIP-SCONN,HA
GND                      J6L1             281      SCONN288_H44441003_PIP-SCONN,HA
GND                      J6L1             283      SCONN288_H44441003_PIP-SCONN,HA
GND                      J6L2             2        SCONN288_H44441003_PIP-SCONN,HA
GND                      J6L2             4        SCONN288_H44441003_PIP-SCONN,HA
GND                      J6L2             6        SCONN288_H44441003_PIP-SCONN,HA
GND                      J6L2             9        SCONN288_H44441003_PIP-SCONN,HA
GND                      J6L2             11       SCONN288_H44441003_PIP-SCONN,HA
GND                      J6L2             13       SCONN288_H44441003_PIP-SCONN,HA
GND                      J6L2             15       SCONN288_H44441003_PIP-SCONN,HA
GND                      J6L2             17       SCONN288_H44441003_PIP-SCONN,HA
GND                      J6L2             20       SCONN288_H44441003_PIP-SCONN,HA
GND                      J6L2             22       SCONN288_H44441003_PIP-SCONN,HA
GND                      J6L2             24       SCONN288_H44441003_PIP-SCONN,HA
GND                      J6L2             26       SCONN288_H44441003_PIP-SCONN,HA
GND                      J6L2             28       SCONN288_H44441003_PIP-SCONN,HA
GND                      J6L2             31       SCONN288_H44441003_PIP-SCONN,HA
GND                      J6L2             33       SCONN288_H44441003_PIP-SCONN,HA
GND                      J6L2             35       SCONN288_H44441003_PIP-SCONN,HA
GND                      J6L2             37       SCONN288_H44441003_PIP-SCONN,HA
GND                      J6L2             39       SCONN288_H44441003_PIP-SCONN,HA
GND                      J6L2             42       SCONN288_H44441003_PIP-SCONN,HA
GND                      J6L2             44       SCONN288_H44441003_PIP-SCONN,HA
GND                      J6L2             46       SCONN288_H44441003_PIP-SCONN,HA
GND                      J6L2             48       SCONN288_H44441003_PIP-SCONN,HA
GND                      J6L2             50       SCONN288_H44441003_PIP-SCONN,HA
GND                      J6L2             53       SCONN288_H44441003_PIP-SCONN,HA
GND                      J6L2             55       SCONN288_H44441003_PIP-SCONN,HA
GND                      J6L2             57       SCONN288_H44441003_PIP-SCONN,HA
GND                      J6L2             94       SCONN288_H44441003_PIP-SCONN,HA
GND                      J6L2             96       SCONN288_H44441003_PIP-SCONN,HA
GND                      J6L2             98       SCONN288_H44441003_PIP-SCONN,HA
GND                      J6L2             101      SCONN288_H44441003_PIP-SCONN,HA
GND                      J6L2             103      SCONN288_H44441003_PIP-SCONN,HA
GND                      J6L2             105      SCONN288_H44441003_PIP-SCONN,HA
GND                      J6L2             107      SCONN288_H44441003_PIP-SCONN,HA
GND                      J6L2             109      SCONN288_H44441003_PIP-SCONN,HA
GND                      J6L2             112      SCONN288_H44441003_PIP-SCONN,HA
GND                      J6L2             114      SCONN288_H44441003_PIP-SCONN,HA
GND                      J6L2             116      SCONN288_H44441003_PIP-SCONN,HA
GND                      J6L2             118      SCONN288_H44441003_PIP-SCONN,HA
GND                      J6L2             120      SCONN288_H44441003_PIP-SCONN,HA
GND                      J6L2             123      SCONN288_H44441003_PIP-SCONN,HA
GND                      J6L2             125      SCONN288_H44441003_PIP-SCONN,HA
GND                      J6L2             127      SCONN288_H44441003_PIP-SCONN,HA
GND                      J6L2             129      SCONN288_H44441003_PIP-SCONN,HA
GND                      J6L2             131      SCONN288_H44441003_PIP-SCONN,HA
GND                      J6L2             134      SCONN288_H44441003_PIP-SCONN,HA
GND                      J6L2             136      SCONN288_H44441003_PIP-SCONN,HA
GND                      J6L2             138      SCONN288_H44441003_PIP-SCONN,HA
GND                      J6L2             147      SCONN288_H44441003_PIP-SCONN,HA
GND                      J6L2             149      SCONN288_H44441003_PIP-SCONN,HA
GND                      J6L2             151      SCONN288_H44441003_PIP-SCONN,HA
GND                      J6L2             154      SCONN288_H44441003_PIP-SCONN,HA
GND                      J6L2             156      SCONN288_H44441003_PIP-SCONN,HA
GND                      J6L2             158      SCONN288_H44441003_PIP-SCONN,HA
GND                      J6L2             160      SCONN288_H44441003_PIP-SCONN,HA
GND                      J6L2             162      SCONN288_H44441003_PIP-SCONN,HA
GND                      J6L2             165      SCONN288_H44441003_PIP-SCONN,HA
GND                      J6L2             167      SCONN288_H44441003_PIP-SCONN,HA
GND                      J6L2             169      SCONN288_H44441003_PIP-SCONN,HA
GND                      J6L2             171      SCONN288_H44441003_PIP-SCONN,HA
GND                      J6L2             173      SCONN288_H44441003_PIP-SCONN,HA
GND                      J6L2             176      SCONN288_H44441003_PIP-SCONN,HA
GND                      J6L2             178      SCONN288_H44441003_PIP-SCONN,HA
GND                      J6L2             180      SCONN288_H44441003_PIP-SCONN,HA
GND                      J6L2             182      SCONN288_H44441003_PIP-SCONN,HA
GND                      J6L2             184      SCONN288_H44441003_PIP-SCONN,HA
GND                      J6L2             187      SCONN288_H44441003_PIP-SCONN,HA
GND                      J6L2             189      SCONN288_H44441003_PIP-SCONN,HA
GND                      J6L2             191      SCONN288_H44441003_PIP-SCONN,HA
GND                      J6L2             193      SCONN288_H44441003_PIP-SCONN,HA
GND                      J6L2             195      SCONN288_H44441003_PIP-SCONN,HA
GND                      J6L2             198      SCONN288_H44441003_PIP-SCONN,HA
GND                      J6L2             200      SCONN288_H44441003_PIP-SCONN,HA
GND                      J6L2             202      SCONN288_H44441003_PIP-SCONN,HA
GND                      J6L2             238      SCONN288_H44441003_PIP-SCONN,HA
GND                      J6L2             239      SCONN288_H44441003_PIP-SCONN,HA
GND                      J6L2             241      SCONN288_H44441003_PIP-SCONN,HA
GND                      J6L2             243      SCONN288_H44441003_PIP-SCONN,HA
GND                      J6L2             246      SCONN288_H44441003_PIP-SCONN,HA
GND                      J6L2             248      SCONN288_H44441003_PIP-SCONN,HA
GND                      J6L2             250      SCONN288_H44441003_PIP-SCONN,HA
GND                      J6L2             252      SCONN288_H44441003_PIP-SCONN,HA
GND                      J6L2             254      SCONN288_H44441003_PIP-SCONN,HA
GND                      J6L2             257      SCONN288_H44441003_PIP-SCONN,HA
GND                      J6L2             259      SCONN288_H44441003_PIP-SCONN,HA
GND                      J6L2             261      SCONN288_H44441003_PIP-SCONN,HA
GND                      J6L2             263      SCONN288_H44441003_PIP-SCONN,HA
GND                      J6L2             265      SCONN288_H44441003_PIP-SCONN,HA
GND                      J6L2             268      SCONN288_H44441003_PIP-SCONN,HA
GND                      J6L2             270      SCONN288_H44441003_PIP-SCONN,HA
GND                      J6L2             272      SCONN288_H44441003_PIP-SCONN,HA
GND                      J6L2             274      SCONN288_H44441003_PIP-SCONN,HA
GND                      J6L2             276      SCONN288_H44441003_PIP-SCONN,HA
GND                      J6L2             279      SCONN288_H44441003_PIP-SCONN,HA
GND                      J6L2             281      SCONN288_H44441003_PIP-SCONN,HA
GND                      J6L2             283      SCONN288_H44441003_PIP-SCONN,HA
GND                      J6M1             2        SCONN288_H44441003_PIP-SCONN,HA
GND                      J6M1             4        SCONN288_H44441003_PIP-SCONN,HA
GND                      J6M1             6        SCONN288_H44441003_PIP-SCONN,HA
GND                      J6M1             9        SCONN288_H44441003_PIP-SCONN,HA
GND                      J6M1             11       SCONN288_H44441003_PIP-SCONN,HA
GND                      J6M1             13       SCONN288_H44441003_PIP-SCONN,HA
GND                      J6M1             15       SCONN288_H44441003_PIP-SCONN,HA
GND                      J6M1             17       SCONN288_H44441003_PIP-SCONN,HA
GND                      J6M1             20       SCONN288_H44441003_PIP-SCONN,HA
GND                      J6M1             22       SCONN288_H44441003_PIP-SCONN,HA
GND                      J6M1             24       SCONN288_H44441003_PIP-SCONN,HA
GND                      J6M1             26       SCONN288_H44441003_PIP-SCONN,HA
GND                      J6M1             28       SCONN288_H44441003_PIP-SCONN,HA
GND                      J6M1             31       SCONN288_H44441003_PIP-SCONN,HA
GND                      J6M1             33       SCONN288_H44441003_PIP-SCONN,HA
GND                      J6M1             35       SCONN288_H44441003_PIP-SCONN,HA
GND                      J6M1             37       SCONN288_H44441003_PIP-SCONN,HA
GND                      J6M1             39       SCONN288_H44441003_PIP-SCONN,HA
GND                      J6M1             42       SCONN288_H44441003_PIP-SCONN,HA
GND                      J6M1             44       SCONN288_H44441003_PIP-SCONN,HA
GND                      J6M1             46       SCONN288_H44441003_PIP-SCONN,HA
GND                      J6M1             48       SCONN288_H44441003_PIP-SCONN,HA
GND                      J6M1             50       SCONN288_H44441003_PIP-SCONN,HA
GND                      J6M1             53       SCONN288_H44441003_PIP-SCONN,HA
GND                      J6M1             55       SCONN288_H44441003_PIP-SCONN,HA
GND                      J6M1             57       SCONN288_H44441003_PIP-SCONN,HA
GND                      J6M1             94       SCONN288_H44441003_PIP-SCONN,HA
GND                      J6M1             96       SCONN288_H44441003_PIP-SCONN,HA
GND                      J6M1             98       SCONN288_H44441003_PIP-SCONN,HA
GND                      J6M1             101      SCONN288_H44441003_PIP-SCONN,HA
GND                      J6M1             103      SCONN288_H44441003_PIP-SCONN,HA
GND                      J6M1             105      SCONN288_H44441003_PIP-SCONN,HA
GND                      J6M1             107      SCONN288_H44441003_PIP-SCONN,HA
GND                      J6M1             109      SCONN288_H44441003_PIP-SCONN,HA
GND                      J6M1             112      SCONN288_H44441003_PIP-SCONN,HA
GND                      J6M1             114      SCONN288_H44441003_PIP-SCONN,HA
GND                      J6M1             116      SCONN288_H44441003_PIP-SCONN,HA
GND                      J6M1             118      SCONN288_H44441003_PIP-SCONN,HA
GND                      J6M1             120      SCONN288_H44441003_PIP-SCONN,HA
GND                      J6M1             123      SCONN288_H44441003_PIP-SCONN,HA
GND                      J6M1             125      SCONN288_H44441003_PIP-SCONN,HA
GND                      J6M1             127      SCONN288_H44441003_PIP-SCONN,HA
GND                      J6M1             129      SCONN288_H44441003_PIP-SCONN,HA
GND                      J6M1             131      SCONN288_H44441003_PIP-SCONN,HA
GND                      J6M1             134      SCONN288_H44441003_PIP-SCONN,HA
GND                      J6M1             136      SCONN288_H44441003_PIP-SCONN,HA
GND                      J6M1             138      SCONN288_H44441003_PIP-SCONN,HA
GND                      J6M1             140      SCONN288_H44441003_PIP-SCONN,HA
GND                      J6M1             147      SCONN288_H44441003_PIP-SCONN,HA
GND                      J6M1             149      SCONN288_H44441003_PIP-SCONN,HA
GND                      J6M1             151      SCONN288_H44441003_PIP-SCONN,HA
GND                      J6M1             154      SCONN288_H44441003_PIP-SCONN,HA
GND                      J6M1             156      SCONN288_H44441003_PIP-SCONN,HA
GND                      J6M1             158      SCONN288_H44441003_PIP-SCONN,HA
GND                      J6M1             160      SCONN288_H44441003_PIP-SCONN,HA
GND                      J6M1             162      SCONN288_H44441003_PIP-SCONN,HA
GND                      J6M1             165      SCONN288_H44441003_PIP-SCONN,HA
GND                      J6M1             167      SCONN288_H44441003_PIP-SCONN,HA
GND                      J6M1             169      SCONN288_H44441003_PIP-SCONN,HA
GND                      J6M1             171      SCONN288_H44441003_PIP-SCONN,HA
GND                      J6M1             173      SCONN288_H44441003_PIP-SCONN,HA
GND                      J6M1             176      SCONN288_H44441003_PIP-SCONN,HA
GND                      J6M1             178      SCONN288_H44441003_PIP-SCONN,HA
GND                      J6M1             180      SCONN288_H44441003_PIP-SCONN,HA
GND                      J6M1             182      SCONN288_H44441003_PIP-SCONN,HA
GND                      J6M1             184      SCONN288_H44441003_PIP-SCONN,HA
GND                      J6M1             187      SCONN288_H44441003_PIP-SCONN,HA
GND                      J6M1             189      SCONN288_H44441003_PIP-SCONN,HA
GND                      J6M1             191      SCONN288_H44441003_PIP-SCONN,HA
GND                      J6M1             193      SCONN288_H44441003_PIP-SCONN,HA
GND                      J6M1             195      SCONN288_H44441003_PIP-SCONN,HA
GND                      J6M1             198      SCONN288_H44441003_PIP-SCONN,HA
GND                      J6M1             200      SCONN288_H44441003_PIP-SCONN,HA
GND                      J6M1             202      SCONN288_H44441003_PIP-SCONN,HA
GND                      J6M1             238      SCONN288_H44441003_PIP-SCONN,HA
GND                      J6M1             239      SCONN288_H44441003_PIP-SCONN,HA
GND                      J6M1             241      SCONN288_H44441003_PIP-SCONN,HA
GND                      J6M1             243      SCONN288_H44441003_PIP-SCONN,HA
GND                      J6M1             246      SCONN288_H44441003_PIP-SCONN,HA
GND                      J6M1             248      SCONN288_H44441003_PIP-SCONN,HA
GND                      J6M1             250      SCONN288_H44441003_PIP-SCONN,HA
GND                      J6M1             252      SCONN288_H44441003_PIP-SCONN,HA
GND                      J6M1             254      SCONN288_H44441003_PIP-SCONN,HA
GND                      J6M1             257      SCONN288_H44441003_PIP-SCONN,HA
GND                      J6M1             259      SCONN288_H44441003_PIP-SCONN,HA
GND                      J6M1             261      SCONN288_H44441003_PIP-SCONN,HA
GND                      J6M1             263      SCONN288_H44441003_PIP-SCONN,HA
GND                      J6M1             265      SCONN288_H44441003_PIP-SCONN,HA
GND                      J6M1             268      SCONN288_H44441003_PIP-SCONN,HA
GND                      J6M1             270      SCONN288_H44441003_PIP-SCONN,HA
GND                      J6M1             272      SCONN288_H44441003_PIP-SCONN,HA
GND                      J6M1             274      SCONN288_H44441003_PIP-SCONN,HA
GND                      J6M1             276      SCONN288_H44441003_PIP-SCONN,HA
GND                      J6M1             279      SCONN288_H44441003_PIP-SCONN,HA
GND                      J6M1             281      SCONN288_H44441003_PIP-SCONN,HA
GND                      J6M1             283      SCONN288_H44441003_PIP-SCONN,HA
GND                      J6T1             2        SCONN288_H44441003_PIP-SCONN,HA
GND                      J6T1             4        SCONN288_H44441003_PIP-SCONN,HA
GND                      J6T1             6        SCONN288_H44441003_PIP-SCONN,HA
GND                      J6T1             9        SCONN288_H44441003_PIP-SCONN,HA
GND                      J6T1             11       SCONN288_H44441003_PIP-SCONN,HA
GND                      J6T1             13       SCONN288_H44441003_PIP-SCONN,HA
GND                      J6T1             15       SCONN288_H44441003_PIP-SCONN,HA
GND                      J6T1             17       SCONN288_H44441003_PIP-SCONN,HA
GND                      J6T1             20       SCONN288_H44441003_PIP-SCONN,HA
GND                      J6T1             22       SCONN288_H44441003_PIP-SCONN,HA
GND                      J6T1             24       SCONN288_H44441003_PIP-SCONN,HA
GND                      J6T1             26       SCONN288_H44441003_PIP-SCONN,HA
GND                      J6T1             28       SCONN288_H44441003_PIP-SCONN,HA
GND                      J6T1             31       SCONN288_H44441003_PIP-SCONN,HA
GND                      J6T1             33       SCONN288_H44441003_PIP-SCONN,HA
GND                      J6T1             35       SCONN288_H44441003_PIP-SCONN,HA
GND                      J6T1             37       SCONN288_H44441003_PIP-SCONN,HA
GND                      J6T1             39       SCONN288_H44441003_PIP-SCONN,HA
GND                      J6T1             42       SCONN288_H44441003_PIP-SCONN,HA
GND                      J6T1             44       SCONN288_H44441003_PIP-SCONN,HA
GND                      J6T1             46       SCONN288_H44441003_PIP-SCONN,HA
GND                      J6T1             48       SCONN288_H44441003_PIP-SCONN,HA
GND                      J6T1             50       SCONN288_H44441003_PIP-SCONN,HA
GND                      J6T1             53       SCONN288_H44441003_PIP-SCONN,HA
GND                      J6T1             55       SCONN288_H44441003_PIP-SCONN,HA
GND                      J6T1             57       SCONN288_H44441003_PIP-SCONN,HA
GND                      J6T1             94       SCONN288_H44441003_PIP-SCONN,HA
GND                      J6T1             96       SCONN288_H44441003_PIP-SCONN,HA
GND                      J6T1             98       SCONN288_H44441003_PIP-SCONN,HA
GND                      J6T1             101      SCONN288_H44441003_PIP-SCONN,HA
GND                      J6T1             103      SCONN288_H44441003_PIP-SCONN,HA
GND                      J6T1             105      SCONN288_H44441003_PIP-SCONN,HA
GND                      J6T1             107      SCONN288_H44441003_PIP-SCONN,HA
GND                      J6T1             109      SCONN288_H44441003_PIP-SCONN,HA
GND                      J6T1             112      SCONN288_H44441003_PIP-SCONN,HA
GND                      J6T1             114      SCONN288_H44441003_PIP-SCONN,HA
GND                      J6T1             116      SCONN288_H44441003_PIP-SCONN,HA
GND                      J6T1             118      SCONN288_H44441003_PIP-SCONN,HA
GND                      J6T1             120      SCONN288_H44441003_PIP-SCONN,HA
GND                      J6T1             123      SCONN288_H44441003_PIP-SCONN,HA
GND                      J6T1             125      SCONN288_H44441003_PIP-SCONN,HA
GND                      J6T1             127      SCONN288_H44441003_PIP-SCONN,HA
GND                      J6T1             129      SCONN288_H44441003_PIP-SCONN,HA
GND                      J6T1             131      SCONN288_H44441003_PIP-SCONN,HA
GND                      J6T1             134      SCONN288_H44441003_PIP-SCONN,HA
GND                      J6T1             136      SCONN288_H44441003_PIP-SCONN,HA
GND                      J6T1             138      SCONN288_H44441003_PIP-SCONN,HA
GND                      J6T1             140      SCONN288_H44441003_PIP-SCONN,HA
GND                      J6T1             147      SCONN288_H44441003_PIP-SCONN,HA
GND                      J6T1             149      SCONN288_H44441003_PIP-SCONN,HA
GND                      J6T1             151      SCONN288_H44441003_PIP-SCONN,HA
GND                      J6T1             154      SCONN288_H44441003_PIP-SCONN,HA
GND                      J6T1             156      SCONN288_H44441003_PIP-SCONN,HA
GND                      J6T1             158      SCONN288_H44441003_PIP-SCONN,HA
GND                      J6T1             160      SCONN288_H44441003_PIP-SCONN,HA
GND                      J6T1             162      SCONN288_H44441003_PIP-SCONN,HA
GND                      J6T1             165      SCONN288_H44441003_PIP-SCONN,HA
GND                      J6T1             167      SCONN288_H44441003_PIP-SCONN,HA
GND                      J6T1             169      SCONN288_H44441003_PIP-SCONN,HA
GND                      J6T1             171      SCONN288_H44441003_PIP-SCONN,HA
GND                      J6T1             173      SCONN288_H44441003_PIP-SCONN,HA
GND                      J6T1             176      SCONN288_H44441003_PIP-SCONN,HA
GND                      J6T1             178      SCONN288_H44441003_PIP-SCONN,HA
GND                      J6T1             180      SCONN288_H44441003_PIP-SCONN,HA
GND                      J6T1             182      SCONN288_H44441003_PIP-SCONN,HA
GND                      J6T1             184      SCONN288_H44441003_PIP-SCONN,HA
GND                      J6T1             187      SCONN288_H44441003_PIP-SCONN,HA
GND                      J6T1             189      SCONN288_H44441003_PIP-SCONN,HA
GND                      J6T1             191      SCONN288_H44441003_PIP-SCONN,HA
GND                      J6T1             193      SCONN288_H44441003_PIP-SCONN,HA
GND                      J6T1             195      SCONN288_H44441003_PIP-SCONN,HA
GND                      J6T1             198      SCONN288_H44441003_PIP-SCONN,HA
GND                      J6T1             200      SCONN288_H44441003_PIP-SCONN,HA
GND                      J6T1             202      SCONN288_H44441003_PIP-SCONN,HA
GND                      J6T1             238      SCONN288_H44441003_PIP-SCONN,HA
GND                      J6T1             239      SCONN288_H44441003_PIP-SCONN,HA
GND                      J6T1             241      SCONN288_H44441003_PIP-SCONN,HA
GND                      J6T1             243      SCONN288_H44441003_PIP-SCONN,HA
GND                      J6T1             246      SCONN288_H44441003_PIP-SCONN,HA
GND                      J6T1             248      SCONN288_H44441003_PIP-SCONN,HA
GND                      J6T1             250      SCONN288_H44441003_PIP-SCONN,HA
GND                      J6T1             252      SCONN288_H44441003_PIP-SCONN,HA
GND                      J6T1             254      SCONN288_H44441003_PIP-SCONN,HA
GND                      J6T1             257      SCONN288_H44441003_PIP-SCONN,HA
GND                      J6T1             259      SCONN288_H44441003_PIP-SCONN,HA
GND                      J6T1             261      SCONN288_H44441003_PIP-SCONN,HA
GND                      J6T1             263      SCONN288_H44441003_PIP-SCONN,HA
GND                      J6T1             265      SCONN288_H44441003_PIP-SCONN,HA
GND                      J6T1             268      SCONN288_H44441003_PIP-SCONN,HA
GND                      J6T1             270      SCONN288_H44441003_PIP-SCONN,HA
GND                      J6T1             272      SCONN288_H44441003_PIP-SCONN,HA
GND                      J6T1             274      SCONN288_H44441003_PIP-SCONN,HA
GND                      J6T1             276      SCONN288_H44441003_PIP-SCONN,HA
GND                      J6T1             279      SCONN288_H44441003_PIP-SCONN,HA
GND                      J6T1             281      SCONN288_H44441003_PIP-SCONN,HA
GND                      J6T1             283      SCONN288_H44441003_PIP-SCONN,HA
GND                      J6U1             2        SCONN288_H44441003_PIP-SCONN,HA
GND                      J6U1             4        SCONN288_H44441003_PIP-SCONN,HA
GND                      J6U1             6        SCONN288_H44441003_PIP-SCONN,HA
GND                      J6U1             9        SCONN288_H44441003_PIP-SCONN,HA
GND                      J6U1             11       SCONN288_H44441003_PIP-SCONN,HA
GND                      J6U1             13       SCONN288_H44441003_PIP-SCONN,HA
GND                      J6U1             15       SCONN288_H44441003_PIP-SCONN,HA
GND                      J6U1             17       SCONN288_H44441003_PIP-SCONN,HA
GND                      J6U1             20       SCONN288_H44441003_PIP-SCONN,HA
GND                      J6U1             22       SCONN288_H44441003_PIP-SCONN,HA
GND                      J6U1             24       SCONN288_H44441003_PIP-SCONN,HA
GND                      J6U1             26       SCONN288_H44441003_PIP-SCONN,HA
GND                      J6U1             28       SCONN288_H44441003_PIP-SCONN,HA
GND                      J6U1             31       SCONN288_H44441003_PIP-SCONN,HA
GND                      J6U1             33       SCONN288_H44441003_PIP-SCONN,HA
GND                      J6U1             35       SCONN288_H44441003_PIP-SCONN,HA
GND                      J6U1             37       SCONN288_H44441003_PIP-SCONN,HA
GND                      J6U1             39       SCONN288_H44441003_PIP-SCONN,HA
GND                      J6U1             42       SCONN288_H44441003_PIP-SCONN,HA
GND                      J6U1             44       SCONN288_H44441003_PIP-SCONN,HA
GND                      J6U1             46       SCONN288_H44441003_PIP-SCONN,HA
GND                      J6U1             48       SCONN288_H44441003_PIP-SCONN,HA
GND                      J6U1             50       SCONN288_H44441003_PIP-SCONN,HA
GND                      J6U1             53       SCONN288_H44441003_PIP-SCONN,HA
GND                      J6U1             55       SCONN288_H44441003_PIP-SCONN,HA
GND                      J6U1             57       SCONN288_H44441003_PIP-SCONN,HA
GND                      J6U1             94       SCONN288_H44441003_PIP-SCONN,HA
GND                      J6U1             96       SCONN288_H44441003_PIP-SCONN,HA
GND                      J6U1             98       SCONN288_H44441003_PIP-SCONN,HA
GND                      J6U1             101      SCONN288_H44441003_PIP-SCONN,HA
GND                      J6U1             103      SCONN288_H44441003_PIP-SCONN,HA
GND                      J6U1             105      SCONN288_H44441003_PIP-SCONN,HA
GND                      J6U1             107      SCONN288_H44441003_PIP-SCONN,HA
GND                      J6U1             109      SCONN288_H44441003_PIP-SCONN,HA
GND                      J6U1             112      SCONN288_H44441003_PIP-SCONN,HA
GND                      J6U1             114      SCONN288_H44441003_PIP-SCONN,HA
GND                      J6U1             116      SCONN288_H44441003_PIP-SCONN,HA
GND                      J6U1             118      SCONN288_H44441003_PIP-SCONN,HA
GND                      J6U1             120      SCONN288_H44441003_PIP-SCONN,HA
GND                      J6U1             123      SCONN288_H44441003_PIP-SCONN,HA
GND                      J6U1             125      SCONN288_H44441003_PIP-SCONN,HA
GND                      J6U1             127      SCONN288_H44441003_PIP-SCONN,HA
GND                      J6U1             129      SCONN288_H44441003_PIP-SCONN,HA
GND                      J6U1             131      SCONN288_H44441003_PIP-SCONN,HA
GND                      J6U1             134      SCONN288_H44441003_PIP-SCONN,HA
GND                      J6U1             136      SCONN288_H44441003_PIP-SCONN,HA
GND                      J6U1             138      SCONN288_H44441003_PIP-SCONN,HA
GND                      J6U1             147      SCONN288_H44441003_PIP-SCONN,HA
GND                      J6U1             149      SCONN288_H44441003_PIP-SCONN,HA
GND                      J6U1             151      SCONN288_H44441003_PIP-SCONN,HA
GND                      J6U1             154      SCONN288_H44441003_PIP-SCONN,HA
GND                      J6U1             156      SCONN288_H44441003_PIP-SCONN,HA
GND                      J6U1             158      SCONN288_H44441003_PIP-SCONN,HA
GND                      J6U1             160      SCONN288_H44441003_PIP-SCONN,HA
GND                      J6U1             162      SCONN288_H44441003_PIP-SCONN,HA
GND                      J6U1             165      SCONN288_H44441003_PIP-SCONN,HA
GND                      J6U1             167      SCONN288_H44441003_PIP-SCONN,HA
GND                      J6U1             169      SCONN288_H44441003_PIP-SCONN,HA
GND                      J6U1             171      SCONN288_H44441003_PIP-SCONN,HA
GND                      J6U1             173      SCONN288_H44441003_PIP-SCONN,HA
GND                      J6U1             176      SCONN288_H44441003_PIP-SCONN,HA
GND                      J6U1             178      SCONN288_H44441003_PIP-SCONN,HA
GND                      J6U1             180      SCONN288_H44441003_PIP-SCONN,HA
GND                      J6U1             182      SCONN288_H44441003_PIP-SCONN,HA
GND                      J6U1             184      SCONN288_H44441003_PIP-SCONN,HA
GND                      J6U1             187      SCONN288_H44441003_PIP-SCONN,HA
GND                      J6U1             189      SCONN288_H44441003_PIP-SCONN,HA
GND                      J6U1             191      SCONN288_H44441003_PIP-SCONN,HA
GND                      J6U1             193      SCONN288_H44441003_PIP-SCONN,HA
GND                      J6U1             195      SCONN288_H44441003_PIP-SCONN,HA
GND                      J6U1             198      SCONN288_H44441003_PIP-SCONN,HA
GND                      J6U1             200      SCONN288_H44441003_PIP-SCONN,HA
GND                      J6U1             202      SCONN288_H44441003_PIP-SCONN,HA
GND                      J6U1             238      SCONN288_H44441003_PIP-SCONN,HA
GND                      J6U1             239      SCONN288_H44441003_PIP-SCONN,HA
GND                      J6U1             241      SCONN288_H44441003_PIP-SCONN,HA
GND                      J6U1             243      SCONN288_H44441003_PIP-SCONN,HA
GND                      J6U1             246      SCONN288_H44441003_PIP-SCONN,HA
GND                      J6U1             248      SCONN288_H44441003_PIP-SCONN,HA
GND                      J6U1             250      SCONN288_H44441003_PIP-SCONN,HA
GND                      J6U1             252      SCONN288_H44441003_PIP-SCONN,HA
GND                      J6U1             254      SCONN288_H44441003_PIP-SCONN,HA
GND                      J6U1             257      SCONN288_H44441003_PIP-SCONN,HA
GND                      J6U1             259      SCONN288_H44441003_PIP-SCONN,HA
GND                      J6U1             261      SCONN288_H44441003_PIP-SCONN,HA
GND                      J6U1             263      SCONN288_H44441003_PIP-SCONN,HA
GND                      J6U1             265      SCONN288_H44441003_PIP-SCONN,HA
GND                      J6U1             268      SCONN288_H44441003_PIP-SCONN,HA
GND                      J6U1             270      SCONN288_H44441003_PIP-SCONN,HA
GND                      J6U1             272      SCONN288_H44441003_PIP-SCONN,HA
GND                      J6U1             274      SCONN288_H44441003_PIP-SCONN,HA
GND                      J6U1             276      SCONN288_H44441003_PIP-SCONN,HA
GND                      J6U1             279      SCONN288_H44441003_PIP-SCONN,HA
GND                      J6U1             281      SCONN288_H44441003_PIP-SCONN,HA
GND                      J6U1             283      SCONN288_H44441003_PIP-SCONN,HA
GND                      J6U2             2        SCONN288_H44441003_PIP-SCONN,HA
GND                      J6U2             4        SCONN288_H44441003_PIP-SCONN,HA
GND                      J6U2             6        SCONN288_H44441003_PIP-SCONN,HA
GND                      J6U2             9        SCONN288_H44441003_PIP-SCONN,HA
GND                      J6U2             11       SCONN288_H44441003_PIP-SCONN,HA
GND                      J6U2             13       SCONN288_H44441003_PIP-SCONN,HA
GND                      J6U2             15       SCONN288_H44441003_PIP-SCONN,HA
GND                      J6U2             17       SCONN288_H44441003_PIP-SCONN,HA
GND                      J6U2             20       SCONN288_H44441003_PIP-SCONN,HA
GND                      J6U2             22       SCONN288_H44441003_PIP-SCONN,HA
GND                      J6U2             24       SCONN288_H44441003_PIP-SCONN,HA
GND                      J6U2             26       SCONN288_H44441003_PIP-SCONN,HA
GND                      J6U2             28       SCONN288_H44441003_PIP-SCONN,HA
GND                      J6U2             31       SCONN288_H44441003_PIP-SCONN,HA
GND                      J6U2             33       SCONN288_H44441003_PIP-SCONN,HA
GND                      J6U2             35       SCONN288_H44441003_PIP-SCONN,HA
GND                      J6U2             37       SCONN288_H44441003_PIP-SCONN,HA
GND                      J6U2             39       SCONN288_H44441003_PIP-SCONN,HA
GND                      J6U2             42       SCONN288_H44441003_PIP-SCONN,HA
GND                      J6U2             44       SCONN288_H44441003_PIP-SCONN,HA
GND                      J6U2             46       SCONN288_H44441003_PIP-SCONN,HA
GND                      J6U2             48       SCONN288_H44441003_PIP-SCONN,HA
GND                      J6U2             50       SCONN288_H44441003_PIP-SCONN,HA
GND                      J6U2             53       SCONN288_H44441003_PIP-SCONN,HA
GND                      J6U2             55       SCONN288_H44441003_PIP-SCONN,HA
GND                      J6U2             57       SCONN288_H44441003_PIP-SCONN,HA
GND                      J6U2             94       SCONN288_H44441003_PIP-SCONN,HA
GND                      J6U2             96       SCONN288_H44441003_PIP-SCONN,HA
GND                      J6U2             98       SCONN288_H44441003_PIP-SCONN,HA
GND                      J6U2             101      SCONN288_H44441003_PIP-SCONN,HA
GND                      J6U2             103      SCONN288_H44441003_PIP-SCONN,HA
GND                      J6U2             105      SCONN288_H44441003_PIP-SCONN,HA
GND                      J6U2             107      SCONN288_H44441003_PIP-SCONN,HA
GND                      J6U2             109      SCONN288_H44441003_PIP-SCONN,HA
GND                      J6U2             112      SCONN288_H44441003_PIP-SCONN,HA
GND                      J6U2             114      SCONN288_H44441003_PIP-SCONN,HA
GND                      J6U2             116      SCONN288_H44441003_PIP-SCONN,HA
GND                      J6U2             118      SCONN288_H44441003_PIP-SCONN,HA
GND                      J6U2             120      SCONN288_H44441003_PIP-SCONN,HA
GND                      J6U2             123      SCONN288_H44441003_PIP-SCONN,HA
GND                      J6U2             125      SCONN288_H44441003_PIP-SCONN,HA
GND                      J6U2             127      SCONN288_H44441003_PIP-SCONN,HA
GND                      J6U2             129      SCONN288_H44441003_PIP-SCONN,HA
GND                      J6U2             131      SCONN288_H44441003_PIP-SCONN,HA
GND                      J6U2             134      SCONN288_H44441003_PIP-SCONN,HA
GND                      J6U2             136      SCONN288_H44441003_PIP-SCONN,HA
GND                      J6U2             138      SCONN288_H44441003_PIP-SCONN,HA
GND                      J6U2             140      SCONN288_H44441003_PIP-SCONN,HA
GND                      J6U2             147      SCONN288_H44441003_PIP-SCONN,HA
GND                      J6U2             149      SCONN288_H44441003_PIP-SCONN,HA
GND                      J6U2             151      SCONN288_H44441003_PIP-SCONN,HA
GND                      J6U2             154      SCONN288_H44441003_PIP-SCONN,HA
GND                      J6U2             156      SCONN288_H44441003_PIP-SCONN,HA
GND                      J6U2             158      SCONN288_H44441003_PIP-SCONN,HA
GND                      J6U2             160      SCONN288_H44441003_PIP-SCONN,HA
GND                      J6U2             162      SCONN288_H44441003_PIP-SCONN,HA
GND                      J6U2             165      SCONN288_H44441003_PIP-SCONN,HA
GND                      J6U2             167      SCONN288_H44441003_PIP-SCONN,HA
GND                      J6U2             169      SCONN288_H44441003_PIP-SCONN,HA
GND                      J6U2             171      SCONN288_H44441003_PIP-SCONN,HA
GND                      J6U2             173      SCONN288_H44441003_PIP-SCONN,HA
GND                      J6U2             176      SCONN288_H44441003_PIP-SCONN,HA
GND                      J6U2             178      SCONN288_H44441003_PIP-SCONN,HA
GND                      J6U2             180      SCONN288_H44441003_PIP-SCONN,HA
GND                      J6U2             182      SCONN288_H44441003_PIP-SCONN,HA
GND                      J6U2             184      SCONN288_H44441003_PIP-SCONN,HA
GND                      J6U2             187      SCONN288_H44441003_PIP-SCONN,HA
GND                      J6U2             189      SCONN288_H44441003_PIP-SCONN,HA
GND                      J6U2             191      SCONN288_H44441003_PIP-SCONN,HA
GND                      J6U2             193      SCONN288_H44441003_PIP-SCONN,HA
GND                      J6U2             195      SCONN288_H44441003_PIP-SCONN,HA
GND                      J6U2             198      SCONN288_H44441003_PIP-SCONN,HA
GND                      J6U2             200      SCONN288_H44441003_PIP-SCONN,HA
GND                      J6U2             202      SCONN288_H44441003_PIP-SCONN,HA
GND                      J6U2             239      SCONN288_H44441003_PIP-SCONN,HA
GND                      J6U2             241      SCONN288_H44441003_PIP-SCONN,HA
GND                      J6U2             243      SCONN288_H44441003_PIP-SCONN,HA
GND                      J6U2             246      SCONN288_H44441003_PIP-SCONN,HA
GND                      J6U2             248      SCONN288_H44441003_PIP-SCONN,HA
GND                      J6U2             250      SCONN288_H44441003_PIP-SCONN,HA
GND                      J6U2             252      SCONN288_H44441003_PIP-SCONN,HA
GND                      J6U2             254      SCONN288_H44441003_PIP-SCONN,HA
GND                      J6U2             257      SCONN288_H44441003_PIP-SCONN,HA
GND                      J6U2             259      SCONN288_H44441003_PIP-SCONN,HA
GND                      J6U2             261      SCONN288_H44441003_PIP-SCONN,HA
GND                      J6U2             263      SCONN288_H44441003_PIP-SCONN,HA
GND                      J6U2             265      SCONN288_H44441003_PIP-SCONN,HA
GND                      J6U2             268      SCONN288_H44441003_PIP-SCONN,HA
GND                      J6U2             270      SCONN288_H44441003_PIP-SCONN,HA
GND                      J6U2             272      SCONN288_H44441003_PIP-SCONN,HA
GND                      J6U2             274      SCONN288_H44441003_PIP-SCONN,HA
GND                      J6U2             276      SCONN288_H44441003_PIP-SCONN,HA
GND                      J6U2             279      SCONN288_H44441003_PIP-SCONN,HA
GND                      J6U2             281      SCONN288_H44441003_PIP-SCONN,HA
GND                      J6U2             283      SCONN288_H44441003_PIP-SCONN,HA
GND                      J7G2             7        CONN8_C77962004_PIP-CONN,C7796A
GND                      J8A1             1A3      CONN72_G97614002_A_CP-CONN,G97A
GND                      J8A1             1A6      CONN72_G97614002_A_CP-CONN,G97A
GND                      J8A1             1A9      CONN72_G97614002_A_CP-CONN,G97A
GND                      J8A1             1B1      CONN72_G97614002_A_CP-CONN,G97A
GND                      J8A1             1B3      CONN72_G97614002_A_CP-CONN,G97A
GND                      J8A1             1B6      CONN72_G97614002_A_CP-CONN,G97A
GND                      J8A1             1B9      CONN72_G97614002_A_CP-CONN,G97A
GND                      J8A1             1C2      CONN72_G97614002_A_CP-CONN,G97A
GND                      J8A1             1C3      CONN72_G97614002_A_CP-CONN,G97A
GND                      J8A1             1C6      CONN72_G97614002_A_CP-CONN,G97A
GND                      J8A1             1C9      CONN72_G97614002_A_CP-CONN,G97A
GND                      J8A1             1D3      CONN72_G97614002_A_CP-CONN,G97A
GND                      J8A1             1D6      CONN72_G97614002_A_CP-CONN,G97A
GND                      J8A1             1D9      CONN72_G97614002_A_CP-CONN,G97A
GND                      J8A1             2A3      CONN72_G97614002_A_CP-CONN,G97A
GND                      J8A1             2A6      CONN72_G97614002_A_CP-CONN,G97A
GND                      J8A1             2A9      CONN72_G97614002_A_CP-CONN,G97A
GND                      J8A1             2B1      CONN72_G97614002_A_CP-CONN,G97A
GND                      J8A1             2B3      CONN72_G97614002_A_CP-CONN,G97A
GND                      J8A1             2B6      CONN72_G97614002_A_CP-CONN,G97A
GND                      J8A1             2B9      CONN72_G97614002_A_CP-CONN,G97A
GND                      J8A1             2C2      CONN72_G97614002_A_CP-CONN,G97A
GND                      J8A1             2C3      CONN72_G97614002_A_CP-CONN,G97A
GND                      J8A1             2C6      CONN72_G97614002_A_CP-CONN,G97A
GND                      J8A1             2C9      CONN72_G97614002_A_CP-CONN,G97A
GND                      J8A1             2D3      CONN72_G97614002_A_CP-CONN,G97A
GND                      J8A1             2D6      CONN72_G97614002_A_CP-CONN,G97A
GND                      J8A1             2D9      CONN72_G97614002_A_CP-CONN,G97A
GND                      J8A2             A3       CONN36_G97614001_CP-CONN,G9761A
GND                      J8A2             A6       CONN36_G97614001_CP-CONN,G9761A
GND                      J8A2             A9       CONN36_G97614001_CP-CONN,G9761A
GND                      J8A2             B1       CONN36_G97614001_CP-CONN,G9761A
GND                      J8A2             B3       CONN36_G97614001_CP-CONN,G9761A
GND                      J8A2             B6       CONN36_G97614001_CP-CONN,G9761A
GND                      J8A2             B9       CONN36_G97614001_CP-CONN,G9761A
GND                      J8A2             C2       CONN36_G97614001_CP-CONN,G9761A
GND                      J8A2             C3       CONN36_G97614001_CP-CONN,G9761A
GND                      J8A2             C6       CONN36_G97614001_CP-CONN,G9761A
GND                      J8A2             C9       CONN36_G97614001_CP-CONN,G9761A
GND                      J8A2             D3       CONN36_G97614001_CP-CONN,G9761A
GND                      J8A2             D6       CONN36_G97614001_CP-CONN,G9761A
GND                      J8A2             D9       CONN36_G97614001_CP-CONN,G9761A
GND                      J8A3             1        CONN7_E82125014_PIP_TH-EMPTY,EA
GND                      J8A3             4        CONN7_E82125014_PIP_TH-EMPTY,EA
GND                      J8A3             7        CONN7_E82125014_PIP_TH-EMPTY,EA
GND                      J8A3             MH1      CONN7_E82125014_PIP_TH-EMPTY,EA
GND                      J8A3             MH2      CONN7_E82125014_PIP_TH-EMPTY,EA
GND                      J8A4             2        CONN4_H73295001_PIP-EMPTY,H732A
GND                      J8A4             3        CONN4_H73295001_PIP-EMPTY,H732A
GND                      J8B1             1        SCONN24_H46321001_SM-SCONN,H46A
GND                      J8B1             7        SCONN24_H46321001_SM-SCONN,H46A
GND                      J8B1             9        SCONN24_H46321001_SM-SCONN,H46A
GND                      J8B1             15       SCONN24_H46321001_SM-SCONN,H46A
GND                      J8B1             23       SCONN24_H46321001_SM-SCONN,H46A
GND                      J8B1             MP1      SCONN24_H46321001_SM-SCONN,H46A
GND                      J8B1             MP2      SCONN24_H46321001_SM-SCONN,H46A
GND                      J8C1             2        CONN3_C95678002_PIP-CONN,C9567A
GND                      J8D4             2        CONN3_C95678002_PIP-CONN,C9567A
GND                      J8E1             11       SCONN11_H67026001_SM-CONN,H670A
GND                      J8E1             MP1      SCONN11_H67026001_SM-CONN,H670A
GND                      J8E1             MP2      SCONN11_H67026001_SM-CONN,H670A
GND                      J8E3             3        SCONN80_E67482007_SM-CONN,E674A
GND                      J8E3             8        SCONN80_E67482007_SM-CONN,E674A
GND                      J8E3             9        SCONN80_E67482007_SM-CONN,E674A
GND                      J8E3             11       SCONN80_E67482007_SM-CONN,E674A
GND                      J8E3             14       SCONN80_E67482007_SM-CONN,E674A
GND                      J8E3             16       SCONN80_E67482007_SM-CONN,E674A
GND                      J8E3             17       SCONN80_E67482007_SM-CONN,E674A
GND                      J8E3             19       SCONN80_E67482007_SM-CONN,E674A
GND                      J8E3             22       SCONN80_E67482007_SM-CONN,E674A
GND                      J8E3             24       SCONN80_E67482007_SM-CONN,E674A
GND                      J8E3             25       SCONN80_E67482007_SM-CONN,E674A
GND                      J8E3             27       SCONN80_E67482007_SM-CONN,E674A
GND                      J8E3             30       SCONN80_E67482007_SM-CONN,E674A
GND                      J8E3             32       SCONN80_E67482007_SM-CONN,E674A
GND                      J8E3             33       SCONN80_E67482007_SM-CONN,E674A
GND                      J8E3             35       SCONN80_E67482007_SM-CONN,E674A
GND                      J8E3             38       SCONN80_E67482007_SM-CONN,E674A
GND                      J8E3             40       SCONN80_E67482007_SM-CONN,E674A
GND                      J8E3             41       SCONN80_E67482007_SM-CONN,E674A
GND                      J8E3             43       SCONN80_E67482007_SM-CONN,E674A
GND                      J8E3             46       SCONN80_E67482007_SM-CONN,E674A
GND                      J8E3             48       SCONN80_E67482007_SM-CONN,E674A
GND                      J8E3             49       SCONN80_E67482007_SM-CONN,E674A
GND                      J8E3             51       SCONN80_E67482007_SM-CONN,E674A
GND                      J8E3             54       SCONN80_E67482007_SM-CONN,E674A
GND                      J8E3             56       SCONN80_E67482007_SM-CONN,E674A
GND                      J8E3             57       SCONN80_E67482007_SM-CONN,E674A
GND                      J8E3             59       SCONN80_E67482007_SM-CONN,E674A
GND                      J8E3             62       SCONN80_E67482007_SM-CONN,E674A
GND                      J8E3             64       SCONN80_E67482007_SM-CONN,E674A
GND                      J8E3             65       SCONN80_E67482007_SM-CONN,E674A
GND                      J8E3             67       SCONN80_E67482007_SM-CONN,E674A
GND                      J8E3             70       SCONN80_E67482007_SM-CONN,E674A
GND                      J8E3             72       SCONN80_E67482007_SM-CONN,E674A
GND                      J8E3             73       SCONN80_E67482007_SM-CONN,E674A
GND                      J8E3             78       SCONN80_E67482007_SM-CONN,E674A
GND                      J8E4             4        SCONN64_H87568002_A_SMT-CONN,HA
GND                      J8E4             7        SCONN64_H87568002_A_SMT-CONN,HA
GND                      J8E4             10       SCONN64_H87568002_A_SMT-CONN,HA
GND                      J8E4             13       SCONN64_H87568002_A_SMT-CONN,HA
GND                      J8E4             16       SCONN64_H87568002_A_SMT-CONN,HA
GND                      J8E4             19       SCONN64_H87568002_A_SMT-CONN,HA
GND                      J8E4             22       SCONN64_H87568002_A_SMT-CONN,HA
GND                      J8E4             25       SCONN64_H87568002_A_SMT-CONN,HA
GND                      J8E4             28       SCONN64_H87568002_A_SMT-CONN,HA
GND                      J8E4             39       SCONN64_H87568002_A_SMT-CONN,HA
GND                      J8E4             42       SCONN64_H87568002_A_SMT-CONN,HA
GND                      J8E4             45       SCONN64_H87568002_A_SMT-CONN,HA
GND                      J8E4             48       SCONN64_H87568002_A_SMT-CONN,HA
GND                      J8E4             51       SCONN64_H87568002_A_SMT-CONN,HA
GND                      J8E4             54       SCONN64_H87568002_A_SMT-CONN,HA
GND                      J8E4             57       SCONN64_H87568002_A_SMT-CONN,HA
GND                      J8E4             60       SCONN64_H87568002_A_SMT-CONN,HA
GND                      J8E4             63       SCONN64_H87568002_A_SMT-CONN,HA
GND                      J8F1             1        SCONN75K_H17033002_SMT1-SCONN,A
GND                      J8F1             3        SCONN75K_H17033002_SMT1-SCONN,A
GND                      J8F1             9        SCONN75K_H17033002_SMT1-SCONN,A
GND                      J8F1             15       SCONN75K_H17033002_SMT1-SCONN,A
GND                      J8F1             21       SCONN75K_H17033002_SMT1-SCONN,A
GND                      J8F1             27       SCONN75K_H17033002_SMT1-SCONN,A
GND                      J8F1             33       SCONN75K_H17033002_SMT1-SCONN,A
GND                      J8F1             39       SCONN75K_H17033002_SMT1-SCONN,A
GND                      J8F1             45       SCONN75K_H17033002_SMT1-SCONN,A
GND                      J8F1             51       SCONN75K_H17033002_SMT1-SCONN,A
GND                      J8F1             57       SCONN75K_H17033002_SMT1-SCONN,A
GND                      J8F1             71       SCONN75K_H17033002_SMT1-SCONN,A
GND                      J8F1             73       SCONN75K_H17033002_SMT1-SCONN,A
GND                      J8F1             75       SCONN75K_H17033002_SMT1-SCONN,A
GND                      J8F1             MP1      SCONN75K_H17033002_SMT1-SCONN,A
GND                      J8F1             MP2      SCONN75K_H17033002_SMT1-SCONN,A
GND                      J8G1             13       SCONN200_H68296001_SM-CONN,H68A
GND                      J8G1             14       SCONN200_H68296001_SM-CONN,H68A
GND                      J8G1             26       SCONN200_H68296001_SM-CONN,H68A
GND                      J8G1             31       SCONN200_H68296001_SM-CONN,H68A
GND                      J8G1             34       SCONN200_H68296001_SM-CONN,H68A
GND                      J8G1             37       SCONN200_H68296001_SM-CONN,H68A
GND                      J8G1             40       SCONN200_H68296001_SM-CONN,H68A
GND                      J8G1             43       SCONN200_H68296001_SM-CONN,H68A
GND                      J8G1             46       SCONN200_H68296001_SM-CONN,H68A
GND                      J8G1             49       SCONN200_H68296001_SM-CONN,H68A
GND                      J8G1             52       SCONN200_H68296001_SM-CONN,H68A
GND                      J8G1             55       SCONN200_H68296001_SM-CONN,H68A
GND                      J8G1             58       SCONN200_H68296001_SM-CONN,H68A
GND                      J8G1             61       SCONN200_H68296001_SM-CONN,H68A
GND                      J8G1             64       SCONN200_H68296001_SM-CONN,H68A
GND                      J8G1             65       SCONN200_H68296001_SM-CONN,H68A
GND                      J8G1             68       SCONN200_H68296001_SM-CONN,H68A
GND                      J8G1             71       SCONN200_H68296001_SM-CONN,H68A
GND                      J8G1             74       SCONN200_H68296001_SM-CONN,H68A
GND                      J8G1             77       SCONN200_H68296001_SM-CONN,H68A
GND                      J8G1             80       SCONN200_H68296001_SM-CONN,H68A
GND                      J8G1             83       SCONN200_H68296001_SM-CONN,H68A
GND                      J8G1             86       SCONN200_H68296001_SM-CONN,H68A
GND                      J8G1             89       SCONN200_H68296001_SM-CONN,H68A
GND                      J8G1             92       SCONN200_H68296001_SM-CONN,H68A
GND                      J8G1             95       SCONN200_H68296001_SM-CONN,H68A
GND                      J8G1             98       SCONN200_H68296001_SM-CONN,H68A
GND                      J8G1             101      SCONN200_H68296001_SM-CONN,H68A
GND                      J8G1             104      SCONN200_H68296001_SM-CONN,H68A
GND                      J8G1             107      SCONN200_H68296001_SM-CONN,H68A
GND                      J8G1             110      SCONN200_H68296001_SM-CONN,H68A
GND                      J8G1             113      SCONN200_H68296001_SM-CONN,H68A
GND                      J8G1             116      SCONN200_H68296001_SM-CONN,H68A
GND                      J8G1             119      SCONN200_H68296001_SM-CONN,H68A
GND                      J8G1             122      SCONN200_H68296001_SM-CONN,H68A
GND                      J8G1             125      SCONN200_H68296001_SM-CONN,H68A
GND                      J8G1             128      SCONN200_H68296001_SM-CONN,H68A
GND                      J8G1             131      SCONN200_H68296001_SM-CONN,H68A
GND                      J8G1             134      SCONN200_H68296001_SM-CONN,H68A
GND                      J8G1             137      SCONN200_H68296001_SM-CONN,H68A
GND                      J8G1             140      SCONN200_H68296001_SM-CONN,H68A
GND                      J8G1             143      SCONN200_H68296001_SM-CONN,H68A
GND                      J8G1             146      SCONN200_H68296001_SM-CONN,H68A
GND                      J8G1             149      SCONN200_H68296001_SM-CONN,H68A
GND                      J8G1             152      SCONN200_H68296001_SM-CONN,H68A
GND                      J8G1             155      SCONN200_H68296001_SM-CONN,H68A
GND                      J8G1             158      SCONN200_H68296001_SM-CONN,H68A
GND                      J8G1             161      SCONN200_H68296001_SM-CONN,H68A
GND                      J8G1             164      SCONN200_H68296001_SM-CONN,H68A
GND                      J8G1             167      SCONN200_H68296001_SM-CONN,H68A
GND                      J8G1             170      SCONN200_H68296001_SM-CONN,H68A
GND                      J8G1             173      SCONN200_H68296001_SM-CONN,H68A
GND                      J8G1             176      SCONN200_H68296001_SM-CONN,H68A
GND                      J8G1             179      SCONN200_H68296001_SM-CONN,H68A
GND                      J8G1             182      SCONN200_H68296001_SM-CONN,H68A
GND                      J8G1             185      SCONN200_H68296001_SM-CONN,H68A
GND                      J8G1             188      SCONN200_H68296001_SM-CONN,H68A
GND                      J8G1             191      SCONN200_H68296001_SM-CONN,H68A
GND                      J8G1             194      SCONN200_H68296001_SM-CONN,H68A
GND                      J8G1             197      SCONN200_H68296001_SM-CONN,H68A
GND                      J8G1             200      SCONN200_H68296001_SM-CONN,H68A
GND                      J8G1             MH1      SCONN200_H68296001_SM-CONN,H68A
GND                      J8G1             MH2      SCONN200_H68296001_SM-CONN,H68A
GND                      J8G2             5        CONN12_C73564003_PIP-CONN,C735A
GND                      J8G2             6        CONN12_C73564003_PIP-CONN,C735A
GND                      J8G2             11       CONN12_C73564003_PIP-CONN,C735A
GND                      J8G2             12       CONN12_C73564003_PIP-CONN,C735A
GND                      J9A1             1        CONN4_D42317002_PIP-CONN,D4231A
GND                      J9A1             3        CONN4_D42317002_PIP-CONN,D4231A
GND                      J9A2             13       CONN14_H54902001_PIP-CONN,H549A
GND                      J9A3             2        SCONN60_C21100002_SMLF-CONN,C2A
GND                      J9A3             7        SCONN60_C21100002_SMLF-CONN,C2A
GND                      J9A3             8        SCONN60_C21100002_SMLF-CONN,C2A
GND                      J9A3             13       SCONN60_C21100002_SMLF-CONN,C2A
GND                      J9A3             14       SCONN60_C21100002_SMLF-CONN,C2A
GND                      J9A3             19       SCONN60_C21100002_SMLF-CONN,C2A
GND                      J9A3             20       SCONN60_C21100002_SMLF-CONN,C2A
GND                      J9A3             25       SCONN60_C21100002_SMLF-CONN,C2A
GND                      J9A3             26       SCONN60_C21100002_SMLF-CONN,C2A
GND                      J9A3             31       SCONN60_C21100002_SMLF-CONN,C2A
GND                      J9A3             32       SCONN60_C21100002_SMLF-CONN,C2A
GND                      J9A3             37       SCONN60_C21100002_SMLF-CONN,C2A
GND                      J9A3             38       SCONN60_C21100002_SMLF-CONN,C2A
GND                      J9A3             49       SCONN60_C21100002_SMLF-CONN,C2A
GND                      J9A3             50       SCONN60_C21100002_SMLF-CONN,C2A
GND                      J9A3             59       SCONN60_C21100002_SMLF-CONN,C2A
GND                      J9B1             4        CONN9_H51826001_PIP2-CONN,H518A
GND                      J9B1             7        CONN9_H51826001_PIP2-CONN,H518A
GND                      J9B1             MH1      CONN9_H51826001_PIP2-CONN,H518A
GND                      J9B1             MH2      CONN9_H51826001_PIP2-CONN,H518A
GND                      J9B1             MH3      CONN9_H51826001_PIP2-CONN,H518A
GND                      J9B1             MH4      CONN9_H51826001_PIP2-CONN,H518A
GND                      J9B2             2        CONN3_C95678002_PIP-CONN,C9567A
GND                      J9B3             8        SCONN120_A28699018_SM-SCONN,A2A
GND                      J9B3             9        SCONN120_A28699018_SM-SCONN,A2A
GND                      J9B3             10       SCONN120_A28699018_SM-SCONN,A2A
GND                      J9B3             11       SCONN120_A28699018_SM-SCONN,A2A
GND                      J9B3             14       SCONN120_A28699018_SM-SCONN,A2A
GND                      J9B3             15       SCONN120_A28699018_SM-SCONN,A2A
GND                      J9B3             16       SCONN120_A28699018_SM-SCONN,A2A
GND                      J9B3             17       SCONN120_A28699018_SM-SCONN,A2A
GND                      J9B3             26       SCONN120_A28699018_SM-SCONN,A2A
GND                      J9B3             38       SCONN120_A28699018_SM-SCONN,A2A
GND                      J9B3             39       SCONN120_A28699018_SM-SCONN,A2A
GND                      J9B3             41       SCONN120_A28699018_SM-SCONN,A2A
GND                      J9B3             44       SCONN120_A28699018_SM-SCONN,A2A
GND                      J9B3             46       SCONN120_A28699018_SM-SCONN,A2A
GND                      J9B3             47       SCONN120_A28699018_SM-SCONN,A2A
GND                      J9B3             49       SCONN120_A28699018_SM-SCONN,A2A
GND                      J9B3             52       SCONN120_A28699018_SM-SCONN,A2A
GND                      J9B3             54       SCONN120_A28699018_SM-SCONN,A2A
GND                      J9B3             55       SCONN120_A28699018_SM-SCONN,A2A
GND                      J9B3             57       SCONN120_A28699018_SM-SCONN,A2A
GND                      J9B3             60       SCONN120_A28699018_SM-SCONN,A2A
GND                      J9B3             62       SCONN120_A28699018_SM-SCONN,A2A
GND                      J9B3             63       SCONN120_A28699018_SM-SCONN,A2A
GND                      J9B3             65       SCONN120_A28699018_SM-SCONN,A2A
GND                      J9B3             68       SCONN120_A28699018_SM-SCONN,A2A
GND                      J9B3             70       SCONN120_A28699018_SM-SCONN,A2A
GND                      J9B3             71       SCONN120_A28699018_SM-SCONN,A2A
GND                      J9B3             73       SCONN120_A28699018_SM-SCONN,A2A
GND                      J9B3             76       SCONN120_A28699018_SM-SCONN,A2A
GND                      J9B3             78       SCONN120_A28699018_SM-SCONN,A2A
GND                      J9B3             79       SCONN120_A28699018_SM-SCONN,A2A
GND                      J9B3             81       SCONN120_A28699018_SM-SCONN,A2A
GND                      J9B3             84       SCONN120_A28699018_SM-SCONN,A2A
GND                      J9B3             86       SCONN120_A28699018_SM-SCONN,A2A
GND                      J9B3             87       SCONN120_A28699018_SM-SCONN,A2A
GND                      J9B3             89       SCONN120_A28699018_SM-SCONN,A2A
GND                      J9B3             92       SCONN120_A28699018_SM-SCONN,A2A
GND                      J9B3             94       SCONN120_A28699018_SM-SCONN,A2A
GND                      J9B3             95       SCONN120_A28699018_SM-SCONN,A2A
GND                      J9B3             97       SCONN120_A28699018_SM-SCONN,A2A
GND                      J9B3             100      SCONN120_A28699018_SM-SCONN,A2A
GND                      J9B3             102      SCONN120_A28699018_SM-SCONN,A2A
GND                      J9B3             103      SCONN120_A28699018_SM-SCONN,A2A
GND                      J9B3             105      SCONN120_A28699018_SM-SCONN,A2A
GND                      J9B3             108      SCONN120_A28699018_SM-SCONN,A2A
GND                      J9B3             110      SCONN120_A28699018_SM-SCONN,A2A
GND                      J9B3             111      SCONN120_A28699018_SM-SCONN,A2A
GND                      J9B3             113      SCONN120_A28699018_SM-SCONN,A2A
GND                      J9B3             116      SCONN120_A28699018_SM-SCONN,A2A
GND                      J9B3             118      SCONN120_A28699018_SM-SCONN,A2A
GND                      J9B3             119      SCONN120_A28699018_SM-SCONN,A2A
GND                      J9B4             2        SCONN10_C12536004_SMLF-CONN,C1A
GND                      J9B4             10       SCONN10_C12536004_SMLF-CONN,C1A
GND                      J9L1             2        SCONN288_H44441003_PIP-SCONN,HA
GND                      J9L1             4        SCONN288_H44441003_PIP-SCONN,HA
GND                      J9L1             6        SCONN288_H44441003_PIP-SCONN,HA
GND                      J9L1             9        SCONN288_H44441003_PIP-SCONN,HA
GND                      J9L1             11       SCONN288_H44441003_PIP-SCONN,HA
GND                      J9L1             13       SCONN288_H44441003_PIP-SCONN,HA
GND                      J9L1             15       SCONN288_H44441003_PIP-SCONN,HA
GND                      J9L1             17       SCONN288_H44441003_PIP-SCONN,HA
GND                      J9L1             20       SCONN288_H44441003_PIP-SCONN,HA
GND                      J9L1             22       SCONN288_H44441003_PIP-SCONN,HA
GND                      J9L1             24       SCONN288_H44441003_PIP-SCONN,HA
GND                      J9L1             26       SCONN288_H44441003_PIP-SCONN,HA
GND                      J9L1             28       SCONN288_H44441003_PIP-SCONN,HA
GND                      J9L1             31       SCONN288_H44441003_PIP-SCONN,HA
GND                      J9L1             33       SCONN288_H44441003_PIP-SCONN,HA
GND                      J9L1             35       SCONN288_H44441003_PIP-SCONN,HA
GND                      J9L1             37       SCONN288_H44441003_PIP-SCONN,HA
GND                      J9L1             39       SCONN288_H44441003_PIP-SCONN,HA
GND                      J9L1             42       SCONN288_H44441003_PIP-SCONN,HA
GND                      J9L1             44       SCONN288_H44441003_PIP-SCONN,HA
GND                      J9L1             46       SCONN288_H44441003_PIP-SCONN,HA
GND                      J9L1             48       SCONN288_H44441003_PIP-SCONN,HA
GND                      J9L1             50       SCONN288_H44441003_PIP-SCONN,HA
GND                      J9L1             53       SCONN288_H44441003_PIP-SCONN,HA
GND                      J9L1             55       SCONN288_H44441003_PIP-SCONN,HA
GND                      J9L1             57       SCONN288_H44441003_PIP-SCONN,HA
GND                      J9L1             94       SCONN288_H44441003_PIP-SCONN,HA
GND                      J9L1             96       SCONN288_H44441003_PIP-SCONN,HA
GND                      J9L1             98       SCONN288_H44441003_PIP-SCONN,HA
GND                      J9L1             101      SCONN288_H44441003_PIP-SCONN,HA
GND                      J9L1             103      SCONN288_H44441003_PIP-SCONN,HA
GND                      J9L1             105      SCONN288_H44441003_PIP-SCONN,HA
GND                      J9L1             107      SCONN288_H44441003_PIP-SCONN,HA
GND                      J9L1             109      SCONN288_H44441003_PIP-SCONN,HA
GND                      J9L1             112      SCONN288_H44441003_PIP-SCONN,HA
GND                      J9L1             114      SCONN288_H44441003_PIP-SCONN,HA
GND                      J9L1             116      SCONN288_H44441003_PIP-SCONN,HA
GND                      J9L1             118      SCONN288_H44441003_PIP-SCONN,HA
GND                      J9L1             120      SCONN288_H44441003_PIP-SCONN,HA
GND                      J9L1             123      SCONN288_H44441003_PIP-SCONN,HA
GND                      J9L1             125      SCONN288_H44441003_PIP-SCONN,HA
GND                      J9L1             127      SCONN288_H44441003_PIP-SCONN,HA
GND                      J9L1             129      SCONN288_H44441003_PIP-SCONN,HA
GND                      J9L1             131      SCONN288_H44441003_PIP-SCONN,HA
GND                      J9L1             134      SCONN288_H44441003_PIP-SCONN,HA
GND                      J9L1             136      SCONN288_H44441003_PIP-SCONN,HA
GND                      J9L1             138      SCONN288_H44441003_PIP-SCONN,HA
GND                      J9L1             140      SCONN288_H44441003_PIP-SCONN,HA
GND                      J9L1             147      SCONN288_H44441003_PIP-SCONN,HA
GND                      J9L1             149      SCONN288_H44441003_PIP-SCONN,HA
GND                      J9L1             151      SCONN288_H44441003_PIP-SCONN,HA
GND                      J9L1             154      SCONN288_H44441003_PIP-SCONN,HA
GND                      J9L1             156      SCONN288_H44441003_PIP-SCONN,HA
GND                      J9L1             158      SCONN288_H44441003_PIP-SCONN,HA
GND                      J9L1             160      SCONN288_H44441003_PIP-SCONN,HA
GND                      J9L1             162      SCONN288_H44441003_PIP-SCONN,HA
GND                      J9L1             165      SCONN288_H44441003_PIP-SCONN,HA
GND                      J9L1             167      SCONN288_H44441003_PIP-SCONN,HA
GND                      J9L1             169      SCONN288_H44441003_PIP-SCONN,HA
GND                      J9L1             171      SCONN288_H44441003_PIP-SCONN,HA
GND                      J9L1             173      SCONN288_H44441003_PIP-SCONN,HA
GND                      J9L1             176      SCONN288_H44441003_PIP-SCONN,HA
GND                      J9L1             178      SCONN288_H44441003_PIP-SCONN,HA
GND                      J9L1             180      SCONN288_H44441003_PIP-SCONN,HA
GND                      J9L1             182      SCONN288_H44441003_PIP-SCONN,HA
GND                      J9L1             184      SCONN288_H44441003_PIP-SCONN,HA
GND                      J9L1             187      SCONN288_H44441003_PIP-SCONN,HA
GND                      J9L1             189      SCONN288_H44441003_PIP-SCONN,HA
GND                      J9L1             191      SCONN288_H44441003_PIP-SCONN,HA
GND                      J9L1             193      SCONN288_H44441003_PIP-SCONN,HA
GND                      J9L1             195      SCONN288_H44441003_PIP-SCONN,HA
GND                      J9L1             198      SCONN288_H44441003_PIP-SCONN,HA
GND                      J9L1             200      SCONN288_H44441003_PIP-SCONN,HA
GND                      J9L1             202      SCONN288_H44441003_PIP-SCONN,HA
GND                      J9L1             239      SCONN288_H44441003_PIP-SCONN,HA
GND                      J9L1             241      SCONN288_H44441003_PIP-SCONN,HA
GND                      J9L1             243      SCONN288_H44441003_PIP-SCONN,HA
GND                      J9L1             246      SCONN288_H44441003_PIP-SCONN,HA
GND                      J9L1             248      SCONN288_H44441003_PIP-SCONN,HA
GND                      J9L1             250      SCONN288_H44441003_PIP-SCONN,HA
GND                      J9L1             252      SCONN288_H44441003_PIP-SCONN,HA
GND                      J9L1             254      SCONN288_H44441003_PIP-SCONN,HA
GND                      J9L1             257      SCONN288_H44441003_PIP-SCONN,HA
GND                      J9L1             259      SCONN288_H44441003_PIP-SCONN,HA
GND                      J9L1             261      SCONN288_H44441003_PIP-SCONN,HA
GND                      J9L1             263      SCONN288_H44441003_PIP-SCONN,HA
GND                      J9L1             265      SCONN288_H44441003_PIP-SCONN,HA
GND                      J9L1             268      SCONN288_H44441003_PIP-SCONN,HA
GND                      J9L1             270      SCONN288_H44441003_PIP-SCONN,HA
GND                      J9L1             272      SCONN288_H44441003_PIP-SCONN,HA
GND                      J9L1             274      SCONN288_H44441003_PIP-SCONN,HA
GND                      J9L1             276      SCONN288_H44441003_PIP-SCONN,HA
GND                      J9L1             279      SCONN288_H44441003_PIP-SCONN,HA
GND                      J9L1             281      SCONN288_H44441003_PIP-SCONN,HA
GND                      J9L1             283      SCONN288_H44441003_PIP-SCONN,HA
GND                      J9L2             2        SCONN288_H44441003_PIP-SCONN,HA
GND                      J9L2             4        SCONN288_H44441003_PIP-SCONN,HA
GND                      J9L2             6        SCONN288_H44441003_PIP-SCONN,HA
GND                      J9L2             9        SCONN288_H44441003_PIP-SCONN,HA
GND                      J9L2             11       SCONN288_H44441003_PIP-SCONN,HA
GND                      J9L2             13       SCONN288_H44441003_PIP-SCONN,HA
GND                      J9L2             15       SCONN288_H44441003_PIP-SCONN,HA
GND                      J9L2             17       SCONN288_H44441003_PIP-SCONN,HA
GND                      J9L2             20       SCONN288_H44441003_PIP-SCONN,HA
GND                      J9L2             22       SCONN288_H44441003_PIP-SCONN,HA
GND                      J9L2             24       SCONN288_H44441003_PIP-SCONN,HA
GND                      J9L2             26       SCONN288_H44441003_PIP-SCONN,HA
GND                      J9L2             28       SCONN288_H44441003_PIP-SCONN,HA
GND                      J9L2             31       SCONN288_H44441003_PIP-SCONN,HA
GND                      J9L2             33       SCONN288_H44441003_PIP-SCONN,HA
GND                      J9L2             35       SCONN288_H44441003_PIP-SCONN,HA
GND                      J9L2             37       SCONN288_H44441003_PIP-SCONN,HA
GND                      J9L2             39       SCONN288_H44441003_PIP-SCONN,HA
GND                      J9L2             42       SCONN288_H44441003_PIP-SCONN,HA
GND                      J9L2             44       SCONN288_H44441003_PIP-SCONN,HA
GND                      J9L2             46       SCONN288_H44441003_PIP-SCONN,HA
GND                      J9L2             48       SCONN288_H44441003_PIP-SCONN,HA
GND                      J9L2             50       SCONN288_H44441003_PIP-SCONN,HA
GND                      J9L2             53       SCONN288_H44441003_PIP-SCONN,HA
GND                      J9L2             55       SCONN288_H44441003_PIP-SCONN,HA
GND                      J9L2             57       SCONN288_H44441003_PIP-SCONN,HA
GND                      J9L2             94       SCONN288_H44441003_PIP-SCONN,HA
GND                      J9L2             96       SCONN288_H44441003_PIP-SCONN,HA
GND                      J9L2             98       SCONN288_H44441003_PIP-SCONN,HA
GND                      J9L2             101      SCONN288_H44441003_PIP-SCONN,HA
GND                      J9L2             103      SCONN288_H44441003_PIP-SCONN,HA
GND                      J9L2             105      SCONN288_H44441003_PIP-SCONN,HA
GND                      J9L2             107      SCONN288_H44441003_PIP-SCONN,HA
GND                      J9L2             109      SCONN288_H44441003_PIP-SCONN,HA
GND                      J9L2             112      SCONN288_H44441003_PIP-SCONN,HA
GND                      J9L2             114      SCONN288_H44441003_PIP-SCONN,HA
GND                      J9L2             116      SCONN288_H44441003_PIP-SCONN,HA
GND                      J9L2             118      SCONN288_H44441003_PIP-SCONN,HA
GND                      J9L2             120      SCONN288_H44441003_PIP-SCONN,HA
GND                      J9L2             123      SCONN288_H44441003_PIP-SCONN,HA
GND                      J9L2             125      SCONN288_H44441003_PIP-SCONN,HA
GND                      J9L2             127      SCONN288_H44441003_PIP-SCONN,HA
GND                      J9L2             129      SCONN288_H44441003_PIP-SCONN,HA
GND                      J9L2             131      SCONN288_H44441003_PIP-SCONN,HA
GND                      J9L2             134      SCONN288_H44441003_PIP-SCONN,HA
GND                      J9L2             136      SCONN288_H44441003_PIP-SCONN,HA
GND                      J9L2             138      SCONN288_H44441003_PIP-SCONN,HA
GND                      J9L2             147      SCONN288_H44441003_PIP-SCONN,HA
GND                      J9L2             149      SCONN288_H44441003_PIP-SCONN,HA
GND                      J9L2             151      SCONN288_H44441003_PIP-SCONN,HA
GND                      J9L2             154      SCONN288_H44441003_PIP-SCONN,HA
GND                      J9L2             156      SCONN288_H44441003_PIP-SCONN,HA
GND                      J9L2             158      SCONN288_H44441003_PIP-SCONN,HA
GND                      J9L2             160      SCONN288_H44441003_PIP-SCONN,HA
GND                      J9L2             162      SCONN288_H44441003_PIP-SCONN,HA
GND                      J9L2             165      SCONN288_H44441003_PIP-SCONN,HA
GND                      J9L2             167      SCONN288_H44441003_PIP-SCONN,HA
GND                      J9L2             169      SCONN288_H44441003_PIP-SCONN,HA
GND                      J9L2             171      SCONN288_H44441003_PIP-SCONN,HA
GND                      J9L2             173      SCONN288_H44441003_PIP-SCONN,HA
GND                      J9L2             176      SCONN288_H44441003_PIP-SCONN,HA
GND                      J9L2             178      SCONN288_H44441003_PIP-SCONN,HA
GND                      J9L2             180      SCONN288_H44441003_PIP-SCONN,HA
GND                      J9L2             182      SCONN288_H44441003_PIP-SCONN,HA
GND                      J9L2             184      SCONN288_H44441003_PIP-SCONN,HA
GND                      J9L2             187      SCONN288_H44441003_PIP-SCONN,HA
GND                      J9L2             189      SCONN288_H44441003_PIP-SCONN,HA
GND                      J9L2             191      SCONN288_H44441003_PIP-SCONN,HA
GND                      J9L2             193      SCONN288_H44441003_PIP-SCONN,HA
GND                      J9L2             195      SCONN288_H44441003_PIP-SCONN,HA
GND                      J9L2             198      SCONN288_H44441003_PIP-SCONN,HA
GND                      J9L2             200      SCONN288_H44441003_PIP-SCONN,HA
GND                      J9L2             202      SCONN288_H44441003_PIP-SCONN,HA
GND                      J9L2             238      SCONN288_H44441003_PIP-SCONN,HA
GND                      J9L2             239      SCONN288_H44441003_PIP-SCONN,HA
GND                      J9L2             241      SCONN288_H44441003_PIP-SCONN,HA
GND                      J9L2             243      SCONN288_H44441003_PIP-SCONN,HA
GND                      J9L2             246      SCONN288_H44441003_PIP-SCONN,HA
GND                      J9L2             248      SCONN288_H44441003_PIP-SCONN,HA
GND                      J9L2             250      SCONN288_H44441003_PIP-SCONN,HA
GND                      J9L2             252      SCONN288_H44441003_PIP-SCONN,HA
GND                      J9L2             254      SCONN288_H44441003_PIP-SCONN,HA
GND                      J9L2             257      SCONN288_H44441003_PIP-SCONN,HA
GND                      J9L2             259      SCONN288_H44441003_PIP-SCONN,HA
GND                      J9L2             261      SCONN288_H44441003_PIP-SCONN,HA
GND                      J9L2             263      SCONN288_H44441003_PIP-SCONN,HA
GND                      J9L2             265      SCONN288_H44441003_PIP-SCONN,HA
GND                      J9L2             268      SCONN288_H44441003_PIP-SCONN,HA
GND                      J9L2             270      SCONN288_H44441003_PIP-SCONN,HA
GND                      J9L2             272      SCONN288_H44441003_PIP-SCONN,HA
GND                      J9L2             274      SCONN288_H44441003_PIP-SCONN,HA
GND                      J9L2             276      SCONN288_H44441003_PIP-SCONN,HA
GND                      J9L2             279      SCONN288_H44441003_PIP-SCONN,HA
GND                      J9L2             281      SCONN288_H44441003_PIP-SCONN,HA
GND                      J9L2             283      SCONN288_H44441003_PIP-SCONN,HA
GND                      J9M1             2        SCONN288_H44441003_PIP-SCONN,HA
GND                      J9M1             4        SCONN288_H44441003_PIP-SCONN,HA
GND                      J9M1             6        SCONN288_H44441003_PIP-SCONN,HA
GND                      J9M1             9        SCONN288_H44441003_PIP-SCONN,HA
GND                      J9M1             11       SCONN288_H44441003_PIP-SCONN,HA
GND                      J9M1             13       SCONN288_H44441003_PIP-SCONN,HA
GND                      J9M1             15       SCONN288_H44441003_PIP-SCONN,HA
GND                      J9M1             17       SCONN288_H44441003_PIP-SCONN,HA
GND                      J9M1             20       SCONN288_H44441003_PIP-SCONN,HA
GND                      J9M1             22       SCONN288_H44441003_PIP-SCONN,HA
GND                      J9M1             24       SCONN288_H44441003_PIP-SCONN,HA
GND                      J9M1             26       SCONN288_H44441003_PIP-SCONN,HA
GND                      J9M1             28       SCONN288_H44441003_PIP-SCONN,HA
GND                      J9M1             31       SCONN288_H44441003_PIP-SCONN,HA
GND                      J9M1             33       SCONN288_H44441003_PIP-SCONN,HA
GND                      J9M1             35       SCONN288_H44441003_PIP-SCONN,HA
GND                      J9M1             37       SCONN288_H44441003_PIP-SCONN,HA
GND                      J9M1             39       SCONN288_H44441003_PIP-SCONN,HA
GND                      J9M1             42       SCONN288_H44441003_PIP-SCONN,HA
GND                      J9M1             44       SCONN288_H44441003_PIP-SCONN,HA
GND                      J9M1             46       SCONN288_H44441003_PIP-SCONN,HA
GND                      J9M1             48       SCONN288_H44441003_PIP-SCONN,HA
GND                      J9M1             50       SCONN288_H44441003_PIP-SCONN,HA
GND                      J9M1             53       SCONN288_H44441003_PIP-SCONN,HA
GND                      J9M1             55       SCONN288_H44441003_PIP-SCONN,HA
GND                      J9M1             57       SCONN288_H44441003_PIP-SCONN,HA
GND                      J9M1             94       SCONN288_H44441003_PIP-SCONN,HA
GND                      J9M1             96       SCONN288_H44441003_PIP-SCONN,HA
GND                      J9M1             98       SCONN288_H44441003_PIP-SCONN,HA
GND                      J9M1             101      SCONN288_H44441003_PIP-SCONN,HA
GND                      J9M1             103      SCONN288_H44441003_PIP-SCONN,HA
GND                      J9M1             105      SCONN288_H44441003_PIP-SCONN,HA
GND                      J9M1             107      SCONN288_H44441003_PIP-SCONN,HA
GND                      J9M1             109      SCONN288_H44441003_PIP-SCONN,HA
GND                      J9M1             112      SCONN288_H44441003_PIP-SCONN,HA
GND                      J9M1             114      SCONN288_H44441003_PIP-SCONN,HA
GND                      J9M1             116      SCONN288_H44441003_PIP-SCONN,HA
GND                      J9M1             118      SCONN288_H44441003_PIP-SCONN,HA
GND                      J9M1             120      SCONN288_H44441003_PIP-SCONN,HA
GND                      J9M1             123      SCONN288_H44441003_PIP-SCONN,HA
GND                      J9M1             125      SCONN288_H44441003_PIP-SCONN,HA
GND                      J9M1             127      SCONN288_H44441003_PIP-SCONN,HA
GND                      J9M1             129      SCONN288_H44441003_PIP-SCONN,HA
GND                      J9M1             131      SCONN288_H44441003_PIP-SCONN,HA
GND                      J9M1             134      SCONN288_H44441003_PIP-SCONN,HA
GND                      J9M1             136      SCONN288_H44441003_PIP-SCONN,HA
GND                      J9M1             138      SCONN288_H44441003_PIP-SCONN,HA
GND                      J9M1             140      SCONN288_H44441003_PIP-SCONN,HA
GND                      J9M1             147      SCONN288_H44441003_PIP-SCONN,HA
GND                      J9M1             149      SCONN288_H44441003_PIP-SCONN,HA
GND                      J9M1             151      SCONN288_H44441003_PIP-SCONN,HA
GND                      J9M1             154      SCONN288_H44441003_PIP-SCONN,HA
GND                      J9M1             156      SCONN288_H44441003_PIP-SCONN,HA
GND                      J9M1             158      SCONN288_H44441003_PIP-SCONN,HA
GND                      J9M1             160      SCONN288_H44441003_PIP-SCONN,HA
GND                      J9M1             162      SCONN288_H44441003_PIP-SCONN,HA
GND                      J9M1             165      SCONN288_H44441003_PIP-SCONN,HA
GND                      J9M1             167      SCONN288_H44441003_PIP-SCONN,HA
GND                      J9M1             169      SCONN288_H44441003_PIP-SCONN,HA
GND                      J9M1             171      SCONN288_H44441003_PIP-SCONN,HA
GND                      J9M1             173      SCONN288_H44441003_PIP-SCONN,HA
GND                      J9M1             176      SCONN288_H44441003_PIP-SCONN,HA
GND                      J9M1             178      SCONN288_H44441003_PIP-SCONN,HA
GND                      J9M1             180      SCONN288_H44441003_PIP-SCONN,HA
GND                      J9M1             182      SCONN288_H44441003_PIP-SCONN,HA
GND                      J9M1             184      SCONN288_H44441003_PIP-SCONN,HA
GND                      J9M1             187      SCONN288_H44441003_PIP-SCONN,HA
GND                      J9M1             189      SCONN288_H44441003_PIP-SCONN,HA
GND                      J9M1             191      SCONN288_H44441003_PIP-SCONN,HA
GND                      J9M1             193      SCONN288_H44441003_PIP-SCONN,HA
GND                      J9M1             195      SCONN288_H44441003_PIP-SCONN,HA
GND                      J9M1             198      SCONN288_H44441003_PIP-SCONN,HA
GND                      J9M1             200      SCONN288_H44441003_PIP-SCONN,HA
GND                      J9M1             202      SCONN288_H44441003_PIP-SCONN,HA
GND                      J9M1             238      SCONN288_H44441003_PIP-SCONN,HA
GND                      J9M1             239      SCONN288_H44441003_PIP-SCONN,HA
GND                      J9M1             241      SCONN288_H44441003_PIP-SCONN,HA
GND                      J9M1             243      SCONN288_H44441003_PIP-SCONN,HA
GND                      J9M1             246      SCONN288_H44441003_PIP-SCONN,HA
GND                      J9M1             248      SCONN288_H44441003_PIP-SCONN,HA
GND                      J9M1             250      SCONN288_H44441003_PIP-SCONN,HA
GND                      J9M1             252      SCONN288_H44441003_PIP-SCONN,HA
GND                      J9M1             254      SCONN288_H44441003_PIP-SCONN,HA
GND                      J9M1             257      SCONN288_H44441003_PIP-SCONN,HA
GND                      J9M1             259      SCONN288_H44441003_PIP-SCONN,HA
GND                      J9M1             261      SCONN288_H44441003_PIP-SCONN,HA
GND                      J9M1             263      SCONN288_H44441003_PIP-SCONN,HA
GND                      J9M1             265      SCONN288_H44441003_PIP-SCONN,HA
GND                      J9M1             268      SCONN288_H44441003_PIP-SCONN,HA
GND                      J9M1             270      SCONN288_H44441003_PIP-SCONN,HA
GND                      J9M1             272      SCONN288_H44441003_PIP-SCONN,HA
GND                      J9M1             274      SCONN288_H44441003_PIP-SCONN,HA
GND                      J9M1             276      SCONN288_H44441003_PIP-SCONN,HA
GND                      J9M1             279      SCONN288_H44441003_PIP-SCONN,HA
GND                      J9M1             281      SCONN288_H44441003_PIP-SCONN,HA
GND                      J9M1             283      SCONN288_H44441003_PIP-SCONN,HA
GND                      J9T1             2        SCONN288_H44441003_PIP-SCONN,HA
GND                      J9T1             4        SCONN288_H44441003_PIP-SCONN,HA
GND                      J9T1             6        SCONN288_H44441003_PIP-SCONN,HA
GND                      J9T1             9        SCONN288_H44441003_PIP-SCONN,HA
GND                      J9T1             11       SCONN288_H44441003_PIP-SCONN,HA
GND                      J9T1             13       SCONN288_H44441003_PIP-SCONN,HA
GND                      J9T1             15       SCONN288_H44441003_PIP-SCONN,HA
GND                      J9T1             17       SCONN288_H44441003_PIP-SCONN,HA
GND                      J9T1             20       SCONN288_H44441003_PIP-SCONN,HA
GND                      J9T1             22       SCONN288_H44441003_PIP-SCONN,HA
GND                      J9T1             24       SCONN288_H44441003_PIP-SCONN,HA
GND                      J9T1             26       SCONN288_H44441003_PIP-SCONN,HA
GND                      J9T1             28       SCONN288_H44441003_PIP-SCONN,HA
GND                      J9T1             31       SCONN288_H44441003_PIP-SCONN,HA
GND                      J9T1             33       SCONN288_H44441003_PIP-SCONN,HA
GND                      J9T1             35       SCONN288_H44441003_PIP-SCONN,HA
GND                      J9T1             37       SCONN288_H44441003_PIP-SCONN,HA
GND                      J9T1             39       SCONN288_H44441003_PIP-SCONN,HA
GND                      J9T1             42       SCONN288_H44441003_PIP-SCONN,HA
GND                      J9T1             44       SCONN288_H44441003_PIP-SCONN,HA
GND                      J9T1             46       SCONN288_H44441003_PIP-SCONN,HA
GND                      J9T1             48       SCONN288_H44441003_PIP-SCONN,HA
GND                      J9T1             50       SCONN288_H44441003_PIP-SCONN,HA
GND                      J9T1             53       SCONN288_H44441003_PIP-SCONN,HA
GND                      J9T1             55       SCONN288_H44441003_PIP-SCONN,HA
GND                      J9T1             57       SCONN288_H44441003_PIP-SCONN,HA
GND                      J9T1             94       SCONN288_H44441003_PIP-SCONN,HA
GND                      J9T1             96       SCONN288_H44441003_PIP-SCONN,HA
GND                      J9T1             98       SCONN288_H44441003_PIP-SCONN,HA
GND                      J9T1             101      SCONN288_H44441003_PIP-SCONN,HA
GND                      J9T1             103      SCONN288_H44441003_PIP-SCONN,HA
GND                      J9T1             105      SCONN288_H44441003_PIP-SCONN,HA
GND                      J9T1             107      SCONN288_H44441003_PIP-SCONN,HA
GND                      J9T1             109      SCONN288_H44441003_PIP-SCONN,HA
GND                      J9T1             112      SCONN288_H44441003_PIP-SCONN,HA
GND                      J9T1             114      SCONN288_H44441003_PIP-SCONN,HA
GND                      J9T1             116      SCONN288_H44441003_PIP-SCONN,HA
GND                      J9T1             118      SCONN288_H44441003_PIP-SCONN,HA
GND                      J9T1             120      SCONN288_H44441003_PIP-SCONN,HA
GND                      J9T1             123      SCONN288_H44441003_PIP-SCONN,HA
GND                      J9T1             125      SCONN288_H44441003_PIP-SCONN,HA
GND                      J9T1             127      SCONN288_H44441003_PIP-SCONN,HA
GND                      J9T1             129      SCONN288_H44441003_PIP-SCONN,HA
GND                      J9T1             131      SCONN288_H44441003_PIP-SCONN,HA
GND                      J9T1             134      SCONN288_H44441003_PIP-SCONN,HA
GND                      J9T1             136      SCONN288_H44441003_PIP-SCONN,HA
GND                      J9T1             138      SCONN288_H44441003_PIP-SCONN,HA
GND                      J9T1             140      SCONN288_H44441003_PIP-SCONN,HA
GND                      J9T1             147      SCONN288_H44441003_PIP-SCONN,HA
GND                      J9T1             149      SCONN288_H44441003_PIP-SCONN,HA
GND                      J9T1             151      SCONN288_H44441003_PIP-SCONN,HA
GND                      J9T1             154      SCONN288_H44441003_PIP-SCONN,HA
GND                      J9T1             156      SCONN288_H44441003_PIP-SCONN,HA
GND                      J9T1             158      SCONN288_H44441003_PIP-SCONN,HA
GND                      J9T1             160      SCONN288_H44441003_PIP-SCONN,HA
GND                      J9T1             162      SCONN288_H44441003_PIP-SCONN,HA
GND                      J9T1             165      SCONN288_H44441003_PIP-SCONN,HA
GND                      J9T1             167      SCONN288_H44441003_PIP-SCONN,HA
GND                      J9T1             169      SCONN288_H44441003_PIP-SCONN,HA
GND                      J9T1             171      SCONN288_H44441003_PIP-SCONN,HA
GND                      J9T1             173      SCONN288_H44441003_PIP-SCONN,HA
GND                      J9T1             176      SCONN288_H44441003_PIP-SCONN,HA
GND                      J9T1             178      SCONN288_H44441003_PIP-SCONN,HA
GND                      J9T1             180      SCONN288_H44441003_PIP-SCONN,HA
GND                      J9T1             182      SCONN288_H44441003_PIP-SCONN,HA
GND                      J9T1             184      SCONN288_H44441003_PIP-SCONN,HA
GND                      J9T1             187      SCONN288_H44441003_PIP-SCONN,HA
GND                      J9T1             189      SCONN288_H44441003_PIP-SCONN,HA
GND                      J9T1             191      SCONN288_H44441003_PIP-SCONN,HA
GND                      J9T1             193      SCONN288_H44441003_PIP-SCONN,HA
GND                      J9T1             195      SCONN288_H44441003_PIP-SCONN,HA
GND                      J9T1             198      SCONN288_H44441003_PIP-SCONN,HA
GND                      J9T1             200      SCONN288_H44441003_PIP-SCONN,HA
GND                      J9T1             202      SCONN288_H44441003_PIP-SCONN,HA
GND                      J9T1             238      SCONN288_H44441003_PIP-SCONN,HA
GND                      J9T1             239      SCONN288_H44441003_PIP-SCONN,HA
GND                      J9T1             241      SCONN288_H44441003_PIP-SCONN,HA
GND                      J9T1             243      SCONN288_H44441003_PIP-SCONN,HA
GND                      J9T1             246      SCONN288_H44441003_PIP-SCONN,HA
GND                      J9T1             248      SCONN288_H44441003_PIP-SCONN,HA
GND                      J9T1             250      SCONN288_H44441003_PIP-SCONN,HA
GND                      J9T1             252      SCONN288_H44441003_PIP-SCONN,HA
GND                      J9T1             254      SCONN288_H44441003_PIP-SCONN,HA
GND                      J9T1             257      SCONN288_H44441003_PIP-SCONN,HA
GND                      J9T1             259      SCONN288_H44441003_PIP-SCONN,HA
GND                      J9T1             261      SCONN288_H44441003_PIP-SCONN,HA
GND                      J9T1             263      SCONN288_H44441003_PIP-SCONN,HA
GND                      J9T1             265      SCONN288_H44441003_PIP-SCONN,HA
GND                      J9T1             268      SCONN288_H44441003_PIP-SCONN,HA
GND                      J9T1             270      SCONN288_H44441003_PIP-SCONN,HA
GND                      J9T1             272      SCONN288_H44441003_PIP-SCONN,HA
GND                      J9T1             274      SCONN288_H44441003_PIP-SCONN,HA
GND                      J9T1             276      SCONN288_H44441003_PIP-SCONN,HA
GND                      J9T1             279      SCONN288_H44441003_PIP-SCONN,HA
GND                      J9T1             281      SCONN288_H44441003_PIP-SCONN,HA
GND                      J9T1             283      SCONN288_H44441003_PIP-SCONN,HA
GND                      J9U1             2        SCONN288_H44441003_PIP-SCONN,HA
GND                      J9U1             4        SCONN288_H44441003_PIP-SCONN,HA
GND                      J9U1             6        SCONN288_H44441003_PIP-SCONN,HA
GND                      J9U1             9        SCONN288_H44441003_PIP-SCONN,HA
GND                      J9U1             11       SCONN288_H44441003_PIP-SCONN,HA
GND                      J9U1             13       SCONN288_H44441003_PIP-SCONN,HA
GND                      J9U1             15       SCONN288_H44441003_PIP-SCONN,HA
GND                      J9U1             17       SCONN288_H44441003_PIP-SCONN,HA
GND                      J9U1             20       SCONN288_H44441003_PIP-SCONN,HA
GND                      J9U1             22       SCONN288_H44441003_PIP-SCONN,HA
GND                      J9U1             24       SCONN288_H44441003_PIP-SCONN,HA
GND                      J9U1             26       SCONN288_H44441003_PIP-SCONN,HA
GND                      J9U1             28       SCONN288_H44441003_PIP-SCONN,HA
GND                      J9U1             31       SCONN288_H44441003_PIP-SCONN,HA
GND                      J9U1             33       SCONN288_H44441003_PIP-SCONN,HA
GND                      J9U1             35       SCONN288_H44441003_PIP-SCONN,HA
GND                      J9U1             37       SCONN288_H44441003_PIP-SCONN,HA
GND                      J9U1             39       SCONN288_H44441003_PIP-SCONN,HA
GND                      J9U1             42       SCONN288_H44441003_PIP-SCONN,HA
GND                      J9U1             44       SCONN288_H44441003_PIP-SCONN,HA
GND                      J9U1             46       SCONN288_H44441003_PIP-SCONN,HA
GND                      J9U1             48       SCONN288_H44441003_PIP-SCONN,HA
GND                      J9U1             50       SCONN288_H44441003_PIP-SCONN,HA
GND                      J9U1             53       SCONN288_H44441003_PIP-SCONN,HA
GND                      J9U1             55       SCONN288_H44441003_PIP-SCONN,HA
GND                      J9U1             57       SCONN288_H44441003_PIP-SCONN,HA
GND                      J9U1             94       SCONN288_H44441003_PIP-SCONN,HA
GND                      J9U1             96       SCONN288_H44441003_PIP-SCONN,HA
GND                      J9U1             98       SCONN288_H44441003_PIP-SCONN,HA
GND                      J9U1             101      SCONN288_H44441003_PIP-SCONN,HA
GND                      J9U1             103      SCONN288_H44441003_PIP-SCONN,HA
GND                      J9U1             105      SCONN288_H44441003_PIP-SCONN,HA
GND                      J9U1             107      SCONN288_H44441003_PIP-SCONN,HA
GND                      J9U1             109      SCONN288_H44441003_PIP-SCONN,HA
GND                      J9U1             112      SCONN288_H44441003_PIP-SCONN,HA
GND                      J9U1             114      SCONN288_H44441003_PIP-SCONN,HA
GND                      J9U1             116      SCONN288_H44441003_PIP-SCONN,HA
GND                      J9U1             118      SCONN288_H44441003_PIP-SCONN,HA
GND                      J9U1             120      SCONN288_H44441003_PIP-SCONN,HA
GND                      J9U1             123      SCONN288_H44441003_PIP-SCONN,HA
GND                      J9U1             125      SCONN288_H44441003_PIP-SCONN,HA
GND                      J9U1             127      SCONN288_H44441003_PIP-SCONN,HA
GND                      J9U1             129      SCONN288_H44441003_PIP-SCONN,HA
GND                      J9U1             131      SCONN288_H44441003_PIP-SCONN,HA
GND                      J9U1             134      SCONN288_H44441003_PIP-SCONN,HA
GND                      J9U1             136      SCONN288_H44441003_PIP-SCONN,HA
GND                      J9U1             138      SCONN288_H44441003_PIP-SCONN,HA
GND                      J9U1             147      SCONN288_H44441003_PIP-SCONN,HA
GND                      J9U1             149      SCONN288_H44441003_PIP-SCONN,HA
GND                      J9U1             151      SCONN288_H44441003_PIP-SCONN,HA
GND                      J9U1             154      SCONN288_H44441003_PIP-SCONN,HA
GND                      J9U1             156      SCONN288_H44441003_PIP-SCONN,HA
GND                      J9U1             158      SCONN288_H44441003_PIP-SCONN,HA
GND                      J9U1             160      SCONN288_H44441003_PIP-SCONN,HA
GND                      J9U1             162      SCONN288_H44441003_PIP-SCONN,HA
GND                      J9U1             165      SCONN288_H44441003_PIP-SCONN,HA
GND                      J9U1             167      SCONN288_H44441003_PIP-SCONN,HA
GND                      J9U1             169      SCONN288_H44441003_PIP-SCONN,HA
GND                      J9U1             171      SCONN288_H44441003_PIP-SCONN,HA
GND                      J9U1             173      SCONN288_H44441003_PIP-SCONN,HA
GND                      J9U1             176      SCONN288_H44441003_PIP-SCONN,HA
GND                      J9U1             178      SCONN288_H44441003_PIP-SCONN,HA
GND                      J9U1             180      SCONN288_H44441003_PIP-SCONN,HA
GND                      J9U1             182      SCONN288_H44441003_PIP-SCONN,HA
GND                      J9U1             184      SCONN288_H44441003_PIP-SCONN,HA
GND                      J9U1             187      SCONN288_H44441003_PIP-SCONN,HA
GND                      J9U1             189      SCONN288_H44441003_PIP-SCONN,HA
GND                      J9U1             191      SCONN288_H44441003_PIP-SCONN,HA
GND                      J9U1             193      SCONN288_H44441003_PIP-SCONN,HA
GND                      J9U1             195      SCONN288_H44441003_PIP-SCONN,HA
GND                      J9U1             198      SCONN288_H44441003_PIP-SCONN,HA
GND                      J9U1             200      SCONN288_H44441003_PIP-SCONN,HA
GND                      J9U1             202      SCONN288_H44441003_PIP-SCONN,HA
GND                      J9U1             238      SCONN288_H44441003_PIP-SCONN,HA
GND                      J9U1             239      SCONN288_H44441003_PIP-SCONN,HA
GND                      J9U1             241      SCONN288_H44441003_PIP-SCONN,HA
GND                      J9U1             243      SCONN288_H44441003_PIP-SCONN,HA
GND                      J9U1             246      SCONN288_H44441003_PIP-SCONN,HA
GND                      J9U1             248      SCONN288_H44441003_PIP-SCONN,HA
GND                      J9U1             250      SCONN288_H44441003_PIP-SCONN,HA
GND                      J9U1             252      SCONN288_H44441003_PIP-SCONN,HA
GND                      J9U1             254      SCONN288_H44441003_PIP-SCONN,HA
GND                      J9U1             257      SCONN288_H44441003_PIP-SCONN,HA
GND                      J9U1             259      SCONN288_H44441003_PIP-SCONN,HA
GND                      J9U1             261      SCONN288_H44441003_PIP-SCONN,HA
GND                      J9U1             263      SCONN288_H44441003_PIP-SCONN,HA
GND                      J9U1             265      SCONN288_H44441003_PIP-SCONN,HA
GND                      J9U1             268      SCONN288_H44441003_PIP-SCONN,HA
GND                      J9U1             270      SCONN288_H44441003_PIP-SCONN,HA
GND                      J9U1             272      SCONN288_H44441003_PIP-SCONN,HA
GND                      J9U1             274      SCONN288_H44441003_PIP-SCONN,HA
GND                      J9U1             276      SCONN288_H44441003_PIP-SCONN,HA
GND                      J9U1             279      SCONN288_H44441003_PIP-SCONN,HA
GND                      J9U1             281      SCONN288_H44441003_PIP-SCONN,HA
GND                      J9U1             283      SCONN288_H44441003_PIP-SCONN,HA
GND                      J9U2             2        SCONN288_H44441003_PIP-SCONN,HA
GND                      J9U2             4        SCONN288_H44441003_PIP-SCONN,HA
GND                      J9U2             6        SCONN288_H44441003_PIP-SCONN,HA
GND                      J9U2             9        SCONN288_H44441003_PIP-SCONN,HA
GND                      J9U2             11       SCONN288_H44441003_PIP-SCONN,HA
GND                      J9U2             13       SCONN288_H44441003_PIP-SCONN,HA
GND                      J9U2             15       SCONN288_H44441003_PIP-SCONN,HA
GND                      J9U2             17       SCONN288_H44441003_PIP-SCONN,HA
GND                      J9U2             20       SCONN288_H44441003_PIP-SCONN,HA
GND                      J9U2             22       SCONN288_H44441003_PIP-SCONN,HA
GND                      J9U2             24       SCONN288_H44441003_PIP-SCONN,HA
GND                      J9U2             26       SCONN288_H44441003_PIP-SCONN,HA
GND                      J9U2             28       SCONN288_H44441003_PIP-SCONN,HA
GND                      J9U2             31       SCONN288_H44441003_PIP-SCONN,HA
GND                      J9U2             33       SCONN288_H44441003_PIP-SCONN,HA
GND                      J9U2             35       SCONN288_H44441003_PIP-SCONN,HA
GND                      J9U2             37       SCONN288_H44441003_PIP-SCONN,HA
GND                      J9U2             39       SCONN288_H44441003_PIP-SCONN,HA
GND                      J9U2             42       SCONN288_H44441003_PIP-SCONN,HA
GND                      J9U2             44       SCONN288_H44441003_PIP-SCONN,HA
GND                      J9U2             46       SCONN288_H44441003_PIP-SCONN,HA
GND                      J9U2             48       SCONN288_H44441003_PIP-SCONN,HA
GND                      J9U2             50       SCONN288_H44441003_PIP-SCONN,HA
GND                      J9U2             53       SCONN288_H44441003_PIP-SCONN,HA
GND                      J9U2             55       SCONN288_H44441003_PIP-SCONN,HA
GND                      J9U2             57       SCONN288_H44441003_PIP-SCONN,HA
GND                      J9U2             94       SCONN288_H44441003_PIP-SCONN,HA
GND                      J9U2             96       SCONN288_H44441003_PIP-SCONN,HA
GND                      J9U2             98       SCONN288_H44441003_PIP-SCONN,HA
GND                      J9U2             101      SCONN288_H44441003_PIP-SCONN,HA
GND                      J9U2             103      SCONN288_H44441003_PIP-SCONN,HA
GND                      J9U2             105      SCONN288_H44441003_PIP-SCONN,HA
GND                      J9U2             107      SCONN288_H44441003_PIP-SCONN,HA
GND                      J9U2             109      SCONN288_H44441003_PIP-SCONN,HA
GND                      J9U2             112      SCONN288_H44441003_PIP-SCONN,HA
GND                      J9U2             114      SCONN288_H44441003_PIP-SCONN,HA
GND                      J9U2             116      SCONN288_H44441003_PIP-SCONN,HA
GND                      J9U2             118      SCONN288_H44441003_PIP-SCONN,HA
GND                      J9U2             120      SCONN288_H44441003_PIP-SCONN,HA
GND                      J9U2             123      SCONN288_H44441003_PIP-SCONN,HA
GND                      J9U2             125      SCONN288_H44441003_PIP-SCONN,HA
GND                      J9U2             127      SCONN288_H44441003_PIP-SCONN,HA
GND                      J9U2             129      SCONN288_H44441003_PIP-SCONN,HA
GND                      J9U2             131      SCONN288_H44441003_PIP-SCONN,HA
GND                      J9U2             134      SCONN288_H44441003_PIP-SCONN,HA
GND                      J9U2             136      SCONN288_H44441003_PIP-SCONN,HA
GND                      J9U2             138      SCONN288_H44441003_PIP-SCONN,HA
GND                      J9U2             140      SCONN288_H44441003_PIP-SCONN,HA
GND                      J9U2             147      SCONN288_H44441003_PIP-SCONN,HA
GND                      J9U2             149      SCONN288_H44441003_PIP-SCONN,HA
GND                      J9U2             151      SCONN288_H44441003_PIP-SCONN,HA
GND                      J9U2             154      SCONN288_H44441003_PIP-SCONN,HA
GND                      J9U2             156      SCONN288_H44441003_PIP-SCONN,HA
GND                      J9U2             158      SCONN288_H44441003_PIP-SCONN,HA
GND                      J9U2             160      SCONN288_H44441003_PIP-SCONN,HA
GND                      J9U2             162      SCONN288_H44441003_PIP-SCONN,HA
GND                      J9U2             165      SCONN288_H44441003_PIP-SCONN,HA
GND                      J9U2             167      SCONN288_H44441003_PIP-SCONN,HA
GND                      J9U2             169      SCONN288_H44441003_PIP-SCONN,HA
GND                      J9U2             171      SCONN288_H44441003_PIP-SCONN,HA
GND                      J9U2             173      SCONN288_H44441003_PIP-SCONN,HA
GND                      J9U2             176      SCONN288_H44441003_PIP-SCONN,HA
GND                      J9U2             178      SCONN288_H44441003_PIP-SCONN,HA
GND                      J9U2             180      SCONN288_H44441003_PIP-SCONN,HA
GND                      J9U2             182      SCONN288_H44441003_PIP-SCONN,HA
GND                      J9U2             184      SCONN288_H44441003_PIP-SCONN,HA
GND                      J9U2             187      SCONN288_H44441003_PIP-SCONN,HA
GND                      J9U2             189      SCONN288_H44441003_PIP-SCONN,HA
GND                      J9U2             191      SCONN288_H44441003_PIP-SCONN,HA
GND                      J9U2             193      SCONN288_H44441003_PIP-SCONN,HA
GND                      J9U2             195      SCONN288_H44441003_PIP-SCONN,HA
GND                      J9U2             198      SCONN288_H44441003_PIP-SCONN,HA
GND                      J9U2             200      SCONN288_H44441003_PIP-SCONN,HA
GND                      J9U2             202      SCONN288_H44441003_PIP-SCONN,HA
GND                      J9U2             239      SCONN288_H44441003_PIP-SCONN,HA
GND                      J9U2             241      SCONN288_H44441003_PIP-SCONN,HA
GND                      J9U2             243      SCONN288_H44441003_PIP-SCONN,HA
GND                      J9U2             246      SCONN288_H44441003_PIP-SCONN,HA
GND                      J9U2             248      SCONN288_H44441003_PIP-SCONN,HA
GND                      J9U2             250      SCONN288_H44441003_PIP-SCONN,HA
GND                      J9U2             252      SCONN288_H44441003_PIP-SCONN,HA
GND                      J9U2             254      SCONN288_H44441003_PIP-SCONN,HA
GND                      J9U2             257      SCONN288_H44441003_PIP-SCONN,HA
GND                      J9U2             259      SCONN288_H44441003_PIP-SCONN,HA
GND                      J9U2             261      SCONN288_H44441003_PIP-SCONN,HA
GND                      J9U2             263      SCONN288_H44441003_PIP-SCONN,HA
GND                      J9U2             265      SCONN288_H44441003_PIP-SCONN,HA
GND                      J9U2             268      SCONN288_H44441003_PIP-SCONN,HA
GND                      J9U2             270      SCONN288_H44441003_PIP-SCONN,HA
GND                      J9U2             272      SCONN288_H44441003_PIP-SCONN,HA
GND                      J9U2             274      SCONN288_H44441003_PIP-SCONN,HA
GND                      J9U2             276      SCONN288_H44441003_PIP-SCONN,HA
GND                      J9U2             279      SCONN288_H44441003_PIP-SCONN,HA
GND                      J9U2             281      SCONN288_H44441003_PIP-SCONN,HA
GND                      J9U2             283      SCONN288_H44441003_PIP-SCONN,HA
GND                      Q1D2             2        FET_N_SOT23LF-2N7002,FET,C7925A
GND                      Q1D3             2        NPN_SM-MMBT3904,IC,C52245-001
GND                      Q1L1             2        NPN_SM-MMBT3904,IC,C52245-001
GND                      Q1L2             4        FET_N_DUAL_SMLF-NTJD4001N,FET,A
GND                      Q1L3             2        NPN_SM-MMBT3904,IC,C52245-001
GND                      Q1L4             1        FET_N_DUAL_SMLF-2N7002DW,FET,DA
GND                      Q2P1             2        FET_N_SOT23LF-2N7002,FET,C7925A
GND                      Q2P2             2        FET_N_SOT23-2N7002,FET,C79254-A
GND                      Q2T1             2        NPN_SM-MMBT3904,IC,C52245-001
GND                      Q2T2             2        FET_N_SOT23LF-2N7002,FET,C7925A
GND                      Q2U1             1        FET_N_DUAL_SMLF-NTJD4001N,FET,A
GND                      Q2U1             4        FET_N_DUAL_SMLF-NTJD4001N,FET,A
GND                      Q3U1             1        FET_N_DUAL_SMLF-NTJD4001N,FET,A
GND                      Q3U1             4        FET_N_DUAL_SMLF-NTJD4001N,FET,A
GND                      Q4B1             1        FET_N_DUAL_SMLF-NTJD4001N,FET,A
GND                      Q4B1             4        FET_N_DUAL_SMLF-NTJD4001N,FET,A
GND                      Q4B2             1        FET_N_DUAL_SMLF-NTJD4001N,FET,A
GND                      Q4B2             4        FET_N_DUAL_SMLF-NTJD4001N,FET,A
GND                      Q4U1             1        FET_N_DUAL_SMLF-NTJD4001N,FET,A
GND                      Q4U1             4        FET_N_DUAL_SMLF-NTJD4001N,FET,A
GND                      Q6F1             2        FET_N_SOT23-2N7002,FET,C79254-A
GND                      Q7D1             2        FET_N_SOT23-2N7002,FET,C79254-A
GND                      Q7E1             1        FET_N_DUAL_SMLF-NTJD4001N,FET,A
GND                      Q7E1             4        FET_N_DUAL_SMLF-NTJD4001N,FET,A
GND                      Q7E2             1        FET_N_DUAL_SMLF-NTJD4001N,FET,A
GND                      Q7E2             4        FET_N_DUAL_SMLF-NTJD4001N,FET,A
GND                      Q7E3             1        FET_N_DUAL_SMLF-NTJD4001N,FET,A
GND                      Q7E3             4        FET_N_DUAL_SMLF-NTJD4001N,FET,A
GND                      Q7E4             2        FET_N_SOT23-2N7002,FET,C79254-A
GND                      Q7E5             1        FET_N_DUAL_SMLF-NTJD4001N,FET,A
GND                      Q7E5             4        FET_N_DUAL_SMLF-NTJD4001N,FET,A
GND                      Q7E6             1        FET_N_DUAL_SMLF-NTJD4001N,FET,A
GND                      Q7E6             4        FET_N_DUAL_SMLF-NTJD4001N,FET,A
GND                      Q7E8             2        FET_N_SOT23-2N7002,FET,C79254-A
GND                      Q8D1             1        NPN_DUAL_SSOPLF-MBT3904,XSTR,CA
GND                      Q8D1             4        NPN_DUAL_SSOPLF-MBT3904,XSTR,CA
GND                      Q8E1             2        FET_N_SOT23LF-2N7002,FET,C7925A
GND                      Q8E2             2        FET_N_SOT23LF-2N7002,FET,C7925A
GND                      Q8F1             2        FET_N_SOT23LF-2N7002,FET,C7925A
GND                      Q8F2             2        FET_N_SOT23LF-2N7002,FET,C7925A
GND                      Q9A2             1        FET_N_DUAL_SMLF-NTJD4001N,FET,A
GND                      Q9A2             4        FET_N_DUAL_SMLF-NTJD4001N,FET,A
GND                      Q9A3             2        FET_N_SOT23LF-2N7002,FET,C7925A
GND                      Q9E1             1        FET_N_DUAL_SMLF-NTJD4001N,FET,A
GND                      Q9E1             4        FET_N_DUAL_SMLF-NTJD4001N,FET,A
GND                      Q9F1             1        FET_N_DUAL_SMLF-NTJD4001N,FET,A
GND                      Q9F1             4        FET_N_DUAL_SMLF-NTJD4001N,FET,A
GND                      Q9G1             1        FET_N_DUAL_SMLF-NTJD4001N,FET,A
GND                      Q9P1             1        FET_N_DUAL_SMLF-2N7002DW,FET,DA
GND                      Q9P1             4        FET_N_DUAL_SMLF-2N7002DW,FET,DA
GND                      Q9T1             2        NPN_SM-MMBT3904,IC,C52245-001
GND                      R1A1             2        RES_0603-120.0,1%,1/10W,CHIP,GA
GND                      R1A2             2        RES_0402-68.1K,1%,1/16W,EMPTY,A
GND                      R1A3             2        RES_0402-68.1K,1%,1/16W,EMPTY,A
GND                      R1B9             2        RES_0402-1.5K,1%,1/16W,CHIP,G2A
GND                      R1B12            2        RES_0402-3.16K,1%,1/16W,CHIP,GA
GND                      R1B15            2        RES_0402-5.36K,1.0%,1/16W,CHIPA
GND                      R1C4             2        RES_0402-100.0,1%,1/16W,CHIP,GA
GND                      R1C16            2        RES_0402-1.5K,1%,1/16W,CHIP,G2A
GND                      R1C32            1        RES_0402-1.00K,1%,1/16W,CHIP,GA
GND                      R1C33            1        RES_0402-1.00K,1%,1/16W,CHIP,GA
GND                      R1C36            2        RES_0402-1.00K,1%,1/16W,CHIP,GA
GND                      R1C37            2        RES_0402-68.1K,1%,1/16W,EMPTY,A
GND                      R1D31            2        RES_0402-6.19K,1%,1/16W,CHIP,GA
GND                      R1D41            1        RES_0805-0.0,5%,1/8W,CHIP,G221A
GND                      R1D52            2        RES_0402-68.1K,1%,1/16W,EMPTY,A
GND                      R1D54            2        RES_0402-68.1K,1%,1/16W,EMPTY,A
GND                      R1D55            2        RES_0402-68.1K,1%,1/16W,EMPTY,A
GND                      R1E3             2        RES_0603-100.0,1%,1/10W,CHIP,GA
GND                      R1E8             2        RES_0402-100.0,1%,1/16W,CHIP,GA
GND                      R1E13            2        RES_0402-68.1K,1%,1/16W,EMPTY,A
GND                      R1E14            2        RES_0402-68.1K,1%,1/16W,EMPTY,A
GND                      R1F6             2        RES_0402-1.00K,1%,1/16W,CHIP,GA
GND                      R1G3             2        RES_0402-1.00K,1%,1/16W,CHIP,GA
GND                      R1G17            2        RES_0402-1.00K,1%,1/16W,CHIP,GA
GND                      R1G20            2        RES_0603-120.0,1%,1/10W,CHIP,GA
GND                      R1G22            2        RES_0402-5.36K,1.0%,1/16W,CHIPA
GND                      R1G23            2        RES_0402-4.02K,1%,1/16W,CHIP,GA
GND                      R1G24            2        RES_0402-1.5K,1%,1/16W,CHIP,G2A
GND                      R1G25            2        RES_0402-68.1K,1%,1/16W,EMPTY,A
GND                      R1G26            2        RES_0402-68.1K,1%,1/16W,EMPTY,A
GND                      R1L3             2        RES_0402-1.00K,1%,1/16W,CHIP,GA
GND                      R1M23            2        RES_0402-1.00K,1%,1/16W,EMPTY,A
GND                      R1M25            2        RES_0402-10.0K,1%,1/16W,CHIP,GA
GND                      R1R6             2        RES_0402-3.32K,1%,1/16W,EMPTY,A
GND                      R1R12            2        RES_0402-10.0K,1%,1/16W,CHIP,GA
GND                      R1T1             2        RES_0402-10.0K,1%,1/16W,CHIP,GA
GND                      R1T10            2        RES_0402-1.00K,1%,1/16W,EMPTY,A
GND                      R1T11            2        RES_0402-1.00K,1%,1/16W,CHIP,GA
GND                      R1T12            2        RES_0402-1.00K,1%,1/16W,CHIP,GA
GND                      R1T23            2        RES_0402-0.0,5%,1/16W,EMPTY,G2A
GND                      R1T25            2        RES_0402-8.2K,1%,1/16W,CHIP,G2A
GND                      R1T27            2        RES_0402-240,1.0%,1/16W,CHIP,GA
GND                      R1T29            2        RES_0402-1.00K,1%,1/16W,CHIP,GA
GND                      R1U1             2        RES_0402-100.0K,1%,1/16W,CHIP,A
GND                      R1U2             2        RES_0402-100.0K,1%,1/16W,CHIP,A
GND                      R1U3             1        RES_0402-0.0,5%,1/16W,CHIP,G21A
GND                      R1U4             2        RES_0402-100.0K,1%,1/16W,CHIP,A
GND                      R1U5             2        RES_0402-100.0K,1%,1/16W,CHIP,A
GND                      R1U6             2        RES_0402-10.0K,1%,1/16W,CHIP,GA
GND                      R1U7             1        RES_0402-10.0K,1%,1/16W,CHIP,GA
GND                      R1U15            2        RES_0402-1.00K,1%,1/16W,EMPTY,A
GND                      R1U16            2        RES_0402-1.00K,1%,1/16W,EMPTY,A
GND                      R1U17            2        RES_0402-1.00K,1%,1/16W,CHIP,GA
GND                      R1U18            2        RES_0402-1.00K,1%,1/16W,CHIP,GA
GND                      R1U27            2        RES_0402-8.2K,1%,1/16W,CHIP,G2A
GND                      R1U28            2        RES_0402-3.48K,1.0%,1/16W,CHIPA
GND                      R1U30            2        RES_0402-1.00K,1%,1/16W,CHIP,GA
GND                      R1U33            2        RES_0402-1.00K,1%,1/16W,CHIP,GA
GND                      R1U37            2        RES_0402-100.0,1%,1/16W,CHIP,GA
GND                      R1U38            2        RES_0402-8.2K,1%,1/16W,CHIP,G2A
GND                      R1U44            2        RES_0402-3.48K,1.0%,1/16W,CHIPA
GND                      R1U45            2        RES_0402-4.75K,1%,1/16W,CHIP,GA
GND                      R1U48            2        RES_0402-4.75K,1%,1/16W,CHIP,GA
GND                      R1U51            1        RES_0402-0.0,5%,1/16W,CHIP,G21A
GND                      R1U63            2        RES_0402-1.00K,1%,1/16W,CHIP,GA
GND                      R1U64            2        RES_0402-1.00K,1%,1/16W,CHIP,GA
GND                      R2L9             2        RES_0402-4.02K,1%,1/16W,CHIP,GA
GND                      R2L10            2        RES_0402-1.5K,1%,1/16W,CHIP,G2A
GND                      R2L18            2        RES_0402-1.00K,1%,1/16W,CHIP,GA
GND                      R2L19            2        RES_0402-49.9K,1%,1/16W,CHIP,GA
GND                      R2L22            2        RES_0402-1.00K,1%,1/16W,CHIP,GA
GND                      R2N12            1        RES_0402-10.0K,1%,1/16W,EMPTY,A
GND                      R2N13            2        RES_0402-10.0K,1%,1/16W,CHIP,GA
GND                      R2N18            2        RES_0402-1.00K,1%,1/16W,CHIP,GA
GND                      R2N24            2        RES_0402-1.00K,1%,1/16W,EMPTY,A
GND                      R2P11            2        RES_0402-1.00K,1%,1/16W,EMPTY,A
GND                      R2R8             2        RES_0402-100.0,1%,1/16W,CHIP,GA
GND                      R2R11            2        RES_0402-1.00K,1%,1/16W,EMPTY,A
GND                      R2T1             2        RES_0402-1.00K,1%,1/16W,CHIP,GA
GND                      R2T4             2        RES_0402-1.0K,0.1%,1/16W,CHIP,A
GND                      R2T12            2        RES_0402-10.0K,1%,1/16W,EMPTY,A
GND                      R2T15            2        RES_0402-100.0K,1%,1/16W,CHIP,A
GND                      R2T25            2        RES_0402-1.00K,1%,1/16W,CHIP,GA
GND                      R2T39            2        RES_0402-100.0,1%,1/16W,CHIP,GA
GND                      R2T50            2        RES_0402-1.00K,1%,1/16W,CHIP,GA
GND                      R3D1             2        RES_0402-90.9,1%,1/16W,CHIP,G2A
GND                      R3D2             2        RES_0402-90.9,1%,1/16W,CHIP,G2A
GND                      R3D3             2        RES_0402-100.0,1%,1/16W,CHIP,GA
GND                      R3D4             2        RES_0402-49.9,1%,1/16W,CHIP,G2A
GND                      R3D9             2        RES_0402-49.9,1%,1/16W,CHIP,G2A
GND                      R3D12            1        RES_0402-240,1.0%,1/16W,CHIP,GA
GND                      R3D13            1        RES_0402-240,1.0%,1/16W,EMPTY,A
GND                      R3D19            2        RES_0402-49.9,1%,1/16W,CHIP,G2A
GND                      R3D27            2        RES_0402-249,0.1%,1/16W,CHIP,GA
GND                      R3D28            2        RES_0402-100.0,1%,1/16W,CHIP,GA
GND                      R3L14            2        RES_0402-68.1K,1%,1/16W,EMPTY,A
GND                      R3L15            2        RES_0402-68.1K,1%,1/16W,EMPTY,A
GND                      R3M8             2        RES_0402-100.0K,1%,1/16W,CHIP,A
GND                      R3M9             2        RES_0402-100.0K,1%,1/16W,CHIP,A
GND                      R3M10            2        RES_0402-1.00K,1%,1/16W,CHIP,GA
GND                      R3N1             2        RES_0402-169,1.0%,1/16W,CHIP,GA
GND                      R3N3             1        RES_0402-2.0K,1%,1/16W,CHIP,G2A
GND                      R3N14            2        RES_0402-49.9,1%,1/16W,EMPTY,GA
GND                      R3N20            2        RES_0402-100.0,1%,1/16W,CHIP,GA
GND                      R3N22            2        RES_0402-4.02K,1%,1/16W,CHIP,GA
GND                      R3N29            2        RES_0402-16K,1.0%,1/16W,CHIP,GA
GND                      R3N31            2        RES_0402-3.16K,1%,1/16W,CHIP,GA
GND                      R3P16            2        RES_0402-1.5K,1%,1/16W,CHIP,G2A
GND                      R3P32            1        RES_0402-1.00K,1%,1/16W,CHIP,GA
GND                      R3P49            2        RES_0402-100.0,1%,1/16W,CHIP,GA
GND                      R3P51            2        RES_0402-6.34K,1%,1/16W,CHIP,GA
GND                      R3P56            2        RES_0402-1.00K,1%,1/16W,CHIP,GA
GND                      R3P64            2        RES_0402-1.00K,1%,1/16W,EMPTY,A
GND                      R3R1             2        RES_0402-1.00K,1%,1/16W,CHIP,GA
GND                      R3R2             2        RES_0402-1.00K,1%,1/16W,CHIP,GA
GND                      R3R11            2        RES_0402-10.0K,1%,1/16W,EMPTY,A
GND                      R3T9             2        RES_0402-10.0K,1%,1/16W,EMPTY,A
GND                      R3T14            2        RES_0402-10.0K,1%,1/16W,CHIP,GA
GND                      R3U4             2        RES_0603-120.0,1%,1/10W,CHIP,GA
GND                      R4A1             1        RES_0402-51.1,1.0%,1/16W,CHIP,A
GND                      R4A7             2        RES_0402-2.2,5%,1/16W,EMPTY,G2A
GND                      R4B2             2        RES_0603-120.0,1%,1/10W,CHIP,GA
GND                      R4B14            1        RES_0402-0.0,5%,1/16W,CHIP,G21A
GND                      R4C1             2        RES_0402-100.0,1%,1/16W,CHIP,GA
GND                      R4C9             1        RES_0402-1.00K,1%,1/16W,CHIP,GA
GND                      R4C11            2        RES_0402-3.16K,1%,1/16W,CHIP,GA
GND                      R4C12            2        RES_0402-8.06K,1%,1/16W,CHIP,GA
GND                      R4C13            2        RES_0402-68.1K,1%,1/16W,EMPTY,A
GND                      R4D18            2        RES_0402-42.2,1.0%,1/16W,EMPTYA
GND                      R4D24            2        RES_0402-42.2,1.0%,1/16W,EMPTYA
GND                      R4D32            2        RES_0402-1.5K,1%,1/16W,CHIP,G2A
GND                      R4D57            2        RES_0402-1.5K,1%,1/16W,CHIP,G2A
GND                      R4D64            2        RES_0402-3.16K,1%,1/16W,CHIP,GA
GND                      R4D68            2        RES_0402-68.1K,1%,1/16W,EMPTY,A
GND                      R4D71            2        RES_0402-68.1K,1%,1/16W,EMPTY,A
GND                      R4D72            2        RES_0402-68.1K,1%,1/16W,EMPTY,A
GND                      R4E2             2        RES_0402-3.16K,1%,1/16W,CHIP,GA
GND                      R4E13            2        RES_0603-100.0,1%,1/10W,CHIP,GA
GND                      R4E18            2        RES_0402-100.0,1%,1/16W,CHIP,GA
GND                      R4E19            2        RES_0402-68.1K,1%,1/16W,EMPTY,A
GND                      R4E21            2        RES_0402-68.1K,1%,1/16W,EMPTY,A
GND                      R4E22            2        RES_0402-68.1K,1%,1/16W,EMPTY,A
GND                      R4F5             2        RES_0402-1.00K,1%,1/16W,CHIP,GA
GND                      R4F6             2        RES_0402-2.2,5%,1/16W,EMPTY,G2A
GND                      R4G3             2        RES_0402-1.00K,1%,1/16W,CHIP,GA
GND                      R4G5             2        RES_0402-10.0K,1%,1/16W,CHIP,GA
GND                      R4G6             2        RES_0603-120.0,1%,1/10W,CHIP,GA
GND                      R4G22            2        RES_0402-1.00K,1%,1/16W,CHIP,GA
GND                      R4G25            1        RES_0402-0.0,5%,1/16W,CHIP,G21A
GND                      R4L4             2        RES_0603-120.0,1%,1/10W,CHIP,GA
GND                      R4P1             1        RES_0402-240,1.0%,1/16W,EMPTY,A
GND                      R4P2             2        RES_0402-49.9,1%,1/16W,CHIP,G2A
GND                      R4P3             2        RES_0402-49.9,1%,1/16W,CHIP,G2A
GND                      R4P4             2        RES_0402-49.9,1%,1/16W,CHIP,G2A
GND                      R4P5             1        RES_0402-10.0K,1%,1/16W,CHIP,GA
GND                      R4P6             1        RES_0402-240,1.0%,1/16W,EMPTY,A
GND                      R4P7             1        RES_0402-240,1.0%,1/16W,EMPTY,A
GND                      R4P8             2        RES_0402-90.9,1%,1/16W,CHIP,G2A
GND                      R4P10            2        RES_0402-90.9,1%,1/16W,CHIP,G2A
GND                      R4P11            2        RES_0402-100.0,1%,1/16W,CHIP,GA
GND                      R4U4             2        RES_0402-33.0K,5%,1/16W,CHIP,GA
GND                      R5D1             2        RES_0402-90.9,1%,1/16W,CHIP,G2A
GND                      R5D2             2        RES_0402-90.9,1%,1/16W,CHIP,G2A
GND                      R5D5             2        RES_0402-249,0.1%,1/16W,CHIP,GA
GND                      R5P2             2        RES_0402-49.9,1%,1/16W,CHIP,G2A
GND                      R5P3             2        RES_0402-49.9,1%,1/16W,CHIP,G2A
GND                      R5P4             2        RES_0402-49.9,1%,1/16W,CHIP,G2A
GND                      R5R1             2        RES_0402-49.9,1%,1/16W,CHIP,G2A
GND                      R6D1             2        RES_0402-100.0,1%,1/16W,CHIP,GA
GND                      R6D2             2        RES_0402-49.9,1%,1/16W,CHIP,G2A
GND                      R6D5             2        RES_0402-49.9,1%,1/16W,CHIP,G2A
GND                      R6D6             1        RES_0402-240,1.0%,1/16W,CHIP,GA
GND                      R6D11            2        RES_0402-49.9,1%,1/16W,CHIP,G2A
GND                      R6L1             2        RES_0402-1.00K,1%,1/16W,CHIP,GA
GND                      R6L7             1        RES_0402-51.1,1.0%,1/16W,CHIP,A
GND                      R6L12            2        RES_0402-1.00K,1%,1/16W,CHIP,GA
GND                      R6L16            2        RES_0402-1.00K,1%,1/16W,CHIP,GA
GND                      R6N4             2        RES_0402-51.1,1.0%,1/16W,CHIP,A
GND                      R6N13            1        RES_0402-1.00K,1%,1/16W,CHIP,GA
GND                      R6N14            1        RES_0402-1.00K,1%,1/16W,CHIP,GA
GND                      R6N15            1        RES_0402-1.00K,1%,1/16W,CHIP,GA
GND                      R6P1             2        RES_0402-42.2,1.0%,1/16W,EMPTYA
GND                      R6P2             2        RES_0402-42.2,1.0%,1/16W,EMPTYA
GND                      R6P3             2        RES_0402-42.2,1.0%,1/16W,EMPTYA
GND                      R6P4             2        RES_0402-42.2,1.0%,1/16W,EMPTYA
GND                      R6P5             2        RES_0402-42.2,1.0%,1/16W,EMPTYA
GND                      R6P6             2        RES_0402-42.2,1.0%,1/16W,EMPTYA
GND                      R6P7             2        RES_0402-42.2,1.0%,1/16W,EMPTYA
GND                      R6P8             2        RES_0402-42.2,1.0%,1/16W,EMPTYA
GND                      R6P9             2        RES_0402-42.2,1.0%,1/16W,EMPTYA
GND                      R6P11            2        RES_0402-42.2,1.0%,1/16W,EMPTYA
GND                      R6P12            2        RES_0402-42.2,1.0%,1/16W,EMPTYA
GND                      R6P13            2        RES_0402-42.2,1.0%,1/16W,EMPTYA
GND                      R6P15            2        RES_0402-42.2,1.0%,1/16W,EMPTYA
GND                      R6P17            2        RES_0402-42.2,1.0%,1/16W,EMPTYA
GND                      R6P20            2        RES_0402-1.00K,1%,1/16W,CHIP,GA
GND                      R6P21            2        RES_0402-1.00K,1%,1/16W,CHIP,GA
GND                      R6P22            2        RES_0402-4.75K,1%,1/16W,EMPTY,A
GND                      R6P23            2        RES_0402-4.75K,1%,1/16W,EMPTY,A
GND                      R6P27            2        RES_0402-4.02K,1%,1/16W,CHIP,GA
GND                      R6P28            2        RES_0402-4.02K,1%,1/16W,CHIP,GA
GND                      R6T5             2        RES_0402-1.00K,1%,1/16W,CHIP,GA
GND                      R6U8             1        RES_0402-51.1,1.0%,1/16W,CHIP,A
GND                      R6U16            1        RES_0402-51.1,1.0%,1/16W,CHIP,A
GND                      R7A8             2        RES_0402-8.06K,1%,1/16W,CHIP,GA
GND                      R7A10            2        RES_0402-3.16K,1%,1/16W,CHIP,GA
GND                      R7A15            2        RES_0402-2.2,5%,1/16W,EMPTY,G2A
GND                      R7A16            2        RES_0402-1.5K,1%,1/16W,CHIP,G2A
GND                      R7A18            1        RES_0402-0.0,5%,1/16W,CHIP,G21A
GND                      R7A20            2        RES_0402-68.1K,1%,1/16W,EMPTY,A
GND                      R7A21            2        RES_0402-68.1K,1%,1/16W,EMPTY,A
GND                      R7B7             2        RES_0402-10.0K,1%,1/16W,EMPTY,A
GND                      R7B8             2        RES_0402-10.0K,1%,1/16W,EMPTY,A
GND                      R7B10            2        RES_0603-120.0,1%,1/10W,CHIP,GA
GND                      R7B20            1        RES_0402-0.0,5%,1/16W,CHIP,G21A
GND                      R7C3             2        RES_0402-51.1,1.0%,1/16W,CHIP,A
GND                      R7C11            1        RES_0402-1.0M,1%,1/16W,EMPTY,GA
GND                      R7C20            2        RES_0402-10.0K,1%,1/16W,CHIP,GA
GND                      R7C24            2        RES_0402-4.02K,1%,1/16W,CHIP,GA
GND                      R7C25            2        RES_0402-68.1K,1%,1/16W,EMPTY,A
GND                      R7D1             2        RES_0402-1.00K,1%,1/16W,CHIP,GA
GND                      R7D15            2        RES_0402-348,1%,1/16W,CHIP,G21A
GND                      R7D19            2        RES_0402-1.00K,1%,1/16W,EMPTY,A
GND                      R7D26            2        RES_0402-1.00K,1%,1/16W,CHIP,GA
GND                      R7D32            2        RES_0402-100.0,1%,1/16W,CHIP,GA
GND                      R7E13            1        RES_0402-0.0,5%,1/16W,CHIP,G21A
GND                      R7E20            2        RES_0402-1.00K,1%,1/16W,CHIP,GA
GND                      R7F7             2        RES_0402-2.2,5%,1/16W,EMPTY,G2A
GND                      R7F10            2        RES_0603-120.0,1%,1/10W,CHIP,GA
GND                      R7F14            2        RES_0402-10.0K,1%,1/16W,CHIP,GA
GND                      R7F30            2        RES_0402-10.0K,1%,1/16W,EMPTY,A
GND                      R7F35            1        RES_0402-0.0,5%,1/16W,CHIP,G21A
GND                      R7G3             2        RES_0402-1.5K,1%,1/16W,CHIP,G2A
GND                      R7G8             2        RES_0402-4.02K,1%,1/16W,CHIP,GA
GND                      R7G10            2        RES_0402-8.06K,1%,1/16W,CHIP,GA
GND                      R7G25            2        RES_0402-68.1K,1%,1/16W,EMPTY,A
GND                      R7G28            2        RES_0402-1.00K,1%,1/16W,CHIP,GA
GND                      R7G29            2        RES_0402-1.00K,1%,1/16W,CHIP,GA
GND                      R7G30            2        RES_0402-68.1K,1%,1/16W,EMPTY,A
GND                      R7P1             2        RES_0402-42.2,1.0%,1/16W,EMPTYA
GND                      R7P2             2        RES_0402-42.2,1.0%,1/16W,EMPTYA
GND                      R7P3             2        RES_0402-42.2,1.0%,1/16W,EMPTYA
GND                      R7P4             2        RES_0402-42.2,1.0%,1/16W,EMPTYA
GND                      R7P6             2        RES_0402-42.2,1.0%,1/16W,EMPTYA
GND                      R7P7             2        RES_0402-42.2,1.0%,1/16W,EMPTYA
GND                      R7P8             2        RES_0402-49.9,1%,1/16W,CHIP,G2A
GND                      R7P9             2        RES_0402-42.2,1.0%,1/16W,EMPTYA
GND                      R7P10            2        RES_0402-49.9,1%,1/16W,CHIP,G2A
GND                      R7P11            2        RES_0402-49.9,1%,1/16W,CHIP,G2A
GND                      R7P12            2        RES_0402-42.2,1.0%,1/16W,EMPTYA
GND                      R7P13            1        RES_0402-10.0K,1%,1/16W,CHIP,GA
GND                      R7P14            1        RES_0402-240,1.0%,1/16W,CHIP,GA
GND                      R7P15            1        RES_0402-240,1.0%,1/16W,EMPTY,A
GND                      R7P16            2        RES_0402-90.9,1%,1/16W,CHIP,G2A
GND                      R7P17            2        RES_0402-90.9,1%,1/16W,CHIP,G2A
GND                      R7P19            2        RES_0402-100.0,1%,1/16W,CHIP,GA
GND                      R7P29            2        RES_0402-51.1,1.0%,1/16W,CHIP,A
GND                      R7R1             2        RES_0402-51.1,1.0%,1/16W,CHIP,A
GND                      R8A2             2        RES_0402-2.67K,1%,1/16W,CHIP,GA
GND                      R8A12            2        RES_0603-475.0,1%,1/10W,CHIP,GA
GND                      R8B1             2        RES_0402-51.1,1.0%,1/16W,CHIP,A
GND                      R8B2             2        RES_0402-1.00K,1%,1/16W,CHIP,GA
GND                      R8B4             2        RES_0402-100.0K,1%,1/16W,CHIP,A
GND                      R8B9             2        RES_0402-113,1%,1/16W,CHIP,G21A
GND                      R8B12            2        RES_0402-0.0,5%,1/16W,CHIP,G21A
GND                      R8B21            2        RES_0402-49.9,1%,1/16W,EMPTY,GA
GND                      R8B32            2        RES_0402-10.0K,1%,1/16W,CHIP,GA
GND                      R8C17            2        RES_0402-1.00K,1%,1/16W,EMPTY,A
GND                      R8C21            2        RES_0402-100.0,1%,1/16W,CHIP,GA
GND                      R8C26            2        RES_0402-100.0,1%,1/16W,CHIP,GA
GND                      R8D5             2        RES_0402-1.00K,1%,1/16W,EMPTY,A
GND                      R8D27            2        RES_0402-1.00K,1%,1/16W,CHIP,GA
GND                      R8D37            2        RES_0402-4.75K,1%,1/16W,CHIP,GA
GND                      R8D40            2        RES_0402-3.74K,1%,1/16W,CHIP,GA
GND                      R8E4             2        RES_0402-1.00K,1%,1/16W,EMPTY,A
GND                      R8E16            2        RES_0402-20.0K,1%,1/16W,CHIP,GA
GND                      R8E18            2        RES_0402-1.0K,0.1%,1/16W,CHIP,A
GND                      R8F1             2        RES_0402-10.0K,1%,1/16W,EMPTY,A
GND                      R8F3             2        RES_0402-2.2,5%,1/16W,EMPTY,G2A
GND                      R8F11            1        RES_0402-0.0,5%,1/16W,CHIP,G21A
GND                      R8F25            2        RES_0402-475.0,1%,1/16W,CHIP,GA
GND                      R8F35            2        RES_0402-1.00K,1%,1/16W,EMPTY,A
GND                      R8G23            2        RES_0402-4.75K,1%,1/16W,CHIP,GA
GND                      R8P1             2        RES_0402-49.9,1%,1/16W,CHIP,G2A
GND                      R8P2             2        RES_0402-49.9,1%,1/16W,CHIP,G2A
GND                      R8P3             2        RES_0402-49.9,1%,1/16W,CHIP,G2A
GND                      R8R1             2        RES_0402-49.9,1%,1/16W,CHIP,G2A
GND                      R9B7             1        RES_0402-100.0,1%,1/16W,CHIP,GA
GND                      R9B8             2        RES_0402-1.00K,1%,1/16W,CHIP,GA
GND                      R9B9             2        RES_0402-1.00K,1%,1/16W,CHIP,GA
GND                      R9E13            2        RES_0402-10.0K,1%,1/16W,CHIP,GA
GND                      R9E23            2        RES_0402-4.99K,1%,1/16W,CHIP,GA
GND                      R9F4             2        RES_0402-100.0K,1%,1/16W,CHIP,A
GND                      R9F8             1        RES_0402-10.0K,1%,1/16W,CHIP,GA
GND                      R9F20            2        RES_0402-348,1%,1/16W,EMPTY,G2A
GND                      R9F32            1        RES_0402-13K,1.0%,1/16W,CHIP,GA
GND                      R9F42            2        RES_0402-100.0K,1%,1/16W,CHIP,A
GND                      R9F43            2        RES_0402-100.0K,1%,1/16W,CHIP,A
GND                      R9F44            2        RES_0402-100.0K,1%,1/16W,CHIP,A
GND                      R9F45            2        RES_0402-100.0K,1%,1/16W,CHIP,A
GND                      R9F46            2        RES_0402-100.0K,1%,1/16W,CHIP,A
GND                      R9F50            2        RES_0402-1.00K,1%,1/16W,CHIP,GA
GND                      R9F51            2        RES_0402-1.00K,1%,1/16W,CHIP,GA
GND                      R9G5             2        RES_0402-0.0,5%,1/16W,EMPTY,G2A
GND                      R9G6             2        RES_0402-0.0,5%,1/16W,EMPTY,G2A
GND                      R9G7             2        RES_0402-49.9K,1%,1/16W,CHIP,GA
GND                      R9G8             2        RES_0402-2.7K,1%,1/16W,CHIP,G2A
GND                      R9G26            2        RES_0402-100.0K,1%,1/16W,CHIP,A
GND                      R9L1             2        RES_0402-1.00K,1%,1/16W,CHIP,GA
GND                      R9L6             2        RES_0402-1.00K,1%,1/16W,CHIP,GA
GND                      R9L11            2        RES_0402-1.00K,1%,1/16W,CHIP,GA
GND                      R9N4             2        RES_0402-51.1,1.0%,1/16W,CHIP,A
GND                      R9N7             2        RES_0402-3.16K,1%,1/16W,CHIP,GA
GND                      R9N8             2        RES_0402-4.02K,1%,1/16W,CHIP,GA
GND                      R9T3             2        RES_0402-6.19K,1%,1/16W,CHIP,GA
GND                      R9T8             2        RES_0402-0.0,5%,1/16W,EMPTY,G2A
GND                      RM1E1            1        CONN3_G98259001_PIP-CONN,G9825A
GND                      RM1E1            2        CONN3_G98259001_PIP-CONN,G9825A
GND                      RM1E1            3        CONN3_G98259001_PIP-CONN,G9825A
GND                      RM8D1            1        STANDOFF_TH1-SO,H72821-001
GND                      RTI2             1        3D01R5F-GP_SMD-RG5-3D01R5F-GP,A
GND                      RTI4             1        3D01R5F-GP_SMD-RG5-3D01R5F-GP,A
GND                      RTI6             2        3D01R5F-GP_SMD-RG5-3D01R5F-GP,A
GND                      RTI7             2        3D01R5F-GP_SMD-RG5-3D01R5F-GP,A
GND                      RTI10            1        3D01R5F-GP_SMD-RG5-3D01R5F-GP,A
GND                      RTI12            1        3D01R5F-GP_SMD-RG5-3D01R5F-GP,A
GND                      RTI13            1        3D01R5F-GP_SMD-RG5-3D01R5F-GP,A
GND                      RTI16            1        3D01R5F-GP_SMD-RG5-3D01R5F-GP,A
GND                      RTI18            1        3D01R5F-GP_SMD-RG5-3D01R5F-GP,A
GND                      RTI20            1        3D01R5F-GP_SMD-RG5-3D01R5F-GP,A
GND                      RTI22            1        3D01R5F-GP_SMD-RG5-3D01R5F-GP,A
GND                      RTI24            1        3D01R5F-GP_SMD-RG5-3D01R5F-GP,A
GND                      RTI26            1        3D01R5F-GP_SMD-RG5-3D01R5F-GP,A
GND                      RTI27            1        3D01R5F-GP_SMD-RG5-3D01R5F-GP,A
GND                      RTI29            1        3D01R5F-GP_SMD-RG5-3D01R5F-GP,A
GND                      RTI32            1        3D01R5F-GP_SMD-RG5-3D01R5F-GP,A
GND                      RTI34            1        3D01R5F-GP_SMD-RG5-3D01R5F-GP,A
GND                      RTI35            1        3D01R5F-GP_SMD-RG5-3D01R5F-GP,A
GND                      RTI38            1        3D01R5F-GP_SMD-RG5-3D01R5F-GP,A
GND                      RTI39            1        3D01R5F-GP_SMD-RG5-3D01R5F-GP,A
GND                      RTI42            1        3D01R5F-GP_SMD-RG5-3D01R5F-GP,A
GND                      RTI43            1        3D01R5F-GP_SMD-RG5-3D01R5F-GP,A
GND                      RTI45            1        3D01R5F-GP_SMD-RG5-3D01R5F-GP,A
GND                      RTI48            1        3D01R5F-GP_SMD-RG5-3D01R5F-GP,A
GND                      S8E1             1        SWITCH_D90553001_SMLF-IC,D9055A
GND                      S9A1             3        SWITCH_D37771002_SM-IC,D37771-A
GND                      S9A1             4        SWITCH_D37771002_SM-IC,D37771-A
GND                      S9A2             3        SW_H67881001_SM-IC,H67881-001
GND                      S9A2             4        SW_H67881001_SM-IC,H67881-001
GND                      SH4L1            2        SHUNT_SH0201-EMPTY,N_A
GND                      SH4U1            2        SHUNT_SH0201-EMPTY,N_A
GND                      SH7L1            2        SHUNT_SH0201-EMPTY,N_A
GND                      SH7U2            2        SHUNT_SH0201-EMPTY,N_A
GND                      TC1A1            1        RCC_DFX1940_ID4-EMPTY,N_A
GND                      TC1G1            1        RCC_DFX1940_ID4-EMPTY,N_A
GND                      TC9A1            1        RCC_DFX1940_ID4-EMPTY,N_A
GND                      TC9F1            1        RCC_DFX1940_ID4-EMPTY,N_A
GND                      TH1A1            1        MTG_KEYHOLE_TH-EMPTY,NA
GND                      TH4A1            1        MTG_KEYHOLE_TH-EMPTY,NA
GND                      TH4G1            1        MTG_KEYHOLE_TH-EMPTY,NA
GND                      TH7A1            1        MTG_KEYHOLE_TH-EMPTY,NA
GND                      TH7G1            1        MTG_KEYHOLE_TH-EMPTY,NA
GND                      TH9A1            1        MTG_KEYHOLE_TH-EMPTY,NA
GND                      TH9G1            1        MTG_KEYHOLE_TH-EMPTY,NA
GND                      U1B1             1        MAX9634_SOT-IC,H35789-001
GND                      U1B1             2        MAX9634_SOT-IC,H35789-001
GND                      U1B3             1        ADM4073_SM-EMPTY,G12194-001
GND                      U1B3             2        ADM4073_SM-EMPTY,G12194-001
GND                      U1D2             5        TPS3700_SM-IC,H69492-001
GND                      U1E1             5        TMP421_TSSOP-IC,G62962-001
GND                      U1F1             1        MAX9634_SOT-IC,H35789-001
GND                      U1F1             2        MAX9634_SOT-IC,H35789-001
GND                      U1M2             2        NC7SB3157_SMLF-IC,C99406-001
GND                      U1M3             2        TPS2061_SM-IC,H66405-001
GND                      U1M7             2        NC7SB3157_SMLF-IC,C99406-001
GND                      U2D1             A26      SKX_EXT_B_BGA1-IC,TBD
GND                      U2D1             A30      SKX_EXT_B_BGA1-IC,TBD
GND                      U2D1             A32      SKX_EXT_B_BGA1-IC,TBD
GND                      U2D1             A36      SKX_EXT_B_BGA1-IC,TBD
GND                      U2D1             A38      SKX_EXT_B_BGA1-IC,TBD
GND                      U2D1             A42      SKX_EXT_B_BGA1-IC,TBD
GND                      U2D1             AA4      SKX_EXT_B_BGA1-IC,TBD
GND                      U2D1             AA16     SKX_EXT_B_BGA1-IC,TBD
GND                      U2D1             AA18     SKX_EXT_B_BGA1-IC,TBD
GND                      U2D1             AA22     SKX_EXT_B_BGA1-IC,TBD
GND                      U2D1             AA24     SKX_EXT_B_BGA1-IC,TBD
GND                      U2D1             AA30     SKX_EXT_B_BGA1-IC,TBD
GND                      U2D1             AA36     SKX_EXT_B_BGA1-IC,TBD
GND                      U2D1             AA42     SKX_EXT_B_BGA1-IC,TBD
GND                      U2D1             AA64     SKX_EXT_B_BGA1-IC,TBD
GND                      U2D1             AA66     SKX_EXT_B_BGA1-IC,TBD
GND                      U2D1             AA68     SKX_EXT_B_BGA1-IC,TBD
GND                      U2D1             AA76     SKX_EXT_B_BGA1-IC,TBD
GND                      U2D1             AA78     SKX_EXT_B_BGA1-IC,TBD
GND                      U2D1             AA80     SKX_EXT_B_BGA1-IC,TBD
GND                      U2D1             AA82     SKX_EXT_B_BGA1-IC,TBD
GND                      U2D1             AB1      SKX_EXT_B_BGA1-IC,TBD
GND                      U2D1             AB5      SKX_EXT_B_BGA1-IC,TBD
GND                      U2D1             AB11     SKX_EXT_B_BGA1-IC,TBD
GND                      U2D1             AB21     SKX_EXT_B_BGA1-IC,TBD
GND                      U2D1             AB23     SKX_EXT_B_BGA1-IC,TBD
GND                      U2D1             AB25     SKX_EXT_B_BGA1-IC,TBD
GND                      U2D1             AB29     SKX_EXT_B_BGA1-IC,TBD
GND                      U2D1             AB31     SKX_EXT_B_BGA1-IC,TBD
GND                      U2D1             AB35     SKX_EXT_B_BGA1-IC,TBD
GND                      U2D1             AB37     SKX_EXT_B_BGA1-IC,TBD
GND                      U2D1             AB41     SKX_EXT_B_BGA1-IC,TBD
GND                      U2D1             AB65     SKX_EXT_B_BGA1-IC,TBD
GND                      U2D1             AB69     SKX_EXT_B_BGA1-IC,TBD
GND                      U2D1             AB73     SKX_EXT_B_BGA1-IC,TBD
GND                      U2D1             AB79     SKX_EXT_B_BGA1-IC,TBD
GND                      U2D1             AB83     SKX_EXT_B_BGA1-IC,TBD
GND                      U2D1             AB85     SKX_EXT_B_BGA1-IC,TBD
GND                      U2D1             AC18     SKX_EXT_B_BGA1-IC,TBD
GND                      U2D1             AC22     SKX_EXT_B_BGA1-IC,TBD
GND                      U2D1             AC26     SKX_EXT_B_BGA1-IC,TBD
GND                      U2D1             AC28     SKX_EXT_B_BGA1-IC,TBD
GND                      U2D1             AC32     SKX_EXT_B_BGA1-IC,TBD
GND                      U2D1             AC34     SKX_EXT_B_BGA1-IC,TBD
GND                      U2D1             AC38     SKX_EXT_B_BGA1-IC,TBD
GND                      U2D1             AC40     SKX_EXT_B_BGA1-IC,TBD
GND                      U2D1             AC48     SKX_EXT_B_BGA1-IC,TBD
GND                      U2D1             AC50     SKX_EXT_B_BGA1-IC,TBD
GND                      U2D1             AC52     SKX_EXT_B_BGA1-IC,TBD
GND                      U2D1             AC54     SKX_EXT_B_BGA1-IC,TBD
GND                      U2D1             AC56     SKX_EXT_B_BGA1-IC,TBD
GND                      U2D1             AC58     SKX_EXT_B_BGA1-IC,TBD
GND                      U2D1             AC60     SKX_EXT_B_BGA1-IC,TBD
GND                      U2D1             AC62     SKX_EXT_B_BGA1-IC,TBD
GND                      U2D1             AC64     SKX_EXT_B_BGA1-IC,TBD
GND                      U2D1             AC70     SKX_EXT_B_BGA1-IC,TBD
GND                      U2D1             AC72     SKX_EXT_B_BGA1-IC,TBD
GND                      U2D1             AC78     SKX_EXT_B_BGA1-IC,TBD
GND                      U2D1             AC84     SKX_EXT_B_BGA1-IC,TBD
GND                      U2D1             AC86     SKX_EXT_B_BGA1-IC,TBD
GND                      U2D1             AD3      SKX_EXT_B_BGA1-IC,TBD
GND                      U2D1             AD7      SKX_EXT_B_BGA1-IC,TBD
GND                      U2D1             AD9      SKX_EXT_B_BGA1-IC,TBD
GND                      U2D1             AD11     SKX_EXT_B_BGA1-IC,TBD
GND                      U2D1             AD13     SKX_EXT_B_BGA1-IC,TBD
GND                      U2D1             AD15     SKX_EXT_B_BGA1-IC,TBD
GND                      U2D1             AD19     SKX_EXT_B_BGA1-IC,TBD
GND                      U2D1             AD21     SKX_EXT_B_BGA1-IC,TBD
GND                      U2D1             AD27     SKX_EXT_B_BGA1-IC,TBD
GND                      U2D1             AD33     SKX_EXT_B_BGA1-IC,TBD
GND                      U2D1             AD39     SKX_EXT_B_BGA1-IC,TBD
GND                      U2D1             AD43     SKX_EXT_B_BGA1-IC,TBD
GND                      U2D1             AD71     SKX_EXT_B_BGA1-IC,TBD
GND                      U2D1             AD73     SKX_EXT_B_BGA1-IC,TBD
GND                      U2D1             AD75     SKX_EXT_B_BGA1-IC,TBD
GND                      U2D1             AD81     SKX_EXT_B_BGA1-IC,TBD
GND                      U2D1             AD83     SKX_EXT_B_BGA1-IC,TBD
GND                      U2D1             AD85     SKX_EXT_B_BGA1-IC,TBD
GND                      U2D1             AE4      SKX_EXT_B_BGA1-IC,TBD
GND                      U2D1             AE8      SKX_EXT_B_BGA1-IC,TBD
GND                      U2D1             AE16     SKX_EXT_B_BGA1-IC,TBD
GND                      U2D1             AE38     SKX_EXT_B_BGA1-IC,TBD
GND                      U2D1             AE40     SKX_EXT_B_BGA1-IC,TBD
GND                      U2D1             AE42     SKX_EXT_B_BGA1-IC,TBD
GND                      U2D1             AE64     SKX_EXT_B_BGA1-IC,TBD
GND                      U2D1             AE66     SKX_EXT_B_BGA1-IC,TBD
GND                      U2D1             AE68     SKX_EXT_B_BGA1-IC,TBD
GND                      U2D1             AE70     SKX_EXT_B_BGA1-IC,TBD
GND                      U2D1             AE78     SKX_EXT_B_BGA1-IC,TBD
GND                      U2D1             AF1      SKX_EXT_B_BGA1-IC,TBD
GND                      U2D1             AF9      SKX_EXT_B_BGA1-IC,TBD
GND                      U2D1             AF21     SKX_EXT_B_BGA1-IC,TBD
GND                      U2D1             AF23     SKX_EXT_B_BGA1-IC,TBD
GND                      U2D1             AF25     SKX_EXT_B_BGA1-IC,TBD
GND                      U2D1             AF27     SKX_EXT_B_BGA1-IC,TBD
GND                      U2D1             AF29     SKX_EXT_B_BGA1-IC,TBD
GND                      U2D1             AF31     SKX_EXT_B_BGA1-IC,TBD
GND                      U2D1             AF33     SKX_EXT_B_BGA1-IC,TBD
GND                      U2D1             AF37     SKX_EXT_B_BGA1-IC,TBD
GND                      U2D1             AF39     SKX_EXT_B_BGA1-IC,TBD
GND                      U2D1             AF41     SKX_EXT_B_BGA1-IC,TBD
GND                      U2D1             AF73     SKX_EXT_B_BGA1-IC,TBD
GND                      U2D1             AF77     SKX_EXT_B_BGA1-IC,TBD
GND                      U2D1             AF83     SKX_EXT_B_BGA1-IC,TBD
GND                      U2D1             AF85     SKX_EXT_B_BGA1-IC,TBD
GND                      U2D1             AG12     SKX_EXT_B_BGA1-IC,TBD
GND                      U2D1             AG14     SKX_EXT_B_BGA1-IC,TBD
GND                      U2D1             AG18     SKX_EXT_B_BGA1-IC,TBD
GND                      U2D1             AG36     SKX_EXT_B_BGA1-IC,TBD
GND                      U2D1             AG64     SKX_EXT_B_BGA1-IC,TBD
GND                      U2D1             AG70     SKX_EXT_B_BGA1-IC,TBD
GND                      U2D1             AG74     SKX_EXT_B_BGA1-IC,TBD
GND                      U2D1             AG76     SKX_EXT_B_BGA1-IC,TBD
GND                      U2D1             AG78     SKX_EXT_B_BGA1-IC,TBD
GND                      U2D1             AG80     SKX_EXT_B_BGA1-IC,TBD
GND                      U2D1             AH1      SKX_EXT_B_BGA1-IC,TBD
GND                      U2D1             AH5      SKX_EXT_B_BGA1-IC,TBD
GND                      U2D1             AH21     SKX_EXT_B_BGA1-IC,TBD
GND                      U2D1             AH27     SKX_EXT_B_BGA1-IC,TBD
GND                      U2D1             AH33     SKX_EXT_B_BGA1-IC,TBD
GND                      U2D1             AH35     SKX_EXT_B_BGA1-IC,TBD
GND                      U2D1             AH45     SKX_EXT_B_BGA1-IC,TBD
GND                      U2D1             AH47     SKX_EXT_B_BGA1-IC,TBD
GND                      U2D1             AH49     SKX_EXT_B_BGA1-IC,TBD
GND                      U2D1             AH51     SKX_EXT_B_BGA1-IC,TBD
GND                      U2D1             AH53     SKX_EXT_B_BGA1-IC,TBD
GND                      U2D1             AH59     SKX_EXT_B_BGA1-IC,TBD
GND                      U2D1             AH61     SKX_EXT_B_BGA1-IC,TBD
GND                      U2D1             AH65     SKX_EXT_B_BGA1-IC,TBD
GND                      U2D1             AH69     SKX_EXT_B_BGA1-IC,TBD
GND                      U2D1             AH75     SKX_EXT_B_BGA1-IC,TBD
GND                      U2D1             AH77     SKX_EXT_B_BGA1-IC,TBD
GND                      U2D1             AH83     SKX_EXT_B_BGA1-IC,TBD
GND                      U2D1             AJ4      SKX_EXT_B_BGA1-IC,TBD
GND                      U2D1             AJ8      SKX_EXT_B_BGA1-IC,TBD
GND                      U2D1             AJ22     SKX_EXT_B_BGA1-IC,TBD
GND                      U2D1             AJ26     SKX_EXT_B_BGA1-IC,TBD
GND                      U2D1             AJ28     SKX_EXT_B_BGA1-IC,TBD
GND                      U2D1             AJ32     SKX_EXT_B_BGA1-IC,TBD
GND                      U2D1             AJ34     SKX_EXT_B_BGA1-IC,TBD
GND                      U2D1             AJ46     SKX_EXT_B_BGA1-IC,TBD
GND                      U2D1             AJ48     SKX_EXT_B_BGA1-IC,TBD
GND                      U2D1             AJ50     SKX_EXT_B_BGA1-IC,TBD
GND                      U2D1             AJ52     SKX_EXT_B_BGA1-IC,TBD
GND                      U2D1             AJ54     SKX_EXT_B_BGA1-IC,TBD
GND                      U2D1             AJ66     SKX_EXT_B_BGA1-IC,TBD
GND                      U2D1             AJ68     SKX_EXT_B_BGA1-IC,TBD
GND                      U2D1             AJ74     SKX_EXT_B_BGA1-IC,TBD
GND                      U2D1             AJ78     SKX_EXT_B_BGA1-IC,TBD
GND                      U2D1             AJ82     SKX_EXT_B_BGA1-IC,TBD
GND                      U2D1             AJ86     SKX_EXT_B_BGA1-IC,TBD
GND                      U2D1             AK9      SKX_EXT_B_BGA1-IC,TBD
GND                      U2D1             AK13     SKX_EXT_B_BGA1-IC,TBD
GND                      U2D1             AK19     SKX_EXT_B_BGA1-IC,TBD
GND                      U2D1             AK23     SKX_EXT_B_BGA1-IC,TBD
GND                      U2D1             AK25     SKX_EXT_B_BGA1-IC,TBD
GND                      U2D1             AK29     SKX_EXT_B_BGA1-IC,TBD
GND                      U2D1             AK31     SKX_EXT_B_BGA1-IC,TBD
GND                      U2D1             AK33     SKX_EXT_B_BGA1-IC,TBD
GND                      U2D1             AK55     SKX_EXT_B_BGA1-IC,TBD
GND                      U2D1             AK65     SKX_EXT_B_BGA1-IC,TBD
GND                      U2D1             AK67     SKX_EXT_B_BGA1-IC,TBD
GND                      U2D1             AK73     SKX_EXT_B_BGA1-IC,TBD
GND                      U2D1             AK79     SKX_EXT_B_BGA1-IC,TBD
GND                      U2D1             AK81     SKX_EXT_B_BGA1-IC,TBD
GND                      U2D1             AK83     SKX_EXT_B_BGA1-IC,TBD
GND                      U2D1             AK85     SKX_EXT_B_BGA1-IC,TBD
GND                      U2D1             AL4      SKX_EXT_B_BGA1-IC,TBD
GND                      U2D1             AL10     SKX_EXT_B_BGA1-IC,TBD
GND                      U2D1             AL24     SKX_EXT_B_BGA1-IC,TBD
GND                      U2D1             AL30     SKX_EXT_B_BGA1-IC,TBD
GND                      U2D1             AL32     SKX_EXT_B_BGA1-IC,TBD
GND                      U2D1             AL56     SKX_EXT_B_BGA1-IC,TBD
GND                      U2D1             AL64     SKX_EXT_B_BGA1-IC,TBD
GND                      U2D1             AL68     SKX_EXT_B_BGA1-IC,TBD
GND                      U2D1             AL76     SKX_EXT_B_BGA1-IC,TBD
GND                      U2D1             AL78     SKX_EXT_B_BGA1-IC,TBD
GND                      U2D1             AL80     SKX_EXT_B_BGA1-IC,TBD
GND                      U2D1             AL82     SKX_EXT_B_BGA1-IC,TBD
GND                      U2D1             AL86     SKX_EXT_B_BGA1-IC,TBD
GND                      U2D1             AM1      SKX_EXT_B_BGA1-IC,TBD
GND                      U2D1             AM31     SKX_EXT_B_BGA1-IC,TBD
GND                      U2D1             AM57     SKX_EXT_B_BGA1-IC,TBD
GND                      U2D1             AM63     SKX_EXT_B_BGA1-IC,TBD
GND                      U2D1             AM69     SKX_EXT_B_BGA1-IC,TBD
GND                      U2D1             AM73     SKX_EXT_B_BGA1-IC,TBD
GND                      U2D1             AM79     SKX_EXT_B_BGA1-IC,TBD
GND                      U2D1             AM83     SKX_EXT_B_BGA1-IC,TBD
GND                      U2D1             AN2      SKX_EXT_B_BGA1-IC,TBD
GND                      U2D1             AN6      SKX_EXT_B_BGA1-IC,TBD
GND                      U2D1             AN28     SKX_EXT_B_BGA1-IC,TBD
GND                      U2D1             AN58     SKX_EXT_B_BGA1-IC,TBD
GND                      U2D1             AN78     SKX_EXT_B_BGA1-IC,TBD
GND                      U2D1             AP5      SKX_EXT_B_BGA1-IC,TBD
GND                      U2D1             AP9      SKX_EXT_B_BGA1-IC,TBD
GND                      U2D1             AP13     SKX_EXT_B_BGA1-IC,TBD
GND                      U2D1             AP19     SKX_EXT_B_BGA1-IC,TBD
GND                      U2D1             AP31     SKX_EXT_B_BGA1-IC,TBD
GND                      U2D1             AP59     SKX_EXT_B_BGA1-IC,TBD
GND                      U2D1             AP63     SKX_EXT_B_BGA1-IC,TBD
GND                      U2D1             AP65     SKX_EXT_B_BGA1-IC,TBD
GND                      U2D1             AP67     SKX_EXT_B_BGA1-IC,TBD
GND                      U2D1             AP69     SKX_EXT_B_BGA1-IC,TBD
GND                      U2D1             AP73     SKX_EXT_B_BGA1-IC,TBD
GND                      U2D1             AP75     SKX_EXT_B_BGA1-IC,TBD
GND                      U2D1             AP81     SKX_EXT_B_BGA1-IC,TBD
GND                      U2D1             AP83     SKX_EXT_B_BGA1-IC,TBD
GND                      U2D1             AP85     SKX_EXT_B_BGA1-IC,TBD
GND                      U2D1             AR6      SKX_EXT_B_BGA1-IC,TBD
GND                      U2D1             AR10     SKX_EXT_B_BGA1-IC,TBD
GND                      U2D1             AR24     SKX_EXT_B_BGA1-IC,TBD
GND                      U2D1             AR30     SKX_EXT_B_BGA1-IC,TBD
GND                      U2D1             AR60     SKX_EXT_B_BGA1-IC,TBD
GND                      U2D1             AR72     SKX_EXT_B_BGA1-IC,TBD
GND                      U2D1             AR78     SKX_EXT_B_BGA1-IC,TBD
GND                      U2D1             AT15     SKX_EXT_B_BGA1-IC,TBD
GND                      U2D1             AT17     SKX_EXT_B_BGA1-IC,TBD
GND                      U2D1             AT21     SKX_EXT_B_BGA1-IC,TBD
GND                      U2D1             AT27     SKX_EXT_B_BGA1-IC,TBD
GND                      U2D1             AT61     SKX_EXT_B_BGA1-IC,TBD
GND                      U2D1             AT63     SKX_EXT_B_BGA1-IC,TBD
GND                      U2D1             AT69     SKX_EXT_B_BGA1-IC,TBD
GND                      U2D1             AT73     SKX_EXT_B_BGA1-IC,TBD
GND                      U2D1             AT77     SKX_EXT_B_BGA1-IC,TBD
GND                      U2D1             AT83     SKX_EXT_B_BGA1-IC,TBD
GND                      U2D1             AT85     SKX_EXT_B_BGA1-IC,TBD
GND                      U2D1             AU2      SKX_EXT_B_BGA1-IC,TBD
GND                      U2D1             AU6      SKX_EXT_B_BGA1-IC,TBD
GND                      U2D1             AU26     SKX_EXT_B_BGA1-IC,TBD
GND                      U2D1             AU28     SKX_EXT_B_BGA1-IC,TBD
GND                      U2D1             AU62     SKX_EXT_B_BGA1-IC,TBD
GND                      U2D1             AU64     SKX_EXT_B_BGA1-IC,TBD
GND                      U2D1             AU68     SKX_EXT_B_BGA1-IC,TBD
GND                      U2D1             AU74     SKX_EXT_B_BGA1-IC,TBD
GND                      U2D1             AU76     SKX_EXT_B_BGA1-IC,TBD
GND                      U2D1             AU78     SKX_EXT_B_BGA1-IC,TBD
GND                      U2D1             AU80     SKX_EXT_B_BGA1-IC,TBD
GND                      U2D1             AU84     SKX_EXT_B_BGA1-IC,TBD
GND                      U2D1             AU86     SKX_EXT_B_BGA1-IC,TBD
GND                      U2D1             AV1      SKX_EXT_B_BGA1-IC,TBD
GND                      U2D1             AV3      SKX_EXT_B_BGA1-IC,TBD
GND                      U2D1             AV7      SKX_EXT_B_BGA1-IC,TBD
GND                      U2D1             AV11     SKX_EXT_B_BGA1-IC,TBD
GND                      U2D1             AV13     SKX_EXT_B_BGA1-IC,TBD
GND                      U2D1             AV19     SKX_EXT_B_BGA1-IC,TBD
GND                      U2D1             AV23     SKX_EXT_B_BGA1-IC,TBD
GND                      U2D1             AV25     SKX_EXT_B_BGA1-IC,TBD
GND                      U2D1             AV63     SKX_EXT_B_BGA1-IC,TBD
GND                      U2D1             AV65     SKX_EXT_B_BGA1-IC,TBD
GND                      U2D1             AV67     SKX_EXT_B_BGA1-IC,TBD
GND                      U2D1             AV75     SKX_EXT_B_BGA1-IC,TBD
GND                      U2D1             AV83     SKX_EXT_B_BGA1-IC,TBD
GND                      U2D1             AW2      SKX_EXT_B_BGA1-IC,TBD
GND                      U2D1             AW10     SKX_EXT_B_BGA1-IC,TBD
GND                      U2D1             AW62     SKX_EXT_B_BGA1-IC,TBD
GND                      U2D1             AW66     SKX_EXT_B_BGA1-IC,TBD
GND                      U2D1             AW68     SKX_EXT_B_BGA1-IC,TBD
GND                      U2D1             AW70     SKX_EXT_B_BGA1-IC,TBD
GND                      U2D1             AW72     SKX_EXT_B_BGA1-IC,TBD
GND                      U2D1             AW74     SKX_EXT_B_BGA1-IC,TBD
GND                      U2D1             AW78     SKX_EXT_B_BGA1-IC,TBD
GND                      U2D1             AW82     SKX_EXT_B_BGA1-IC,TBD
GND                      U2D1             AW84     SKX_EXT_B_BGA1-IC,TBD
GND                      U2D1             AY5      SKX_EXT_B_BGA1-IC,TBD
GND                      U2D1             AY15     SKX_EXT_B_BGA1-IC,TBD
GND                      U2D1             AY17     SKX_EXT_B_BGA1-IC,TBD
GND                      U2D1             AY21     SKX_EXT_B_BGA1-IC,TBD
GND                      U2D1             AY23     SKX_EXT_B_BGA1-IC,TBD
GND                      U2D1             AY25     SKX_EXT_B_BGA1-IC,TBD
GND                      U2D1             AY63     SKX_EXT_B_BGA1-IC,TBD
GND                      U2D1             AY79     SKX_EXT_B_BGA1-IC,TBD
GND                      U2D1             AY81     SKX_EXT_B_BGA1-IC,TBD
GND                      U2D1             B5       SKX_EXT_B_BGA1-IC,TBD
GND                      U2D1             B9       SKX_EXT_B_BGA1-IC,TBD
GND                      U2D1             B25      SKX_EXT_B_BGA1-IC,TBD
GND                      U2D1             B31      SKX_EXT_B_BGA1-IC,TBD
GND                      U2D1             B37      SKX_EXT_B_BGA1-IC,TBD
GND                      U2D1             B43      SKX_EXT_B_BGA1-IC,TBD
GND                      U2D1             B71      SKX_EXT_B_BGA1-IC,TBD
GND                      U2D1             B75      SKX_EXT_B_BGA1-IC,TBD
GND                      U2D1             B79      SKX_EXT_B_BGA1-IC,TBD
GND                      U2D1             BA2      SKX_EXT_B_BGA1-IC,TBD
GND                      U2D1             BA6      SKX_EXT_B_BGA1-IC,TBD
GND                      U2D1             BA12     SKX_EXT_B_BGA1-IC,TBD
GND                      U2D1             BA62     SKX_EXT_B_BGA1-IC,TBD
GND                      U2D1             BA68     SKX_EXT_B_BGA1-IC,TBD
GND                      U2D1             BA74     SKX_EXT_B_BGA1-IC,TBD
GND                      U2D1             BA80     SKX_EXT_B_BGA1-IC,TBD
GND                      U2D1             BA84     SKX_EXT_B_BGA1-IC,TBD
GND                      U2D1             BB19     SKX_EXT_B_BGA1-IC,TBD
GND                      U2D1             BB23     SKX_EXT_B_BGA1-IC,TBD
GND                      U2D1             BB63     SKX_EXT_B_BGA1-IC,TBD
GND                      U2D1             BB69     SKX_EXT_B_BGA1-IC,TBD
GND                      U2D1             BB73     SKX_EXT_B_BGA1-IC,TBD
GND                      U2D1             BB75     SKX_EXT_B_BGA1-IC,TBD
GND                      U2D1             BB77     SKX_EXT_B_BGA1-IC,TBD
GND                      U2D1             BB79     SKX_EXT_B_BGA1-IC,TBD
GND                      U2D1             BB81     SKX_EXT_B_BGA1-IC,TBD
GND                      U2D1             BB83     SKX_EXT_B_BGA1-IC,TBD
GND                      U2D1             BC4      SKX_EXT_B_BGA1-IC,TBD
GND                      U2D1             BC8      SKX_EXT_B_BGA1-IC,TBD
GND                      U2D1             BC12     SKX_EXT_B_BGA1-IC,TBD
GND                      U2D1             BC16     SKX_EXT_B_BGA1-IC,TBD
GND                      U2D1             BC70     SKX_EXT_B_BGA1-IC,TBD
GND                      U2D1             BC72     SKX_EXT_B_BGA1-IC,TBD
GND                      U2D1             BC74     SKX_EXT_B_BGA1-IC,TBD
GND                      U2D1             BC76     SKX_EXT_B_BGA1-IC,TBD
GND                      U2D1             BC78     SKX_EXT_B_BGA1-IC,TBD
GND                      U2D1             BC80     SKX_EXT_B_BGA1-IC,TBD
GND                      U2D1             BC82     SKX_EXT_B_BGA1-IC,TBD
GND                      U2D1             BD5      SKX_EXT_B_BGA1-IC,TBD
GND                      U2D1             BD11     SKX_EXT_B_BGA1-IC,TBD
GND                      U2D1             BD15     SKX_EXT_B_BGA1-IC,TBD
GND                      U2D1             BD21     SKX_EXT_B_BGA1-IC,TBD
GND                      U2D1             BD27     SKX_EXT_B_BGA1-IC,TBD
GND                      U2D1             BD63     SKX_EXT_B_BGA1-IC,TBD
GND                      U2D1             BD71     SKX_EXT_B_BGA1-IC,TBD
GND                      U2D1             BE4      SKX_EXT_B_BGA1-IC,TBD
GND                      U2D1             BE6      SKX_EXT_B_BGA1-IC,TBD
GND                      U2D1             BE8      SKX_EXT_B_BGA1-IC,TBD
GND                      U2D1             BE10     SKX_EXT_B_BGA1-IC,TBD
GND                      U2D1             BE26     SKX_EXT_B_BGA1-IC,TBD
GND                      U2D1             BE64     SKX_EXT_B_BGA1-IC,TBD
GND                      U2D1             BE66     SKX_EXT_B_BGA1-IC,TBD
GND                      U2D1             BE68     SKX_EXT_B_BGA1-IC,TBD
GND                      U2D1             BE70     SKX_EXT_B_BGA1-IC,TBD
GND                      U2D1             BF9      SKX_EXT_B_BGA1-IC,TBD
GND                      U2D1             BF15     SKX_EXT_B_BGA1-IC,TBD
GND                      U2D1             BF17     SKX_EXT_B_BGA1-IC,TBD
GND                      U2D1             BF19     SKX_EXT_B_BGA1-IC,TBD
GND                      U2D1             BF25     SKX_EXT_B_BGA1-IC,TBD
GND                      U2D1             BF63     SKX_EXT_B_BGA1-IC,TBD
GND                      U2D1             BF65     SKX_EXT_B_BGA1-IC,TBD
GND                      U2D1             BF67     SKX_EXT_B_BGA1-IC,TBD
GND                      U2D1             BF69     SKX_EXT_B_BGA1-IC,TBD
GND                      U2D1             BF71     SKX_EXT_B_BGA1-IC,TBD
GND                      U2D1             BG6      SKX_EXT_B_BGA1-IC,TBD
GND                      U2D1             BG8      SKX_EXT_B_BGA1-IC,TBD
GND                      U2D1             BG10     SKX_EXT_B_BGA1-IC,TBD
GND                      U2D1             BG22     SKX_EXT_B_BGA1-IC,TBD
GND                      U2D1             BG24     SKX_EXT_B_BGA1-IC,TBD
GND                      U2D1             BG72     SKX_EXT_B_BGA1-IC,TBD
GND                      U2D1             BG74     SKX_EXT_B_BGA1-IC,TBD
GND                      U2D1             BG76     SKX_EXT_B_BGA1-IC,TBD
GND                      U2D1             BG78     SKX_EXT_B_BGA1-IC,TBD
GND                      U2D1             BG80     SKX_EXT_B_BGA1-IC,TBD
GND                      U2D1             BG82     SKX_EXT_B_BGA1-IC,TBD
GND                      U2D1             BH7      SKX_EXT_B_BGA1-IC,TBD
GND                      U2D1             BH9      SKX_EXT_B_BGA1-IC,TBD
GND                      U2D1             BH11     SKX_EXT_B_BGA1-IC,TBD
GND                      U2D1             BH15     SKX_EXT_B_BGA1-IC,TBD
GND                      U2D1             BH17     SKX_EXT_B_BGA1-IC,TBD
GND                      U2D1             BH21     SKX_EXT_B_BGA1-IC,TBD
GND                      U2D1             BJ4      SKX_EXT_B_BGA1-IC,TBD
GND                      U2D1             BJ6      SKX_EXT_B_BGA1-IC,TBD
GND                      U2D1             BK3      SKX_EXT_B_BGA1-IC,TBD
GND                      U2D1             BK7      SKX_EXT_B_BGA1-IC,TBD
GND                      U2D1             BK11     SKX_EXT_B_BGA1-IC,TBD
GND                      U2D1             BK19     SKX_EXT_B_BGA1-IC,TBD
GND                      U2D1             BL6      SKX_EXT_B_BGA1-IC,TBD
GND                      U2D1             BL10     SKX_EXT_B_BGA1-IC,TBD
GND                      U2D1             BL12     SKX_EXT_B_BGA1-IC,TBD
GND                      U2D1             BL22     SKX_EXT_B_BGA1-IC,TBD
GND                      U2D1             BL24     SKX_EXT_B_BGA1-IC,TBD
GND                      U2D1             BL64     SKX_EXT_B_BGA1-IC,TBD
GND                      U2D1             BL66     SKX_EXT_B_BGA1-IC,TBD
GND                      U2D1             BL68     SKX_EXT_B_BGA1-IC,TBD
GND                      U2D1             BL70     SKX_EXT_B_BGA1-IC,TBD
GND                      U2D1             BL72     SKX_EXT_B_BGA1-IC,TBD
GND                      U2D1             BL74     SKX_EXT_B_BGA1-IC,TBD
GND                      U2D1             BL76     SKX_EXT_B_BGA1-IC,TBD
GND                      U2D1             BL78     SKX_EXT_B_BGA1-IC,TBD
GND                      U2D1             BL80     SKX_EXT_B_BGA1-IC,TBD
GND                      U2D1             BL82     SKX_EXT_B_BGA1-IC,TBD
GND                      U2D1             BM9      SKX_EXT_B_BGA1-IC,TBD
GND                      U2D1             BM13     SKX_EXT_B_BGA1-IC,TBD
GND                      U2D1             BM15     SKX_EXT_B_BGA1-IC,TBD
GND                      U2D1             BM25     SKX_EXT_B_BGA1-IC,TBD
GND                      U2D1             BN6      SKX_EXT_B_BGA1-IC,TBD
GND                      U2D1             BN10     SKX_EXT_B_BGA1-IC,TBD
GND                      U2D1             BN20     SKX_EXT_B_BGA1-IC,TBD
GND                      U2D1             BN26     SKX_EXT_B_BGA1-IC,TBD
GND                      U2D1             BP3      SKX_EXT_B_BGA1-IC,TBD
GND                      U2D1             BP27     SKX_EXT_B_BGA1-IC,TBD
GND                      U2D1             BR6      SKX_EXT_B_BGA1-IC,TBD
GND                      U2D1             BR10     SKX_EXT_B_BGA1-IC,TBD
GND                      U2D1             BR16     SKX_EXT_B_BGA1-IC,TBD
GND                      U2D1             BR18     SKX_EXT_B_BGA1-IC,TBD
GND                      U2D1             BR26     SKX_EXT_B_BGA1-IC,TBD
GND                      U2D1             BR64     SKX_EXT_B_BGA1-IC,TBD
GND                      U2D1             BR66     SKX_EXT_B_BGA1-IC,TBD
GND                      U2D1             BR68     SKX_EXT_B_BGA1-IC,TBD
GND                      U2D1             BR70     SKX_EXT_B_BGA1-IC,TBD
GND                      U2D1             BR72     SKX_EXT_B_BGA1-IC,TBD
GND                      U2D1             BR74     SKX_EXT_B_BGA1-IC,TBD
GND                      U2D1             BR76     SKX_EXT_B_BGA1-IC,TBD
GND                      U2D1             BR78     SKX_EXT_B_BGA1-IC,TBD
GND                      U2D1             BR80     SKX_EXT_B_BGA1-IC,TBD
GND                      U2D1             BR82     SKX_EXT_B_BGA1-IC,TBD
GND                      U2D1             BT3      SKX_EXT_B_BGA1-IC,TBD
GND                      U2D1             BT5      SKX_EXT_B_BGA1-IC,TBD
GND                      U2D1             BT9      SKX_EXT_B_BGA1-IC,TBD
GND                      U2D1             BT21     SKX_EXT_B_BGA1-IC,TBD
GND                      U2D1             BT23     SKX_EXT_B_BGA1-IC,TBD
GND                      U2D1             BT25     SKX_EXT_B_BGA1-IC,TBD
GND                      U2D1             BU8      SKX_EXT_B_BGA1-IC,TBD
GND                      U2D1             BU10     SKX_EXT_B_BGA1-IC,TBD
GND                      U2D1             BV5      SKX_EXT_B_BGA1-IC,TBD
GND                      U2D1             BV17     SKX_EXT_B_BGA1-IC,TBD
GND                      U2D1             BV25     SKX_EXT_B_BGA1-IC,TBD
GND                      U2D1             BW6      SKX_EXT_B_BGA1-IC,TBD
GND                      U2D1             BW12     SKX_EXT_B_BGA1-IC,TBD
GND                      U2D1             BW14     SKX_EXT_B_BGA1-IC,TBD
GND                      U2D1             BW16     SKX_EXT_B_BGA1-IC,TBD
GND                      U2D1             BW18     SKX_EXT_B_BGA1-IC,TBD
GND                      U2D1             BW26     SKX_EXT_B_BGA1-IC,TBD
GND                      U2D1             BW72     SKX_EXT_B_BGA1-IC,TBD
GND                      U2D1             BW74     SKX_EXT_B_BGA1-IC,TBD
GND                      U2D1             BW76     SKX_EXT_B_BGA1-IC,TBD
GND                      U2D1             BW78     SKX_EXT_B_BGA1-IC,TBD
GND                      U2D1             BW80     SKX_EXT_B_BGA1-IC,TBD
GND                      U2D1             BW82     SKX_EXT_B_BGA1-IC,TBD
GND                      U2D1             BY11     SKX_EXT_B_BGA1-IC,TBD
GND                      U2D1             BY13     SKX_EXT_B_BGA1-IC,TBD
GND                      U2D1             BY15     SKX_EXT_B_BGA1-IC,TBD
GND                      U2D1             BY17     SKX_EXT_B_BGA1-IC,TBD
GND                      U2D1             BY23     SKX_EXT_B_BGA1-IC,TBD
GND                      U2D1             BY63     SKX_EXT_B_BGA1-IC,TBD
GND                      U2D1             BY65     SKX_EXT_B_BGA1-IC,TBD
GND                      U2D1             BY67     SKX_EXT_B_BGA1-IC,TBD
GND                      U2D1             BY69     SKX_EXT_B_BGA1-IC,TBD
GND                      U2D1             BY71     SKX_EXT_B_BGA1-IC,TBD
GND                      U2D1             C4       SKX_EXT_B_BGA1-IC,TBD
GND                      U2D1             C8       SKX_EXT_B_BGA1-IC,TBD
GND                      U2D1             C10      SKX_EXT_B_BGA1-IC,TBD
GND                      U2D1             C12      SKX_EXT_B_BGA1-IC,TBD
GND                      U2D1             C14      SKX_EXT_B_BGA1-IC,TBD
GND                      U2D1             C16      SKX_EXT_B_BGA1-IC,TBD
GND                      U2D1             C76      SKX_EXT_B_BGA1-IC,TBD
GND                      U2D1             C78      SKX_EXT_B_BGA1-IC,TBD
GND                      U2D1             C80      SKX_EXT_B_BGA1-IC,TBD
GND                      U2D1             CA2      SKX_EXT_B_BGA1-IC,TBD
GND                      U2D1             CA6      SKX_EXT_B_BGA1-IC,TBD
GND                      U2D1             CA8      SKX_EXT_B_BGA1-IC,TBD
GND                      U2D1             CA10     SKX_EXT_B_BGA1-IC,TBD
GND                      U2D1             CA14     SKX_EXT_B_BGA1-IC,TBD
GND                      U2D1             CA16     SKX_EXT_B_BGA1-IC,TBD
GND                      U2D1             CA18     SKX_EXT_B_BGA1-IC,TBD
GND                      U2D1             CA20     SKX_EXT_B_BGA1-IC,TBD
GND                      U2D1             CA26     SKX_EXT_B_BGA1-IC,TBD
GND                      U2D1             CA64     SKX_EXT_B_BGA1-IC,TBD
GND                      U2D1             CA66     SKX_EXT_B_BGA1-IC,TBD
GND                      U2D1             CA68     SKX_EXT_B_BGA1-IC,TBD
GND                      U2D1             CA70     SKX_EXT_B_BGA1-IC,TBD
GND                      U2D1             CB7      SKX_EXT_B_BGA1-IC,TBD
GND                      U2D1             CB9      SKX_EXT_B_BGA1-IC,TBD
GND                      U2D1             CB15     SKX_EXT_B_BGA1-IC,TBD
GND                      U2D1             CB27     SKX_EXT_B_BGA1-IC,TBD
GND                      U2D1             CB63     SKX_EXT_B_BGA1-IC,TBD
GND                      U2D1             CB71     SKX_EXT_B_BGA1-IC,TBD
GND                      U2D1             CC4      SKX_EXT_B_BGA1-IC,TBD
GND                      U2D1             CC14     SKX_EXT_B_BGA1-IC,TBD
GND                      U2D1             CC16     SKX_EXT_B_BGA1-IC,TBD
GND                      U2D1             CC18     SKX_EXT_B_BGA1-IC,TBD
GND                      U2D1             CC24     SKX_EXT_B_BGA1-IC,TBD
GND                      U2D1             CC64     SKX_EXT_B_BGA1-IC,TBD
GND                      U2D1             CC72     SKX_EXT_B_BGA1-IC,TBD
GND                      U2D1             CC74     SKX_EXT_B_BGA1-IC,TBD
GND                      U2D1             CC76     SKX_EXT_B_BGA1-IC,TBD
GND                      U2D1             CC78     SKX_EXT_B_BGA1-IC,TBD
GND                      U2D1             CC80     SKX_EXT_B_BGA1-IC,TBD
GND                      U2D1             CC82     SKX_EXT_B_BGA1-IC,TBD
GND                      U2D1             CD5      SKX_EXT_B_BGA1-IC,TBD
GND                      U2D1             CD13     SKX_EXT_B_BGA1-IC,TBD
GND                      U2D1             CD15     SKX_EXT_B_BGA1-IC,TBD
GND                      U2D1             CD17     SKX_EXT_B_BGA1-IC,TBD
GND                      U2D1             CD63     SKX_EXT_B_BGA1-IC,TBD
GND                      U2D1             CD73     SKX_EXT_B_BGA1-IC,TBD
GND                      U2D1             CD75     SKX_EXT_B_BGA1-IC,TBD
GND                      U2D1             CD77     SKX_EXT_B_BGA1-IC,TBD
GND                      U2D1             CD79     SKX_EXT_B_BGA1-IC,TBD
GND                      U2D1             CD81     SKX_EXT_B_BGA1-IC,TBD
GND                      U2D1             CE10     SKX_EXT_B_BGA1-IC,TBD
GND                      U2D1             CE14     SKX_EXT_B_BGA1-IC,TBD
GND                      U2D1             CE16     SKX_EXT_B_BGA1-IC,TBD
GND                      U2D1             CE20     SKX_EXT_B_BGA1-IC,TBD
GND                      U2D1             CE26     SKX_EXT_B_BGA1-IC,TBD
GND                      U2D1             CE62     SKX_EXT_B_BGA1-IC,TBD
GND                      U2D1             CE70     SKX_EXT_B_BGA1-IC,TBD
GND                      U2D1             CE82     SKX_EXT_B_BGA1-IC,TBD
GND                      U2D1             CF9      SKX_EXT_B_BGA1-IC,TBD
GND                      U2D1             CF15     SKX_EXT_B_BGA1-IC,TBD
GND                      U2D1             CF17     SKX_EXT_B_BGA1-IC,TBD
GND                      U2D1             CF63     SKX_EXT_B_BGA1-IC,TBD
GND                      U2D1             CF69     SKX_EXT_B_BGA1-IC,TBD
GND                      U2D1             CF71     SKX_EXT_B_BGA1-IC,TBD
GND                      U2D1             CF77     SKX_EXT_B_BGA1-IC,TBD
GND                      U2D1             CF83     SKX_EXT_B_BGA1-IC,TBD
GND                      U2D1             CG6      SKX_EXT_B_BGA1-IC,TBD
GND                      U2D1             CG16     SKX_EXT_B_BGA1-IC,TBD
GND                      U2D1             CG18     SKX_EXT_B_BGA1-IC,TBD
GND                      U2D1             CG22     SKX_EXT_B_BGA1-IC,TBD
GND                      U2D1             CG62     SKX_EXT_B_BGA1-IC,TBD
GND                      U2D1             CG68     SKX_EXT_B_BGA1-IC,TBD
GND                      U2D1             CG72     SKX_EXT_B_BGA1-IC,TBD
GND                      U2D1             CG80     SKX_EXT_B_BGA1-IC,TBD
GND                      U2D1             CH1      SKX_EXT_B_BGA1-IC,TBD
GND                      U2D1             CH3      SKX_EXT_B_BGA1-IC,TBD
GND                      U2D1             CH15     SKX_EXT_B_BGA1-IC,TBD
GND                      U2D1             CH17     SKX_EXT_B_BGA1-IC,TBD
GND                      U2D1             CH19     SKX_EXT_B_BGA1-IC,TBD
GND                      U2D1             CH63     SKX_EXT_B_BGA1-IC,TBD
GND                      U2D1             CH67     SKX_EXT_B_BGA1-IC,TBD
GND                      U2D1             CH73     SKX_EXT_B_BGA1-IC,TBD
GND                      U2D1             CH79     SKX_EXT_B_BGA1-IC,TBD
GND                      U2D1             CH81     SKX_EXT_B_BGA1-IC,TBD
GND                      U2D1             CH83     SKX_EXT_B_BGA1-IC,TBD
GND                      U2D1             CJ2      SKX_EXT_B_BGA1-IC,TBD
GND                      U2D1             CJ6      SKX_EXT_B_BGA1-IC,TBD
GND                      U2D1             CJ8      SKX_EXT_B_BGA1-IC,TBD
GND                      U2D1             CJ10     SKX_EXT_B_BGA1-IC,TBD
GND                      U2D1             CJ12     SKX_EXT_B_BGA1-IC,TBD
GND                      U2D1             CJ16     SKX_EXT_B_BGA1-IC,TBD
GND                      U2D1             CJ18     SKX_EXT_B_BGA1-IC,TBD
GND                      U2D1             CJ62     SKX_EXT_B_BGA1-IC,TBD
GND                      U2D1             CJ74     SKX_EXT_B_BGA1-IC,TBD
GND                      U2D1             CJ76     SKX_EXT_B_BGA1-IC,TBD
GND                      U2D1             CJ78     SKX_EXT_B_BGA1-IC,TBD
GND                      U2D1             CJ82     SKX_EXT_B_BGA1-IC,TBD
GND                      U2D1             CJ84     SKX_EXT_B_BGA1-IC,TBD
GND                      U2D1             CJ86     SKX_EXT_B_BGA1-IC,TBD
GND                      U2D1             CK11     SKX_EXT_B_BGA1-IC,TBD
GND                      U2D1             CK15     SKX_EXT_B_BGA1-IC,TBD
GND                      U2D1             CK17     SKX_EXT_B_BGA1-IC,TBD
GND                      U2D1             CK21     SKX_EXT_B_BGA1-IC,TBD
GND                      U2D1             CK27     SKX_EXT_B_BGA1-IC,TBD
GND                      U2D1             CK63     SKX_EXT_B_BGA1-IC,TBD
GND                      U2D1             CK65     SKX_EXT_B_BGA1-IC,TBD
GND                      U2D1             CK67     SKX_EXT_B_BGA1-IC,TBD
GND                      U2D1             CK69     SKX_EXT_B_BGA1-IC,TBD
GND                      U2D1             CK71     SKX_EXT_B_BGA1-IC,TBD
GND                      U2D1             CK73     SKX_EXT_B_BGA1-IC,TBD
GND                      U2D1             CK75     SKX_EXT_B_BGA1-IC,TBD
GND                      U2D1             CK83     SKX_EXT_B_BGA1-IC,TBD
GND                      U2D1             CK85     SKX_EXT_B_BGA1-IC,TBD
GND                      U2D1             CL8      SKX_EXT_B_BGA1-IC,TBD
GND                      U2D1             CL14     SKX_EXT_B_BGA1-IC,TBD
GND                      U2D1             CL16     SKX_EXT_B_BGA1-IC,TBD
GND                      U2D1             CL18     SKX_EXT_B_BGA1-IC,TBD
GND                      U2D1             CL22     SKX_EXT_B_BGA1-IC,TBD
GND                      U2D1             CL62     SKX_EXT_B_BGA1-IC,TBD
GND                      U2D1             CL64     SKX_EXT_B_BGA1-IC,TBD
GND                      U2D1             CL66     SKX_EXT_B_BGA1-IC,TBD
GND                      U2D1             CL74     SKX_EXT_B_BGA1-IC,TBD
GND                      U2D1             CL76     SKX_EXT_B_BGA1-IC,TBD
GND                      U2D1             CL78     SKX_EXT_B_BGA1-IC,TBD
GND                      U2D1             CL80     SKX_EXT_B_BGA1-IC,TBD
GND                      U2D1             CM5      SKX_EXT_B_BGA1-IC,TBD
GND                      U2D1             CM19     SKX_EXT_B_BGA1-IC,TBD
GND                      U2D1             CM21     SKX_EXT_B_BGA1-IC,TBD
GND                      U2D1             CM27     SKX_EXT_B_BGA1-IC,TBD
GND                      U2D1             CM29     SKX_EXT_B_BGA1-IC,TBD
GND                      U2D1             CM31     SKX_EXT_B_BGA1-IC,TBD
GND                      U2D1             CM61     SKX_EXT_B_BGA1-IC,TBD
GND                      U2D1             CM63     SKX_EXT_B_BGA1-IC,TBD
GND                      U2D1             CM67     SKX_EXT_B_BGA1-IC,TBD
GND                      U2D1             CM73     SKX_EXT_B_BGA1-IC,TBD
GND                      U2D1             CM77     SKX_EXT_B_BGA1-IC,TBD
GND                      U2D1             CM83     SKX_EXT_B_BGA1-IC,TBD
GND                      U2D1             CM85     SKX_EXT_B_BGA1-IC,TBD
GND                      U2D1             CN2      SKX_EXT_B_BGA1-IC,TBD
GND                      U2D1             CN12     SKX_EXT_B_BGA1-IC,TBD
GND                      U2D1             CN14     SKX_EXT_B_BGA1-IC,TBD
GND                      U2D1             CN18     SKX_EXT_B_BGA1-IC,TBD
GND                      U2D1             CN20     SKX_EXT_B_BGA1-IC,TBD
GND                      U2D1             CN26     SKX_EXT_B_BGA1-IC,TBD
GND                      U2D1             CN32     SKX_EXT_B_BGA1-IC,TBD
GND                      U2D1             CN60     SKX_EXT_B_BGA1-IC,TBD
GND                      U2D1             CN62     SKX_EXT_B_BGA1-IC,TBD
GND                      U2D1             CN68     SKX_EXT_B_BGA1-IC,TBD
GND                      U2D1             CN78     SKX_EXT_B_BGA1-IC,TBD
GND                      U2D1             CP1      SKX_EXT_B_BGA1-IC,TBD
GND                      U2D1             CP19     SKX_EXT_B_BGA1-IC,TBD
GND                      U2D1             CP21     SKX_EXT_B_BGA1-IC,TBD
GND                      U2D1             CP25     SKX_EXT_B_BGA1-IC,TBD
GND                      U2D1             CP59     SKX_EXT_B_BGA1-IC,TBD
GND                      U2D1             CP69     SKX_EXT_B_BGA1-IC,TBD
GND                      U2D1             CP73     SKX_EXT_B_BGA1-IC,TBD
GND                      U2D1             CP75     SKX_EXT_B_BGA1-IC,TBD
GND                      U2D1             CP81     SKX_EXT_B_BGA1-IC,TBD
GND                      U2D1             CP83     SKX_EXT_B_BGA1-IC,TBD
GND                      U2D1             CR6      SKX_EXT_B_BGA1-IC,TBD
GND                      U2D1             CR10     SKX_EXT_B_BGA1-IC,TBD
GND                      U2D1             CR18     SKX_EXT_B_BGA1-IC,TBD
GND                      U2D1             CR20     SKX_EXT_B_BGA1-IC,TBD
GND                      U2D1             CR22     SKX_EXT_B_BGA1-IC,TBD
GND                      U2D1             CR24     SKX_EXT_B_BGA1-IC,TBD
GND                      U2D1             CR32     SKX_EXT_B_BGA1-IC,TBD
GND                      U2D1             CR58     SKX_EXT_B_BGA1-IC,TBD
GND                      U2D1             CR62     SKX_EXT_B_BGA1-IC,TBD
GND                      U2D1             CR64     SKX_EXT_B_BGA1-IC,TBD
GND                      U2D1             CR66     SKX_EXT_B_BGA1-IC,TBD
GND                      U2D1             CR68     SKX_EXT_B_BGA1-IC,TBD
GND                      U2D1             CR78     SKX_EXT_B_BGA1-IC,TBD
GND                      U2D1             CR86     SKX_EXT_B_BGA1-IC,TBD
GND                      U2D1             CT7      SKX_EXT_B_BGA1-IC,TBD
GND                      U2D1             CT13     SKX_EXT_B_BGA1-IC,TBD
GND                      U2D1             CT19     SKX_EXT_B_BGA1-IC,TBD
GND                      U2D1             CT21     SKX_EXT_B_BGA1-IC,TBD
GND                      U2D1             CT27     SKX_EXT_B_BGA1-IC,TBD
GND                      U2D1             CT29     SKX_EXT_B_BGA1-IC,TBD
GND                      U2D1             CT33     SKX_EXT_B_BGA1-IC,TBD
GND                      U2D1             CT35     SKX_EXT_B_BGA1-IC,TBD
GND                      U2D1             CT57     SKX_EXT_B_BGA1-IC,TBD
GND                      U2D1             CT73     SKX_EXT_B_BGA1-IC,TBD
GND                      U2D1             CT79     SKX_EXT_B_BGA1-IC,TBD
GND                      U2D1             CT83     SKX_EXT_B_BGA1-IC,TBD
GND                      U2D1             CT85     SKX_EXT_B_BGA1-IC,TBD
GND                      U2D1             CU4      SKX_EXT_B_BGA1-IC,TBD
GND                      U2D1             CU20     SKX_EXT_B_BGA1-IC,TBD
GND                      U2D1             CU22     SKX_EXT_B_BGA1-IC,TBD
GND                      U2D1             CU28     SKX_EXT_B_BGA1-IC,TBD
GND                      U2D1             CU30     SKX_EXT_B_BGA1-IC,TBD
GND                      U2D1             CU34     SKX_EXT_B_BGA1-IC,TBD
GND                      U2D1             CU36     SKX_EXT_B_BGA1-IC,TBD
GND                      U2D1             CU56     SKX_EXT_B_BGA1-IC,TBD
GND                      U2D1             CU62     SKX_EXT_B_BGA1-IC,TBD
GND                      U2D1             CU68     SKX_EXT_B_BGA1-IC,TBD
GND                      U2D1             CU76     SKX_EXT_B_BGA1-IC,TBD
GND                      U2D1             CU78     SKX_EXT_B_BGA1-IC,TBD
GND                      U2D1             CU80     SKX_EXT_B_BGA1-IC,TBD
GND                      U2D1             CU82     SKX_EXT_B_BGA1-IC,TBD
GND                      U2D1             CU86     SKX_EXT_B_BGA1-IC,TBD
GND                      U2D1             CV1      SKX_EXT_B_BGA1-IC,TBD
GND                      U2D1             CV17     SKX_EXT_B_BGA1-IC,TBD
GND                      U2D1             CV19     SKX_EXT_B_BGA1-IC,TBD
GND                      U2D1             CV25     SKX_EXT_B_BGA1-IC,TBD
GND                      U2D1             CV27     SKX_EXT_B_BGA1-IC,TBD
GND                      U2D1             CV31     SKX_EXT_B_BGA1-IC,TBD
GND                      U2D1             CV33     SKX_EXT_B_BGA1-IC,TBD
GND                      U2D1             CV37     SKX_EXT_B_BGA1-IC,TBD
GND                      U2D1             CV39     SKX_EXT_B_BGA1-IC,TBD
GND                      U2D1             CV41     SKX_EXT_B_BGA1-IC,TBD
GND                      U2D1             CV53     SKX_EXT_B_BGA1-IC,TBD
GND                      U2D1             CV55     SKX_EXT_B_BGA1-IC,TBD
GND                      U2D1             CV63     SKX_EXT_B_BGA1-IC,TBD
GND                      U2D1             CV67     SKX_EXT_B_BGA1-IC,TBD
GND                      U2D1             CV73     SKX_EXT_B_BGA1-IC,TBD
GND                      U2D1             CV79     SKX_EXT_B_BGA1-IC,TBD
GND                      U2D1             CV81     SKX_EXT_B_BGA1-IC,TBD
GND                      U2D1             CV83     SKX_EXT_B_BGA1-IC,TBD
GND                      U2D1             CW6      SKX_EXT_B_BGA1-IC,TBD
GND                      U2D1             CW12     SKX_EXT_B_BGA1-IC,TBD
GND                      U2D1             CW18     SKX_EXT_B_BGA1-IC,TBD
GND                      U2D1             CW20     SKX_EXT_B_BGA1-IC,TBD
GND                      U2D1             CW26     SKX_EXT_B_BGA1-IC,TBD
GND                      U2D1             CW32     SKX_EXT_B_BGA1-IC,TBD
GND                      U2D1             CW38     SKX_EXT_B_BGA1-IC,TBD
GND                      U2D1             CW40     SKX_EXT_B_BGA1-IC,TBD
GND                      U2D1             CW42     SKX_EXT_B_BGA1-IC,TBD
GND                      U2D1             CW52     SKX_EXT_B_BGA1-IC,TBD
GND                      U2D1             CW54     SKX_EXT_B_BGA1-IC,TBD
GND                      U2D1             CW64     SKX_EXT_B_BGA1-IC,TBD
GND                      U2D1             CW66     SKX_EXT_B_BGA1-IC,TBD
GND                      U2D1             CW68     SKX_EXT_B_BGA1-IC,TBD
GND                      U2D1             CW74     SKX_EXT_B_BGA1-IC,TBD
GND                      U2D1             CW78     SKX_EXT_B_BGA1-IC,TBD
GND                      U2D1             CW82     SKX_EXT_B_BGA1-IC,TBD
GND                      U2D1             CY1      SKX_EXT_B_BGA1-IC,TBD
GND                      U2D1             CY9      SKX_EXT_B_BGA1-IC,TBD
GND                      U2D1             CY13     SKX_EXT_B_BGA1-IC,TBD
GND                      U2D1             CY15     SKX_EXT_B_BGA1-IC,TBD
GND                      U2D1             CY19     SKX_EXT_B_BGA1-IC,TBD
GND                      U2D1             CY21     SKX_EXT_B_BGA1-IC,TBD
GND                      U2D1             CY41     SKX_EXT_B_BGA1-IC,TBD
GND                      U2D1             CY45     SKX_EXT_B_BGA1-IC,TBD
GND                      U2D1             CY51     SKX_EXT_B_BGA1-IC,TBD
GND                      U2D1             CY59     SKX_EXT_B_BGA1-IC,TBD
GND                      U2D1             CY61     SKX_EXT_B_BGA1-IC,TBD
GND                      U2D1             CY65     SKX_EXT_B_BGA1-IC,TBD
GND                      U2D1             CY69     SKX_EXT_B_BGA1-IC,TBD
GND                      U2D1             CY75     SKX_EXT_B_BGA1-IC,TBD
GND                      U2D1             CY77     SKX_EXT_B_BGA1-IC,TBD
GND                      U2D1             CY83     SKX_EXT_B_BGA1-IC,TBD
GND                      U2D1             CY85     SKX_EXT_B_BGA1-IC,TBD
GND                      U2D1             D3       SKX_EXT_B_BGA1-IC,TBD
GND                      U2D1             D11      SKX_EXT_B_BGA1-IC,TBD
GND                      U2D1             D13      SKX_EXT_B_BGA1-IC,TBD
GND                      U2D1             D25      SKX_EXT_B_BGA1-IC,TBD
GND                      U2D1             D27      SKX_EXT_B_BGA1-IC,TBD
GND                      U2D1             D29      SKX_EXT_B_BGA1-IC,TBD
GND                      U2D1             D31      SKX_EXT_B_BGA1-IC,TBD
GND                      U2D1             D33      SKX_EXT_B_BGA1-IC,TBD
GND                      U2D1             D35      SKX_EXT_B_BGA1-IC,TBD
GND                      U2D1             D37      SKX_EXT_B_BGA1-IC,TBD
GND                      U2D1             D39      SKX_EXT_B_BGA1-IC,TBD
GND                      U2D1             D41      SKX_EXT_B_BGA1-IC,TBD
GND                      U2D1             D43      SKX_EXT_B_BGA1-IC,TBD
GND                      U2D1             D77      SKX_EXT_B_BGA1-IC,TBD
GND                      U2D1             D81      SKX_EXT_B_BGA1-IC,TBD
GND                      U2D1             DA6      SKX_EXT_B_BGA1-IC,TBD
GND                      U2D1             DA18     SKX_EXT_B_BGA1-IC,TBD
GND                      U2D1             DA20     SKX_EXT_B_BGA1-IC,TBD
GND                      U2D1             DA22     SKX_EXT_B_BGA1-IC,TBD
GND                      U2D1             DA26     SKX_EXT_B_BGA1-IC,TBD
GND                      U2D1             DA28     SKX_EXT_B_BGA1-IC,TBD
GND                      U2D1             DA30     SKX_EXT_B_BGA1-IC,TBD
GND                      U2D1             DA32     SKX_EXT_B_BGA1-IC,TBD
GND                      U2D1             DA34     SKX_EXT_B_BGA1-IC,TBD
GND                      U2D1             DA36     SKX_EXT_B_BGA1-IC,TBD
GND                      U2D1             DA38     SKX_EXT_B_BGA1-IC,TBD
GND                      U2D1             DA44     SKX_EXT_B_BGA1-IC,TBD
GND                      U2D1             DA46     SKX_EXT_B_BGA1-IC,TBD
GND                      U2D1             DA48     SKX_EXT_B_BGA1-IC,TBD
GND                      U2D1             DA50     SKX_EXT_B_BGA1-IC,TBD
GND                      U2D1             DA64     SKX_EXT_B_BGA1-IC,TBD
GND                      U2D1             DA70     SKX_EXT_B_BGA1-IC,TBD
GND                      U2D1             DA74     SKX_EXT_B_BGA1-IC,TBD
GND                      U2D1             DA76     SKX_EXT_B_BGA1-IC,TBD
GND                      U2D1             DA78     SKX_EXT_B_BGA1-IC,TBD
GND                      U2D1             DA80     SKX_EXT_B_BGA1-IC,TBD
GND                      U2D1             DB3      SKX_EXT_B_BGA1-IC,TBD
GND                      U2D1             DB7      SKX_EXT_B_BGA1-IC,TBD
GND                      U2D1             DB13     SKX_EXT_B_BGA1-IC,TBD
GND                      U2D1             DB17     SKX_EXT_B_BGA1-IC,TBD
GND                      U2D1             DB19     SKX_EXT_B_BGA1-IC,TBD
GND                      U2D1             DB21     SKX_EXT_B_BGA1-IC,TBD
GND                      U2D1             DB23     SKX_EXT_B_BGA1-IC,TBD
GND                      U2D1             DB25     SKX_EXT_B_BGA1-IC,TBD
GND                      U2D1             DB39     SKX_EXT_B_BGA1-IC,TBD
GND                      U2D1             DB41     SKX_EXT_B_BGA1-IC,TBD
GND                      U2D1             DB47     SKX_EXT_B_BGA1-IC,TBD
GND                      U2D1             DB49     SKX_EXT_B_BGA1-IC,TBD
GND                      U2D1             DB73     SKX_EXT_B_BGA1-IC,TBD
GND                      U2D1             DB77     SKX_EXT_B_BGA1-IC,TBD
GND                      U2D1             DB83     SKX_EXT_B_BGA1-IC,TBD
GND                      U2D1             DB85     SKX_EXT_B_BGA1-IC,TBD
GND                      U2D1             DC14     SKX_EXT_B_BGA1-IC,TBD
GND                      U2D1             DC20     SKX_EXT_B_BGA1-IC,TBD
GND                      U2D1             DC22     SKX_EXT_B_BGA1-IC,TBD
GND                      U2D1             DC24     SKX_EXT_B_BGA1-IC,TBD
GND                      U2D1             DC26     SKX_EXT_B_BGA1-IC,TBD
GND                      U2D1             DC32     SKX_EXT_B_BGA1-IC,TBD
GND                      U2D1             DC38     SKX_EXT_B_BGA1-IC,TBD
GND                      U2D1             DC42     SKX_EXT_B_BGA1-IC,TBD
GND                      U2D1             DC64     SKX_EXT_B_BGA1-IC,TBD
GND                      U2D1             DC66     SKX_EXT_B_BGA1-IC,TBD
GND                      U2D1             DC68     SKX_EXT_B_BGA1-IC,TBD
GND                      U2D1             DC70     SKX_EXT_B_BGA1-IC,TBD
GND                      U2D1             DC78     SKX_EXT_B_BGA1-IC,TBD
GND                      U2D1             DC84     SKX_EXT_B_BGA1-IC,TBD
GND                      U2D1             DC86     SKX_EXT_B_BGA1-IC,TBD
GND                      U2D1             DD11     SKX_EXT_B_BGA1-IC,TBD
GND                      U2D1             DD19     SKX_EXT_B_BGA1-IC,TBD
GND                      U2D1             DD21     SKX_EXT_B_BGA1-IC,TBD
GND                      U2D1             DD23     SKX_EXT_B_BGA1-IC,TBD
GND                      U2D1             DD27     SKX_EXT_B_BGA1-IC,TBD
GND                      U2D1             DD31     SKX_EXT_B_BGA1-IC,TBD
GND                      U2D1             DD33     SKX_EXT_B_BGA1-IC,TBD
GND                      U2D1             DD37     SKX_EXT_B_BGA1-IC,TBD
GND                      U2D1             DD71     SKX_EXT_B_BGA1-IC,TBD
GND                      U2D1             DD73     SKX_EXT_B_BGA1-IC,TBD
GND                      U2D1             DD75     SKX_EXT_B_BGA1-IC,TBD
GND                      U2D1             DD81     SKX_EXT_B_BGA1-IC,TBD
GND                      U2D1             DD83     SKX_EXT_B_BGA1-IC,TBD
GND                      U2D1             DE6      SKX_EXT_B_BGA1-IC,TBD
GND                      U2D1             DE8      SKX_EXT_B_BGA1-IC,TBD
GND                      U2D1             DE18     SKX_EXT_B_BGA1-IC,TBD
GND                      U2D1             DE20     SKX_EXT_B_BGA1-IC,TBD
GND                      U2D1             DE22     SKX_EXT_B_BGA1-IC,TBD
GND                      U2D1             DE24     SKX_EXT_B_BGA1-IC,TBD
GND                      U2D1             DE28     SKX_EXT_B_BGA1-IC,TBD
GND                      U2D1             DE30     SKX_EXT_B_BGA1-IC,TBD
GND                      U2D1             DE34     SKX_EXT_B_BGA1-IC,TBD
GND                      U2D1             DE36     SKX_EXT_B_BGA1-IC,TBD
GND                      U2D1             DE48     SKX_EXT_B_BGA1-IC,TBD
GND                      U2D1             DE50     SKX_EXT_B_BGA1-IC,TBD
GND                      U2D1             DE52     SKX_EXT_B_BGA1-IC,TBD
GND                      U2D1             DE54     SKX_EXT_B_BGA1-IC,TBD
GND                      U2D1             DE56     SKX_EXT_B_BGA1-IC,TBD
GND                      U2D1             DE58     SKX_EXT_B_BGA1-IC,TBD
GND                      U2D1             DE60     SKX_EXT_B_BGA1-IC,TBD
GND                      U2D1             DE62     SKX_EXT_B_BGA1-IC,TBD
GND                      U2D1             DE64     SKX_EXT_B_BGA1-IC,TBD
GND                      U2D1             DE70     SKX_EXT_B_BGA1-IC,TBD
GND                      U2D1             DE72     SKX_EXT_B_BGA1-IC,TBD
GND                      U2D1             DE78     SKX_EXT_B_BGA1-IC,TBD
GND                      U2D1             DF5      SKX_EXT_B_BGA1-IC,TBD
GND                      U2D1             DF7      SKX_EXT_B_BGA1-IC,TBD
GND                      U2D1             DF19     SKX_EXT_B_BGA1-IC,TBD
GND                      U2D1             DF23     SKX_EXT_B_BGA1-IC,TBD
GND                      U2D1             DF29     SKX_EXT_B_BGA1-IC,TBD
GND                      U2D1             DF35     SKX_EXT_B_BGA1-IC,TBD
GND                      U2D1             DF37     SKX_EXT_B_BGA1-IC,TBD
GND                      U2D1             DF39     SKX_EXT_B_BGA1-IC,TBD
GND                      U2D1             DF41     SKX_EXT_B_BGA1-IC,TBD
GND                      U2D1             DF65     SKX_EXT_B_BGA1-IC,TBD
GND                      U2D1             DF69     SKX_EXT_B_BGA1-IC,TBD
GND                      U2D1             DF73     SKX_EXT_B_BGA1-IC,TBD
GND                      U2D1             DF79     SKX_EXT_B_BGA1-IC,TBD
GND                      U2D1             DF83     SKX_EXT_B_BGA1-IC,TBD
GND                      U2D1             DF85     SKX_EXT_B_BGA1-IC,TBD
GND                      U2D1             DG2      SKX_EXT_B_BGA1-IC,TBD
GND                      U2D1             DG14     SKX_EXT_B_BGA1-IC,TBD
GND                      U2D1             DG16     SKX_EXT_B_BGA1-IC,TBD
GND                      U2D1             DG22     SKX_EXT_B_BGA1-IC,TBD
GND                      U2D1             DG24     SKX_EXT_B_BGA1-IC,TBD
GND                      U2D1             DG66     SKX_EXT_B_BGA1-IC,TBD
GND                      U2D1             DG68     SKX_EXT_B_BGA1-IC,TBD
GND                      U2D1             DG76     SKX_EXT_B_BGA1-IC,TBD
GND                      U2D1             DG78     SKX_EXT_B_BGA1-IC,TBD
GND                      U2D1             DG80     SKX_EXT_B_BGA1-IC,TBD
GND                      U2D1             DG82     SKX_EXT_B_BGA1-IC,TBD
GND                      U2D1             DH13     SKX_EXT_B_BGA1-IC,TBD
GND                      U2D1             DH15     SKX_EXT_B_BGA1-IC,TBD
GND                      U2D1             DH21     SKX_EXT_B_BGA1-IC,TBD
GND                      U2D1             DH23     SKX_EXT_B_BGA1-IC,TBD
GND                      U2D1             DH25     SKX_EXT_B_BGA1-IC,TBD
GND                      U2D1             DH27     SKX_EXT_B_BGA1-IC,TBD
GND                      U2D1             DH29     SKX_EXT_B_BGA1-IC,TBD
GND                      U2D1             DH31     SKX_EXT_B_BGA1-IC,TBD
GND                      U2D1             DH33     SKX_EXT_B_BGA1-IC,TBD
GND                      U2D1             DH35     SKX_EXT_B_BGA1-IC,TBD
GND                      U2D1             DH37     SKX_EXT_B_BGA1-IC,TBD
GND                      U2D1             DH41     SKX_EXT_B_BGA1-IC,TBD
GND                      U2D1             DH67     SKX_EXT_B_BGA1-IC,TBD
GND                      U2D1             DH71     SKX_EXT_B_BGA1-IC,TBD
GND                      U2D1             DH73     SKX_EXT_B_BGA1-IC,TBD
GND                      U2D1             DH79     SKX_EXT_B_BGA1-IC,TBD
GND                      U2D1             DH81     SKX_EXT_B_BGA1-IC,TBD
GND                      U2D1             DH83     SKX_EXT_B_BGA1-IC,TBD
GND                      U2D1             DJ2      SKX_EXT_B_BGA1-IC,TBD
GND                      U2D1             DJ10     SKX_EXT_B_BGA1-IC,TBD
GND                      U2D1             DJ22     SKX_EXT_B_BGA1-IC,TBD
GND                      U2D1             DJ38     SKX_EXT_B_BGA1-IC,TBD
GND                      U2D1             DJ42     SKX_EXT_B_BGA1-IC,TBD
GND                      U2D1             DJ68     SKX_EXT_B_BGA1-IC,TBD
GND                      U2D1             DJ74     SKX_EXT_B_BGA1-IC,TBD
GND                      U2D1             DJ78     SKX_EXT_B_BGA1-IC,TBD
GND                      U2D1             DJ82     SKX_EXT_B_BGA1-IC,TBD
GND                      U2D1             DJ84     SKX_EXT_B_BGA1-IC,TBD
GND                      U2D1             DK7      SKX_EXT_B_BGA1-IC,TBD
GND                      U2D1             DK23     SKX_EXT_B_BGA1-IC,TBD
GND                      U2D1             DK29     SKX_EXT_B_BGA1-IC,TBD
GND                      U2D1             DK35     SKX_EXT_B_BGA1-IC,TBD
GND                      U2D1             DK39     SKX_EXT_B_BGA1-IC,TBD
GND                      U2D1             DK41     SKX_EXT_B_BGA1-IC,TBD
GND                      U2D1             DK73     SKX_EXT_B_BGA1-IC,TBD
GND                      U2D1             DK75     SKX_EXT_B_BGA1-IC,TBD
GND                      U2D1             DK77     SKX_EXT_B_BGA1-IC,TBD
GND                      U2D1             DK83     SKX_EXT_B_BGA1-IC,TBD
GND                      U2D1             DK85     SKX_EXT_B_BGA1-IC,TBD
GND                      U2D1             DL4      SKX_EXT_B_BGA1-IC,TBD
GND                      U2D1             DL8      SKX_EXT_B_BGA1-IC,TBD
GND                      U2D1             DL16     SKX_EXT_B_BGA1-IC,TBD
GND                      U2D1             DL18     SKX_EXT_B_BGA1-IC,TBD
GND                      U2D1             DL22     SKX_EXT_B_BGA1-IC,TBD
GND                      U2D1             DL24     SKX_EXT_B_BGA1-IC,TBD
GND                      U2D1             DL28     SKX_EXT_B_BGA1-IC,TBD
GND                      U2D1             DL30     SKX_EXT_B_BGA1-IC,TBD
GND                      U2D1             DL34     SKX_EXT_B_BGA1-IC,TBD
GND                      U2D1             DL36     SKX_EXT_B_BGA1-IC,TBD
GND                      U2D1             DL40     SKX_EXT_B_BGA1-IC,TBD
GND                      U2D1             DL68     SKX_EXT_B_BGA1-IC,TBD
GND                      U2D1             DL70     SKX_EXT_B_BGA1-IC,TBD
GND                      U2D1             DL74     SKX_EXT_B_BGA1-IC,TBD
GND                      U2D1             DL76     SKX_EXT_B_BGA1-IC,TBD
GND                      U2D1             DL78     SKX_EXT_B_BGA1-IC,TBD
GND                      U2D1             DL80     SKX_EXT_B_BGA1-IC,TBD
GND                      U2D1             DM15     SKX_EXT_B_BGA1-IC,TBD
GND                      U2D1             DM19     SKX_EXT_B_BGA1-IC,TBD
GND                      U2D1             DM25     SKX_EXT_B_BGA1-IC,TBD
GND                      U2D1             DM27     SKX_EXT_B_BGA1-IC,TBD
GND                      U2D1             DM31     SKX_EXT_B_BGA1-IC,TBD
GND                      U2D1             DM33     SKX_EXT_B_BGA1-IC,TBD
GND                      U2D1             DM37     SKX_EXT_B_BGA1-IC,TBD
GND                      U2D1             DM39     SKX_EXT_B_BGA1-IC,TBD
GND                      U2D1             DM65     SKX_EXT_B_BGA1-IC,TBD
GND                      U2D1             DM73     SKX_EXT_B_BGA1-IC,TBD
GND                      U2D1             DM77     SKX_EXT_B_BGA1-IC,TBD
GND                      U2D1             DM83     SKX_EXT_B_BGA1-IC,TBD
GND                      U2D1             DN2      SKX_EXT_B_BGA1-IC,TBD
GND                      U2D1             DN12     SKX_EXT_B_BGA1-IC,TBD
GND                      U2D1             DN18     SKX_EXT_B_BGA1-IC,TBD
GND                      U2D1             DN22     SKX_EXT_B_BGA1-IC,TBD
GND                      U2D1             DN26     SKX_EXT_B_BGA1-IC,TBD
GND                      U2D1             DN32     SKX_EXT_B_BGA1-IC,TBD
GND                      U2D1             DN38     SKX_EXT_B_BGA1-IC,TBD
GND                      U2D1             DN44     SKX_EXT_B_BGA1-IC,TBD
GND                      U2D1             DN68     SKX_EXT_B_BGA1-IC,TBD
GND                      U2D1             DN72     SKX_EXT_B_BGA1-IC,TBD
GND                      U2D1             DN78     SKX_EXT_B_BGA1-IC,TBD
GND                      U2D1             DP9      SKX_EXT_B_BGA1-IC,TBD
GND                      U2D1             DP45     SKX_EXT_B_BGA1-IC,TBD
GND                      U2D1             DP47     SKX_EXT_B_BGA1-IC,TBD
GND                      U2D1             DP49     SKX_EXT_B_BGA1-IC,TBD
GND                      U2D1             DP51     SKX_EXT_B_BGA1-IC,TBD
GND                      U2D1             DP53     SKX_EXT_B_BGA1-IC,TBD
GND                      U2D1             DP55     SKX_EXT_B_BGA1-IC,TBD
GND                      U2D1             DP57     SKX_EXT_B_BGA1-IC,TBD
GND                      U2D1             DP59     SKX_EXT_B_BGA1-IC,TBD
GND                      U2D1             DP61     SKX_EXT_B_BGA1-IC,TBD
GND                      U2D1             DP63     SKX_EXT_B_BGA1-IC,TBD
GND                      U2D1             DP67     SKX_EXT_B_BGA1-IC,TBD
GND                      U2D1             DP69     SKX_EXT_B_BGA1-IC,TBD
GND                      U2D1             DP71     SKX_EXT_B_BGA1-IC,TBD
GND                      U2D1             DP81     SKX_EXT_B_BGA1-IC,TBD
GND                      U2D1             DP83     SKX_EXT_B_BGA1-IC,TBD
GND                      U2D1             DR6      SKX_EXT_B_BGA1-IC,TBD
GND                      U2D1             DR20     SKX_EXT_B_BGA1-IC,TBD
GND                      U2D1             DR22     SKX_EXT_B_BGA1-IC,TBD
GND                      U2D1             DR24     SKX_EXT_B_BGA1-IC,TBD
GND                      U2D1             DR26     SKX_EXT_B_BGA1-IC,TBD
GND                      U2D1             DR28     SKX_EXT_B_BGA1-IC,TBD
GND                      U2D1             DR30     SKX_EXT_B_BGA1-IC,TBD
GND                      U2D1             DR32     SKX_EXT_B_BGA1-IC,TBD
GND                      U2D1             DR34     SKX_EXT_B_BGA1-IC,TBD
GND                      U2D1             DR36     SKX_EXT_B_BGA1-IC,TBD
GND                      U2D1             DR38     SKX_EXT_B_BGA1-IC,TBD
GND                      U2D1             DR40     SKX_EXT_B_BGA1-IC,TBD
GND                      U2D1             DR42     SKX_EXT_B_BGA1-IC,TBD
GND                      U2D1             DR66     SKX_EXT_B_BGA1-IC,TBD
GND                      U2D1             DR68     SKX_EXT_B_BGA1-IC,TBD
GND                      U2D1             DR70     SKX_EXT_B_BGA1-IC,TBD
GND                      U2D1             DR72     SKX_EXT_B_BGA1-IC,TBD
GND                      U2D1             DR74     SKX_EXT_B_BGA1-IC,TBD
GND                      U2D1             DR76     SKX_EXT_B_BGA1-IC,TBD
GND                      U2D1             DR78     SKX_EXT_B_BGA1-IC,TBD
GND                      U2D1             DT3      SKX_EXT_B_BGA1-IC,TBD
GND                      U2D1             DT17     SKX_EXT_B_BGA1-IC,TBD
GND                      U2D1             DT65     SKX_EXT_B_BGA1-IC,TBD
GND                      U2D1             DT69     SKX_EXT_B_BGA1-IC,TBD
GND                      U2D1             DT79     SKX_EXT_B_BGA1-IC,TBD
GND                      U2D1             DT83     SKX_EXT_B_BGA1-IC,TBD
GND                      U2D1             DT85     SKX_EXT_B_BGA1-IC,TBD
GND                      U2D1             DU10     SKX_EXT_B_BGA1-IC,TBD
GND                      U2D1             DU14     SKX_EXT_B_BGA1-IC,TBD
GND                      U2D1             DU22     SKX_EXT_B_BGA1-IC,TBD
GND                      U2D1             DU26     SKX_EXT_B_BGA1-IC,TBD
GND                      U2D1             DU32     SKX_EXT_B_BGA1-IC,TBD
GND                      U2D1             DU38     SKX_EXT_B_BGA1-IC,TBD
GND                      U2D1             DU70     SKX_EXT_B_BGA1-IC,TBD
GND                      U2D1             DU72     SKX_EXT_B_BGA1-IC,TBD
GND                      U2D1             DU78     SKX_EXT_B_BGA1-IC,TBD
GND                      U2D1             DU80     SKX_EXT_B_BGA1-IC,TBD
GND                      U2D1             DU82     SKX_EXT_B_BGA1-IC,TBD
GND                      U2D1             DU84     SKX_EXT_B_BGA1-IC,TBD
GND                      U2D1             DV19     SKX_EXT_B_BGA1-IC,TBD
GND                      U2D1             DV21     SKX_EXT_B_BGA1-IC,TBD
GND                      U2D1             DV25     SKX_EXT_B_BGA1-IC,TBD
GND                      U2D1             DV27     SKX_EXT_B_BGA1-IC,TBD
GND                      U2D1             DV31     SKX_EXT_B_BGA1-IC,TBD
GND                      U2D1             DV33     SKX_EXT_B_BGA1-IC,TBD
GND                      U2D1             DV37     SKX_EXT_B_BGA1-IC,TBD
GND                      U2D1             DV39     SKX_EXT_B_BGA1-IC,TBD
GND                      U2D1             DV73     SKX_EXT_B_BGA1-IC,TBD
GND                      U2D1             DV77     SKX_EXT_B_BGA1-IC,TBD
GND                      U2D1             DV81     SKX_EXT_B_BGA1-IC,TBD
GND                      U2D1             DW2      SKX_EXT_B_BGA1-IC,TBD
GND                      U2D1             DW8      SKX_EXT_B_BGA1-IC,TBD
GND                      U2D1             DW12     SKX_EXT_B_BGA1-IC,TBD
GND                      U2D1             DW20     SKX_EXT_B_BGA1-IC,TBD
GND                      U2D1             DW24     SKX_EXT_B_BGA1-IC,TBD
GND                      U2D1             DW28     SKX_EXT_B_BGA1-IC,TBD
GND                      U2D1             DW30     SKX_EXT_B_BGA1-IC,TBD
GND                      U2D1             DW34     SKX_EXT_B_BGA1-IC,TBD
GND                      U2D1             DW36     SKX_EXT_B_BGA1-IC,TBD
GND                      U2D1             DW40     SKX_EXT_B_BGA1-IC,TBD
GND                      U2D1             DW64     SKX_EXT_B_BGA1-IC,TBD
GND                      U2D1             DW66     SKX_EXT_B_BGA1-IC,TBD
GND                      U2D1             DW68     SKX_EXT_B_BGA1-IC,TBD
GND                      U2D1             DW70     SKX_EXT_B_BGA1-IC,TBD
GND                      U2D1             DW72     SKX_EXT_B_BGA1-IC,TBD
GND                      U2D1             DW74     SKX_EXT_B_BGA1-IC,TBD
GND                      U2D1             DW76     SKX_EXT_B_BGA1-IC,TBD
GND                      U2D1             DW82     SKX_EXT_B_BGA1-IC,TBD
GND                      U2D1             DW84     SKX_EXT_B_BGA1-IC,TBD
GND                      U2D1             DY5      SKX_EXT_B_BGA1-IC,TBD
GND                      U2D1             DY19     SKX_EXT_B_BGA1-IC,TBD
GND                      U2D1             DY23     SKX_EXT_B_BGA1-IC,TBD
GND                      U2D1             DY29     SKX_EXT_B_BGA1-IC,TBD
GND                      U2D1             DY35     SKX_EXT_B_BGA1-IC,TBD
GND                      U2D1             DY41     SKX_EXT_B_BGA1-IC,TBD
GND                      U2D1             DY45     SKX_EXT_B_BGA1-IC,TBD
GND                      U2D1             DY47     SKX_EXT_B_BGA1-IC,TBD
GND                      U2D1             DY49     SKX_EXT_B_BGA1-IC,TBD
GND                      U2D1             DY51     SKX_EXT_B_BGA1-IC,TBD
GND                      U2D1             DY53     SKX_EXT_B_BGA1-IC,TBD
GND                      U2D1             DY55     SKX_EXT_B_BGA1-IC,TBD
GND                      U2D1             DY57     SKX_EXT_B_BGA1-IC,TBD
GND                      U2D1             DY59     SKX_EXT_B_BGA1-IC,TBD
GND                      U2D1             DY61     SKX_EXT_B_BGA1-IC,TBD
GND                      U2D1             DY63     SKX_EXT_B_BGA1-IC,TBD
GND                      U2D1             DY71     SKX_EXT_B_BGA1-IC,TBD
GND                      U2D1             DY75     SKX_EXT_B_BGA1-IC,TBD
GND                      U2D1             DY85     SKX_EXT_B_BGA1-IC,TBD
GND                      U2D1             E6       SKX_EXT_B_BGA1-IC,TBD
GND                      U2D1             E8       SKX_EXT_B_BGA1-IC,TBD
GND                      U2D1             E16      SKX_EXT_B_BGA1-IC,TBD
GND                      U2D1             E18      SKX_EXT_B_BGA1-IC,TBD
GND                      U2D1             E20      SKX_EXT_B_BGA1-IC,TBD
GND                      U2D1             E22      SKX_EXT_B_BGA1-IC,TBD
GND                      U2D1             E66      SKX_EXT_B_BGA1-IC,TBD
GND                      U2D1             E72      SKX_EXT_B_BGA1-IC,TBD
GND                      U2D1             E74      SKX_EXT_B_BGA1-IC,TBD
GND                      U2D1             E76      SKX_EXT_B_BGA1-IC,TBD
GND                      U2D1             E82      SKX_EXT_B_BGA1-IC,TBD
GND                      U2D1             EA6      SKX_EXT_B_BGA1-IC,TBD
GND                      U2D1             EA14     SKX_EXT_B_BGA1-IC,TBD
GND                      U2D1             EA16     SKX_EXT_B_BGA1-IC,TBD
GND                      U2D1             EA20     SKX_EXT_B_BGA1-IC,TBD
GND                      U2D1             EA22     SKX_EXT_B_BGA1-IC,TBD
GND                      U2D1             EA42     SKX_EXT_B_BGA1-IC,TBD
GND                      U2D1             EA64     SKX_EXT_B_BGA1-IC,TBD
GND                      U2D1             EA70     SKX_EXT_B_BGA1-IC,TBD
GND                      U2D1             EA76     SKX_EXT_B_BGA1-IC,TBD
GND                      U2D1             EA78     SKX_EXT_B_BGA1-IC,TBD
GND                      U2D1             EA80     SKX_EXT_B_BGA1-IC,TBD
GND                      U2D1             EA82     SKX_EXT_B_BGA1-IC,TBD
GND                      U2D1             EA84     SKX_EXT_B_BGA1-IC,TBD
GND                      U2D1             EB13     SKX_EXT_B_BGA1-IC,TBD
GND                      U2D1             EB23     SKX_EXT_B_BGA1-IC,TBD
GND                      U2D1             EB25     SKX_EXT_B_BGA1-IC,TBD
GND                      U2D1             EB27     SKX_EXT_B_BGA1-IC,TBD
GND                      U2D1             EB29     SKX_EXT_B_BGA1-IC,TBD
GND                      U2D1             EB31     SKX_EXT_B_BGA1-IC,TBD
GND                      U2D1             EB33     SKX_EXT_B_BGA1-IC,TBD
GND                      U2D1             EB35     SKX_EXT_B_BGA1-IC,TBD
GND                      U2D1             EB37     SKX_EXT_B_BGA1-IC,TBD
GND                      U2D1             EB39     SKX_EXT_B_BGA1-IC,TBD
GND                      U2D1             EB41     SKX_EXT_B_BGA1-IC,TBD
GND                      U2D1             EB65     SKX_EXT_B_BGA1-IC,TBD
GND                      U2D1             EB69     SKX_EXT_B_BGA1-IC,TBD
GND                      U2D1             EB83     SKX_EXT_B_BGA1-IC,TBD
GND                      U2D1             EC6      SKX_EXT_B_BGA1-IC,TBD
GND                      U2D1             EC10     SKX_EXT_B_BGA1-IC,TBD
GND                      U2D1             EC42     SKX_EXT_B_BGA1-IC,TBD
GND                      U2D1             EC70     SKX_EXT_B_BGA1-IC,TBD
GND                      U2D1             EC72     SKX_EXT_B_BGA1-IC,TBD
GND                      U2D1             EC74     SKX_EXT_B_BGA1-IC,TBD
GND                      U2D1             EC76     SKX_EXT_B_BGA1-IC,TBD
GND                      U2D1             EC82     SKX_EXT_B_BGA1-IC,TBD
GND                      U2D1             ED7      SKX_EXT_B_BGA1-IC,TBD
GND                      U2D1             ED11     SKX_EXT_B_BGA1-IC,TBD
GND                      U2D1             ED15     SKX_EXT_B_BGA1-IC,TBD
GND                      U2D1             ED23     SKX_EXT_B_BGA1-IC,TBD
GND                      U2D1             ED29     SKX_EXT_B_BGA1-IC,TBD
GND                      U2D1             ED35     SKX_EXT_B_BGA1-IC,TBD
GND                      U2D1             ED41     SKX_EXT_B_BGA1-IC,TBD
GND                      U2D1             ED69     SKX_EXT_B_BGA1-IC,TBD
GND                      U2D1             ED77     SKX_EXT_B_BGA1-IC,TBD
GND                      U2D1             ED81     SKX_EXT_B_BGA1-IC,TBD
GND                      U2D1             EE8      SKX_EXT_B_BGA1-IC,TBD
GND                      U2D1             EE24     SKX_EXT_B_BGA1-IC,TBD
GND                      U2D1             EE28     SKX_EXT_B_BGA1-IC,TBD
GND                      U2D1             EE30     SKX_EXT_B_BGA1-IC,TBD
GND                      U2D1             EE34     SKX_EXT_B_BGA1-IC,TBD
GND                      U2D1             EE36     SKX_EXT_B_BGA1-IC,TBD
GND                      U2D1             EE40     SKX_EXT_B_BGA1-IC,TBD
GND                      U2D1             EE70     SKX_EXT_B_BGA1-IC,TBD
GND                      U2D1             EE76     SKX_EXT_B_BGA1-IC,TBD
GND                      U2D1             EE78     SKX_EXT_B_BGA1-IC,TBD
GND                      U2D1             EE80     SKX_EXT_B_BGA1-IC,TBD
GND                      U2D1             EF71     SKX_EXT_B_BGA1-IC,TBD
GND                      U2D1             EF75     SKX_EXT_B_BGA1-IC,TBD
GND                      U2D1             EF79     SKX_EXT_B_BGA1-IC,TBD
GND                      U2D1             F5       SKX_EXT_B_BGA1-IC,TBD
GND                      U2D1             F17      SKX_EXT_B_BGA1-IC,TBD
GND                      U2D1             F19      SKX_EXT_B_BGA1-IC,TBD
GND                      U2D1             F25      SKX_EXT_B_BGA1-IC,TBD
GND                      U2D1             F31      SKX_EXT_B_BGA1-IC,TBD
GND                      U2D1             F37      SKX_EXT_B_BGA1-IC,TBD
GND                      U2D1             F43      SKX_EXT_B_BGA1-IC,TBD
GND                      U2D1             F67      SKX_EXT_B_BGA1-IC,TBD
GND                      U2D1             F69      SKX_EXT_B_BGA1-IC,TBD
GND                      U2D1             G4       SKX_EXT_B_BGA1-IC,TBD
GND                      U2D1             G8       SKX_EXT_B_BGA1-IC,TBD
GND                      U2D1             G22      SKX_EXT_B_BGA1-IC,TBD
GND                      U2D1             G24      SKX_EXT_B_BGA1-IC,TBD
GND                      U2D1             G26      SKX_EXT_B_BGA1-IC,TBD
GND                      U2D1             G30      SKX_EXT_B_BGA1-IC,TBD
GND                      U2D1             G32      SKX_EXT_B_BGA1-IC,TBD
GND                      U2D1             G36      SKX_EXT_B_BGA1-IC,TBD
GND                      U2D1             G38      SKX_EXT_B_BGA1-IC,TBD
GND                      U2D1             G42      SKX_EXT_B_BGA1-IC,TBD
GND                      U2D1             G66      SKX_EXT_B_BGA1-IC,TBD
GND                      U2D1             G70      SKX_EXT_B_BGA1-IC,TBD
GND                      U2D1             G76      SKX_EXT_B_BGA1-IC,TBD
GND                      U2D1             G78      SKX_EXT_B_BGA1-IC,TBD
GND                      U2D1             G80      SKX_EXT_B_BGA1-IC,TBD
GND                      U2D1             G82      SKX_EXT_B_BGA1-IC,TBD
GND                      U2D1             H3       SKX_EXT_B_BGA1-IC,TBD
GND                      U2D1             H11      SKX_EXT_B_BGA1-IC,TBD
GND                      U2D1             H25      SKX_EXT_B_BGA1-IC,TBD
GND                      U2D1             H27      SKX_EXT_B_BGA1-IC,TBD
GND                      U2D1             H29      SKX_EXT_B_BGA1-IC,TBD
GND                      U2D1             H31      SKX_EXT_B_BGA1-IC,TBD
GND                      U2D1             H33      SKX_EXT_B_BGA1-IC,TBD
GND                      U2D1             H35      SKX_EXT_B_BGA1-IC,TBD
GND                      U2D1             H37      SKX_EXT_B_BGA1-IC,TBD
GND                      U2D1             H39      SKX_EXT_B_BGA1-IC,TBD
GND                      U2D1             H41      SKX_EXT_B_BGA1-IC,TBD
GND                      U2D1             H45      SKX_EXT_B_BGA1-IC,TBD
GND                      U2D1             H47      SKX_EXT_B_BGA1-IC,TBD
GND                      U2D1             H49      SKX_EXT_B_BGA1-IC,TBD
GND                      U2D1             H51      SKX_EXT_B_BGA1-IC,TBD
GND                      U2D1             H53      SKX_EXT_B_BGA1-IC,TBD
GND                      U2D1             H55      SKX_EXT_B_BGA1-IC,TBD
GND                      U2D1             H57      SKX_EXT_B_BGA1-IC,TBD
GND                      U2D1             H59      SKX_EXT_B_BGA1-IC,TBD
GND                      U2D1             H61      SKX_EXT_B_BGA1-IC,TBD
GND                      U2D1             H63      SKX_EXT_B_BGA1-IC,TBD
GND                      U2D1             H65      SKX_EXT_B_BGA1-IC,TBD
GND                      U2D1             H71      SKX_EXT_B_BGA1-IC,TBD
GND                      U2D1             H75      SKX_EXT_B_BGA1-IC,TBD
GND                      U2D1             J4       SKX_EXT_B_BGA1-IC,TBD
GND                      U2D1             J12      SKX_EXT_B_BGA1-IC,TBD
GND                      U2D1             J14      SKX_EXT_B_BGA1-IC,TBD
GND                      U2D1             J16      SKX_EXT_B_BGA1-IC,TBD
GND                      U2D1             J22      SKX_EXT_B_BGA1-IC,TBD
GND                      U2D1             J26      SKX_EXT_B_BGA1-IC,TBD
GND                      U2D1             J28      SKX_EXT_B_BGA1-IC,TBD
GND                      U2D1             J32      SKX_EXT_B_BGA1-IC,TBD
GND                      U2D1             J34      SKX_EXT_B_BGA1-IC,TBD
GND                      U2D1             J38      SKX_EXT_B_BGA1-IC,TBD
GND                      U2D1             J40      SKX_EXT_B_BGA1-IC,TBD
GND                      U2D1             J72      SKX_EXT_B_BGA1-IC,TBD
GND                      U2D1             J74      SKX_EXT_B_BGA1-IC,TBD
GND                      U2D1             J76      SKX_EXT_B_BGA1-IC,TBD
GND                      U2D1             J82      SKX_EXT_B_BGA1-IC,TBD
GND                      U2D1             J84      SKX_EXT_B_BGA1-IC,TBD
GND                      U2D1             J86      SKX_EXT_B_BGA1-IC,TBD
GND                      U2D1             K1       SKX_EXT_B_BGA1-IC,TBD
GND                      U2D1             K11      SKX_EXT_B_BGA1-IC,TBD
GND                      U2D1             K13      SKX_EXT_B_BGA1-IC,TBD
GND                      U2D1             K17      SKX_EXT_B_BGA1-IC,TBD
GND                      U2D1             K27      SKX_EXT_B_BGA1-IC,TBD
GND                      U2D1             K33      SKX_EXT_B_BGA1-IC,TBD
GND                      U2D1             K39      SKX_EXT_B_BGA1-IC,TBD
GND                      U2D1             K65      SKX_EXT_B_BGA1-IC,TBD
GND                      U2D1             K67      SKX_EXT_B_BGA1-IC,TBD
GND                      U2D1             K69      SKX_EXT_B_BGA1-IC,TBD
GND                      U2D1             K71      SKX_EXT_B_BGA1-IC,TBD
GND                      U2D1             K73      SKX_EXT_B_BGA1-IC,TBD
GND                      U2D1             K77      SKX_EXT_B_BGA1-IC,TBD
GND                      U2D1             K81      SKX_EXT_B_BGA1-IC,TBD
GND                      U2D1             K83      SKX_EXT_B_BGA1-IC,TBD
GND                      U2D1             K85      SKX_EXT_B_BGA1-IC,TBD
GND                      U2D1             L2       SKX_EXT_B_BGA1-IC,TBD
GND                      U2D1             L6       SKX_EXT_B_BGA1-IC,TBD
GND                      U2D1             L8       SKX_EXT_B_BGA1-IC,TBD
GND                      U2D1             L10      SKX_EXT_B_BGA1-IC,TBD
GND                      U2D1             L20      SKX_EXT_B_BGA1-IC,TBD
GND                      U2D1             L22      SKX_EXT_B_BGA1-IC,TBD
GND                      U2D1             L72      SKX_EXT_B_BGA1-IC,TBD
GND                      U2D1             L78      SKX_EXT_B_BGA1-IC,TBD
GND                      U2D1             L80      SKX_EXT_B_BGA1-IC,TBD
GND                      U2D1             L82      SKX_EXT_B_BGA1-IC,TBD
GND                      U2D1             M15      SKX_EXT_B_BGA1-IC,TBD
GND                      U2D1             M17      SKX_EXT_B_BGA1-IC,TBD
GND                      U2D1             M19      SKX_EXT_B_BGA1-IC,TBD
GND                      U2D1             M23      SKX_EXT_B_BGA1-IC,TBD
GND                      U2D1             M25      SKX_EXT_B_BGA1-IC,TBD
GND                      U2D1             M27      SKX_EXT_B_BGA1-IC,TBD
GND                      U2D1             M29      SKX_EXT_B_BGA1-IC,TBD
GND                      U2D1             M31      SKX_EXT_B_BGA1-IC,TBD
GND                      U2D1             M33      SKX_EXT_B_BGA1-IC,TBD
GND                      U2D1             M35      SKX_EXT_B_BGA1-IC,TBD
GND                      U2D1             M37      SKX_EXT_B_BGA1-IC,TBD
GND                      U2D1             M39      SKX_EXT_B_BGA1-IC,TBD
GND                      U2D1             M41      SKX_EXT_B_BGA1-IC,TBD
GND                      U2D1             M43      SKX_EXT_B_BGA1-IC,TBD
GND                      U2D1             M65      SKX_EXT_B_BGA1-IC,TBD
GND                      U2D1             M71      SKX_EXT_B_BGA1-IC,TBD
GND                      U2D1             M79      SKX_EXT_B_BGA1-IC,TBD
GND                      U2D1             M83      SKX_EXT_B_BGA1-IC,TBD
GND                      U2D1             M85      SKX_EXT_B_BGA1-IC,TBD
GND                      U2D1             N4       SKX_EXT_B_BGA1-IC,TBD
GND                      U2D1             N6       SKX_EXT_B_BGA1-IC,TBD
GND                      U2D1             N8       SKX_EXT_B_BGA1-IC,TBD
GND                      U2D1             N20      SKX_EXT_B_BGA1-IC,TBD
GND                      U2D1             N22      SKX_EXT_B_BGA1-IC,TBD
GND                      U2D1             N66      SKX_EXT_B_BGA1-IC,TBD
GND                      U2D1             N70      SKX_EXT_B_BGA1-IC,TBD
GND                      U2D1             N72      SKX_EXT_B_BGA1-IC,TBD
GND                      U2D1             N74      SKX_EXT_B_BGA1-IC,TBD
GND                      U2D1             N76      SKX_EXT_B_BGA1-IC,TBD
GND                      U2D1             N78      SKX_EXT_B_BGA1-IC,TBD
GND                      U2D1             P11      SKX_EXT_B_BGA1-IC,TBD
GND                      U2D1             P15      SKX_EXT_B_BGA1-IC,TBD
GND                      U2D1             P27      SKX_EXT_B_BGA1-IC,TBD
GND                      U2D1             P33      SKX_EXT_B_BGA1-IC,TBD
GND                      U2D1             P39      SKX_EXT_B_BGA1-IC,TBD
GND                      U2D1             P45      SKX_EXT_B_BGA1-IC,TBD
GND                      U2D1             P47      SKX_EXT_B_BGA1-IC,TBD
GND                      U2D1             P49      SKX_EXT_B_BGA1-IC,TBD
GND                      U2D1             P51      SKX_EXT_B_BGA1-IC,TBD
GND                      U2D1             P53      SKX_EXT_B_BGA1-IC,TBD
GND                      U2D1             P55      SKX_EXT_B_BGA1-IC,TBD
GND                      U2D1             P57      SKX_EXT_B_BGA1-IC,TBD
GND                      U2D1             P59      SKX_EXT_B_BGA1-IC,TBD
GND                      U2D1             P61      SKX_EXT_B_BGA1-IC,TBD
GND                      U2D1             P63      SKX_EXT_B_BGA1-IC,TBD
GND                      U2D1             P67      SKX_EXT_B_BGA1-IC,TBD
GND                      U2D1             P69      SKX_EXT_B_BGA1-IC,TBD
GND                      U2D1             P71      SKX_EXT_B_BGA1-IC,TBD
GND                      U2D1             P81      SKX_EXT_B_BGA1-IC,TBD
GND                      U2D1             P83      SKX_EXT_B_BGA1-IC,TBD
GND                      U2D1             R2       SKX_EXT_B_BGA1-IC,TBD
GND                      U2D1             R4       SKX_EXT_B_BGA1-IC,TBD
GND                      U2D1             R14      SKX_EXT_B_BGA1-IC,TBD
GND                      U2D1             R18      SKX_EXT_B_BGA1-IC,TBD
GND                      U2D1             R22      SKX_EXT_B_BGA1-IC,TBD
GND                      U2D1             R26      SKX_EXT_B_BGA1-IC,TBD
GND                      U2D1             R28      SKX_EXT_B_BGA1-IC,TBD
GND                      U2D1             R32      SKX_EXT_B_BGA1-IC,TBD
GND                      U2D1             R34      SKX_EXT_B_BGA1-IC,TBD
GND                      U2D1             R38      SKX_EXT_B_BGA1-IC,TBD
GND                      U2D1             R40      SKX_EXT_B_BGA1-IC,TBD
GND                      U2D1             R68      SKX_EXT_B_BGA1-IC,TBD
GND                      U2D1             R72      SKX_EXT_B_BGA1-IC,TBD
GND                      U2D1             R78      SKX_EXT_B_BGA1-IC,TBD
GND                      U2D1             R86      SKX_EXT_B_BGA1-IC,TBD
GND                      U2D1             T13      SKX_EXT_B_BGA1-IC,TBD
GND                      U2D1             T17      SKX_EXT_B_BGA1-IC,TBD
GND                      U2D1             T25      SKX_EXT_B_BGA1-IC,TBD
GND                      U2D1             T29      SKX_EXT_B_BGA1-IC,TBD
GND                      U2D1             T31      SKX_EXT_B_BGA1-IC,TBD
GND                      U2D1             T35      SKX_EXT_B_BGA1-IC,TBD
GND                      U2D1             T37      SKX_EXT_B_BGA1-IC,TBD
GND                      U2D1             T41      SKX_EXT_B_BGA1-IC,TBD
GND                      U2D1             T65      SKX_EXT_B_BGA1-IC,TBD
GND                      U2D1             T73      SKX_EXT_B_BGA1-IC,TBD
GND                      U2D1             T77      SKX_EXT_B_BGA1-IC,TBD
GND                      U2D1             T83      SKX_EXT_B_BGA1-IC,TBD
GND                      U2D1             T85      SKX_EXT_B_BGA1-IC,TBD
GND                      U2D1             U2       SKX_EXT_B_BGA1-IC,TBD
GND                      U2D1             U4       SKX_EXT_B_BGA1-IC,TBD
GND                      U2D1             U6       SKX_EXT_B_BGA1-IC,TBD
GND                      U2D1             U20      SKX_EXT_B_BGA1-IC,TBD
GND                      U2D1             U22      SKX_EXT_B_BGA1-IC,TBD
GND                      U2D1             U24      SKX_EXT_B_BGA1-IC,TBD
GND                      U2D1             U30      SKX_EXT_B_BGA1-IC,TBD
GND                      U2D1             U36      SKX_EXT_B_BGA1-IC,TBD
GND                      U2D1             U42      SKX_EXT_B_BGA1-IC,TBD
GND                      U2D1             U68      SKX_EXT_B_BGA1-IC,TBD
GND                      U2D1             U70      SKX_EXT_B_BGA1-IC,TBD
GND                      U2D1             U74      SKX_EXT_B_BGA1-IC,TBD
GND                      U2D1             U76      SKX_EXT_B_BGA1-IC,TBD
GND                      U2D1             U78      SKX_EXT_B_BGA1-IC,TBD
GND                      U2D1             U80      SKX_EXT_B_BGA1-IC,TBD
GND                      U2D1             U86      SKX_EXT_B_BGA1-IC,TBD
GND                      U2D1             V1       SKX_EXT_B_BGA1-IC,TBD
GND                      U2D1             V5       SKX_EXT_B_BGA1-IC,TBD
GND                      U2D1             V9       SKX_EXT_B_BGA1-IC,TBD
GND                      U2D1             V11      SKX_EXT_B_BGA1-IC,TBD
GND                      U2D1             V13      SKX_EXT_B_BGA1-IC,TBD
GND                      U2D1             V15      SKX_EXT_B_BGA1-IC,TBD
GND                      U2D1             V21      SKX_EXT_B_BGA1-IC,TBD
GND                      U2D1             V23      SKX_EXT_B_BGA1-IC,TBD
GND                      U2D1             V43      SKX_EXT_B_BGA1-IC,TBD
GND                      U2D1             V73      SKX_EXT_B_BGA1-IC,TBD
GND                      U2D1             V75      SKX_EXT_B_BGA1-IC,TBD
GND                      U2D1             V77      SKX_EXT_B_BGA1-IC,TBD
GND                      U2D1             V83      SKX_EXT_B_BGA1-IC,TBD
GND                      U2D1             W8       SKX_EXT_B_BGA1-IC,TBD
GND                      U2D1             W12      SKX_EXT_B_BGA1-IC,TBD
GND                      U2D1             W22      SKX_EXT_B_BGA1-IC,TBD
GND                      U2D1             W24      SKX_EXT_B_BGA1-IC,TBD
GND                      U2D1             W26      SKX_EXT_B_BGA1-IC,TBD
GND                      U2D1             W28      SKX_EXT_B_BGA1-IC,TBD
GND                      U2D1             W30      SKX_EXT_B_BGA1-IC,TBD
GND                      U2D1             W32      SKX_EXT_B_BGA1-IC,TBD
GND                      U2D1             W34      SKX_EXT_B_BGA1-IC,TBD
GND                      U2D1             W36      SKX_EXT_B_BGA1-IC,TBD
GND                      U2D1             W38      SKX_EXT_B_BGA1-IC,TBD
GND                      U2D1             W40      SKX_EXT_B_BGA1-IC,TBD
GND                      U2D1             W42      SKX_EXT_B_BGA1-IC,TBD
GND                      U2D1             W68      SKX_EXT_B_BGA1-IC,TBD
GND                      U2D1             W74      SKX_EXT_B_BGA1-IC,TBD
GND                      U2D1             W78      SKX_EXT_B_BGA1-IC,TBD
GND                      U2D1             W82      SKX_EXT_B_BGA1-IC,TBD
GND                      U2D1             Y5       SKX_EXT_B_BGA1-IC,TBD
GND                      U2D1             Y7       SKX_EXT_B_BGA1-IC,TBD
GND                      U2D1             Y9       SKX_EXT_B_BGA1-IC,TBD
GND                      U2D1             Y15      SKX_EXT_B_BGA1-IC,TBD
GND                      U2D1             Y17      SKX_EXT_B_BGA1-IC,TBD
GND                      U2D1             Y67      SKX_EXT_B_BGA1-IC,TBD
GND                      U2D1             Y71      SKX_EXT_B_BGA1-IC,TBD
GND                      U2D1             Y73      SKX_EXT_B_BGA1-IC,TBD
GND                      U2D1             Y79      SKX_EXT_B_BGA1-IC,TBD
GND                      U2D1             Y81      SKX_EXT_B_BGA1-IC,TBD
GND                      U2D1             Y83      SKX_EXT_B_BGA1-IC,TBD
GND                      U2D1             Y85      SKX_EXT_B_BGA1-IC,TBD
GND                      U2M1             2        NC7SB3157_SMLF-IC,C99406-001
GND                      U2T1             8        PI3B3257A_TSSOPLF-IC,E16801-001
GND                      U2T1             15       PI3B3257A_TSSOPLF-IC,E16801-001
GND                      U2T4             7        GTL2014_SM-IC,D66151-001
GND                      U2T4             8        GTL2014_SM-IC,D66151-001
GND                      U2T4             11       GTL2014_SM-IC,D66151-001
GND                      U3P1             7        GTL2014_SM-IC,D66151-001
GND                      U3P1             8        GTL2014_SM-IC,D66151-001
GND                      U3P1             11       GTL2014_SM-IC,D66151-001
GND                      U3P2             7        GTL2014_SM-IC,D66151-001
GND                      U3P2             8        GTL2014_SM-IC,D66151-001
GND                      U3P2             11       GTL2014_SM-IC,D66151-001
GND                      U3T1             10       W25Q256_XSOI-IC,H25002-001
GND                      U4B1             1        MAX9634_SOT-IC,H35789-001
GND                      U4B1             2        MAX9634_SOT-IC,H35789-001
GND                      U4C1             1        ADM4073_SM-EMPTY,G12194-001
GND                      U4C1             2        ADM4073_SM-EMPTY,G12194-001
GND                      U4C2             7        GTL2014_SM-IC,D66151-001
GND                      U4C2             8        GTL2014_SM-IC,D66151-001
GND                      U4C2             11       GTL2014_SM-IC,D66151-001
GND                      U4F1             1        MAX9634_SOT-IC,H35789-001
GND                      U4F1             2        MAX9634_SOT-IC,H35789-001
GND                      U5D1             A26      SKX_EXT_B_BGA1-IC,TBD
GND                      U5D1             A30      SKX_EXT_B_BGA1-IC,TBD
GND                      U5D1             A32      SKX_EXT_B_BGA1-IC,TBD
GND                      U5D1             A36      SKX_EXT_B_BGA1-IC,TBD
GND                      U5D1             A38      SKX_EXT_B_BGA1-IC,TBD
GND                      U5D1             A42      SKX_EXT_B_BGA1-IC,TBD
GND                      U5D1             AA4      SKX_EXT_B_BGA1-IC,TBD
GND                      U5D1             AA16     SKX_EXT_B_BGA1-IC,TBD
GND                      U5D1             AA18     SKX_EXT_B_BGA1-IC,TBD
GND                      U5D1             AA22     SKX_EXT_B_BGA1-IC,TBD
GND                      U5D1             AA24     SKX_EXT_B_BGA1-IC,TBD
GND                      U5D1             AA30     SKX_EXT_B_BGA1-IC,TBD
GND                      U5D1             AA36     SKX_EXT_B_BGA1-IC,TBD
GND                      U5D1             AA42     SKX_EXT_B_BGA1-IC,TBD
GND                      U5D1             AA64     SKX_EXT_B_BGA1-IC,TBD
GND                      U5D1             AA66     SKX_EXT_B_BGA1-IC,TBD
GND                      U5D1             AA68     SKX_EXT_B_BGA1-IC,TBD
GND                      U5D1             AA76     SKX_EXT_B_BGA1-IC,TBD
GND                      U5D1             AA78     SKX_EXT_B_BGA1-IC,TBD
GND                      U5D1             AA80     SKX_EXT_B_BGA1-IC,TBD
GND                      U5D1             AA82     SKX_EXT_B_BGA1-IC,TBD
GND                      U5D1             AB1      SKX_EXT_B_BGA1-IC,TBD
GND                      U5D1             AB5      SKX_EXT_B_BGA1-IC,TBD
GND                      U5D1             AB11     SKX_EXT_B_BGA1-IC,TBD
GND                      U5D1             AB21     SKX_EXT_B_BGA1-IC,TBD
GND                      U5D1             AB23     SKX_EXT_B_BGA1-IC,TBD
GND                      U5D1             AB25     SKX_EXT_B_BGA1-IC,TBD
GND                      U5D1             AB29     SKX_EXT_B_BGA1-IC,TBD
GND                      U5D1             AB31     SKX_EXT_B_BGA1-IC,TBD
GND                      U5D1             AB35     SKX_EXT_B_BGA1-IC,TBD
GND                      U5D1             AB37     SKX_EXT_B_BGA1-IC,TBD
GND                      U5D1             AB41     SKX_EXT_B_BGA1-IC,TBD
GND                      U5D1             AB65     SKX_EXT_B_BGA1-IC,TBD
GND                      U5D1             AB69     SKX_EXT_B_BGA1-IC,TBD
GND                      U5D1             AB73     SKX_EXT_B_BGA1-IC,TBD
GND                      U5D1             AB79     SKX_EXT_B_BGA1-IC,TBD
GND                      U5D1             AB83     SKX_EXT_B_BGA1-IC,TBD
GND                      U5D1             AB85     SKX_EXT_B_BGA1-IC,TBD
GND                      U5D1             AC18     SKX_EXT_B_BGA1-IC,TBD
GND                      U5D1             AC22     SKX_EXT_B_BGA1-IC,TBD
GND                      U5D1             AC26     SKX_EXT_B_BGA1-IC,TBD
GND                      U5D1             AC28     SKX_EXT_B_BGA1-IC,TBD
GND                      U5D1             AC32     SKX_EXT_B_BGA1-IC,TBD
GND                      U5D1             AC34     SKX_EXT_B_BGA1-IC,TBD
GND                      U5D1             AC38     SKX_EXT_B_BGA1-IC,TBD
GND                      U5D1             AC40     SKX_EXT_B_BGA1-IC,TBD
GND                      U5D1             AC48     SKX_EXT_B_BGA1-IC,TBD
GND                      U5D1             AC50     SKX_EXT_B_BGA1-IC,TBD
GND                      U5D1             AC52     SKX_EXT_B_BGA1-IC,TBD
GND                      U5D1             AC54     SKX_EXT_B_BGA1-IC,TBD
GND                      U5D1             AC56     SKX_EXT_B_BGA1-IC,TBD
GND                      U5D1             AC58     SKX_EXT_B_BGA1-IC,TBD
GND                      U5D1             AC60     SKX_EXT_B_BGA1-IC,TBD
GND                      U5D1             AC62     SKX_EXT_B_BGA1-IC,TBD
GND                      U5D1             AC64     SKX_EXT_B_BGA1-IC,TBD
GND                      U5D1             AC70     SKX_EXT_B_BGA1-IC,TBD
GND                      U5D1             AC72     SKX_EXT_B_BGA1-IC,TBD
GND                      U5D1             AC78     SKX_EXT_B_BGA1-IC,TBD
GND                      U5D1             AC84     SKX_EXT_B_BGA1-IC,TBD
GND                      U5D1             AC86     SKX_EXT_B_BGA1-IC,TBD
GND                      U5D1             AD3      SKX_EXT_B_BGA1-IC,TBD
GND                      U5D1             AD7      SKX_EXT_B_BGA1-IC,TBD
GND                      U5D1             AD9      SKX_EXT_B_BGA1-IC,TBD
GND                      U5D1             AD11     SKX_EXT_B_BGA1-IC,TBD
GND                      U5D1             AD13     SKX_EXT_B_BGA1-IC,TBD
GND                      U5D1             AD15     SKX_EXT_B_BGA1-IC,TBD
GND                      U5D1             AD19     SKX_EXT_B_BGA1-IC,TBD
GND                      U5D1             AD21     SKX_EXT_B_BGA1-IC,TBD
GND                      U5D1             AD27     SKX_EXT_B_BGA1-IC,TBD
GND                      U5D1             AD33     SKX_EXT_B_BGA1-IC,TBD
GND                      U5D1             AD39     SKX_EXT_B_BGA1-IC,TBD
GND                      U5D1             AD43     SKX_EXT_B_BGA1-IC,TBD
GND                      U5D1             AD71     SKX_EXT_B_BGA1-IC,TBD
GND                      U5D1             AD73     SKX_EXT_B_BGA1-IC,TBD
GND                      U5D1             AD75     SKX_EXT_B_BGA1-IC,TBD
GND                      U5D1             AD81     SKX_EXT_B_BGA1-IC,TBD
GND                      U5D1             AD83     SKX_EXT_B_BGA1-IC,TBD
GND                      U5D1             AD85     SKX_EXT_B_BGA1-IC,TBD
GND                      U5D1             AE4      SKX_EXT_B_BGA1-IC,TBD
GND                      U5D1             AE8      SKX_EXT_B_BGA1-IC,TBD
GND                      U5D1             AE16     SKX_EXT_B_BGA1-IC,TBD
GND                      U5D1             AE38     SKX_EXT_B_BGA1-IC,TBD
GND                      U5D1             AE40     SKX_EXT_B_BGA1-IC,TBD
GND                      U5D1             AE42     SKX_EXT_B_BGA1-IC,TBD
GND                      U5D1             AE64     SKX_EXT_B_BGA1-IC,TBD
GND                      U5D1             AE66     SKX_EXT_B_BGA1-IC,TBD
GND                      U5D1             AE68     SKX_EXT_B_BGA1-IC,TBD
GND                      U5D1             AE70     SKX_EXT_B_BGA1-IC,TBD
GND                      U5D1             AE78     SKX_EXT_B_BGA1-IC,TBD
GND                      U5D1             AF1      SKX_EXT_B_BGA1-IC,TBD
GND                      U5D1             AF9      SKX_EXT_B_BGA1-IC,TBD
GND                      U5D1             AF21     SKX_EXT_B_BGA1-IC,TBD
GND                      U5D1             AF23     SKX_EXT_B_BGA1-IC,TBD
GND                      U5D1             AF25     SKX_EXT_B_BGA1-IC,TBD
GND                      U5D1             AF27     SKX_EXT_B_BGA1-IC,TBD
GND                      U5D1             AF29     SKX_EXT_B_BGA1-IC,TBD
GND                      U5D1             AF31     SKX_EXT_B_BGA1-IC,TBD
GND                      U5D1             AF33     SKX_EXT_B_BGA1-IC,TBD
GND                      U5D1             AF37     SKX_EXT_B_BGA1-IC,TBD
GND                      U5D1             AF39     SKX_EXT_B_BGA1-IC,TBD
GND                      U5D1             AF41     SKX_EXT_B_BGA1-IC,TBD
GND                      U5D1             AF73     SKX_EXT_B_BGA1-IC,TBD
GND                      U5D1             AF77     SKX_EXT_B_BGA1-IC,TBD
GND                      U5D1             AF83     SKX_EXT_B_BGA1-IC,TBD
GND                      U5D1             AF85     SKX_EXT_B_BGA1-IC,TBD
GND                      U5D1             AG12     SKX_EXT_B_BGA1-IC,TBD
GND                      U5D1             AG14     SKX_EXT_B_BGA1-IC,TBD
GND                      U5D1             AG18     SKX_EXT_B_BGA1-IC,TBD
GND                      U5D1             AG36     SKX_EXT_B_BGA1-IC,TBD
GND                      U5D1             AG64     SKX_EXT_B_BGA1-IC,TBD
GND                      U5D1             AG70     SKX_EXT_B_BGA1-IC,TBD
GND                      U5D1             AG74     SKX_EXT_B_BGA1-IC,TBD
GND                      U5D1             AG76     SKX_EXT_B_BGA1-IC,TBD
GND                      U5D1             AG78     SKX_EXT_B_BGA1-IC,TBD
GND                      U5D1             AG80     SKX_EXT_B_BGA1-IC,TBD
GND                      U5D1             AH1      SKX_EXT_B_BGA1-IC,TBD
GND                      U5D1             AH5      SKX_EXT_B_BGA1-IC,TBD
GND                      U5D1             AH21     SKX_EXT_B_BGA1-IC,TBD
GND                      U5D1             AH27     SKX_EXT_B_BGA1-IC,TBD
GND                      U5D1             AH33     SKX_EXT_B_BGA1-IC,TBD
GND                      U5D1             AH35     SKX_EXT_B_BGA1-IC,TBD
GND                      U5D1             AH45     SKX_EXT_B_BGA1-IC,TBD
GND                      U5D1             AH47     SKX_EXT_B_BGA1-IC,TBD
GND                      U5D1             AH49     SKX_EXT_B_BGA1-IC,TBD
GND                      U5D1             AH51     SKX_EXT_B_BGA1-IC,TBD
GND                      U5D1             AH53     SKX_EXT_B_BGA1-IC,TBD
GND                      U5D1             AH59     SKX_EXT_B_BGA1-IC,TBD
GND                      U5D1             AH61     SKX_EXT_B_BGA1-IC,TBD
GND                      U5D1             AH65     SKX_EXT_B_BGA1-IC,TBD
GND                      U5D1             AH69     SKX_EXT_B_BGA1-IC,TBD
GND                      U5D1             AH75     SKX_EXT_B_BGA1-IC,TBD
GND                      U5D1             AH77     SKX_EXT_B_BGA1-IC,TBD
GND                      U5D1             AH83     SKX_EXT_B_BGA1-IC,TBD
GND                      U5D1             AJ4      SKX_EXT_B_BGA1-IC,TBD
GND                      U5D1             AJ8      SKX_EXT_B_BGA1-IC,TBD
GND                      U5D1             AJ22     SKX_EXT_B_BGA1-IC,TBD
GND                      U5D1             AJ26     SKX_EXT_B_BGA1-IC,TBD
GND                      U5D1             AJ28     SKX_EXT_B_BGA1-IC,TBD
GND                      U5D1             AJ32     SKX_EXT_B_BGA1-IC,TBD
GND                      U5D1             AJ34     SKX_EXT_B_BGA1-IC,TBD
GND                      U5D1             AJ46     SKX_EXT_B_BGA1-IC,TBD
GND                      U5D1             AJ48     SKX_EXT_B_BGA1-IC,TBD
GND                      U5D1             AJ50     SKX_EXT_B_BGA1-IC,TBD
GND                      U5D1             AJ52     SKX_EXT_B_BGA1-IC,TBD
GND                      U5D1             AJ54     SKX_EXT_B_BGA1-IC,TBD
GND                      U5D1             AJ66     SKX_EXT_B_BGA1-IC,TBD
GND                      U5D1             AJ68     SKX_EXT_B_BGA1-IC,TBD
GND                      U5D1             AJ74     SKX_EXT_B_BGA1-IC,TBD
GND                      U5D1             AJ78     SKX_EXT_B_BGA1-IC,TBD
GND                      U5D1             AJ82     SKX_EXT_B_BGA1-IC,TBD
GND                      U5D1             AJ86     SKX_EXT_B_BGA1-IC,TBD
GND                      U5D1             AK9      SKX_EXT_B_BGA1-IC,TBD
GND                      U5D1             AK13     SKX_EXT_B_BGA1-IC,TBD
GND                      U5D1             AK19     SKX_EXT_B_BGA1-IC,TBD
GND                      U5D1             AK23     SKX_EXT_B_BGA1-IC,TBD
GND                      U5D1             AK25     SKX_EXT_B_BGA1-IC,TBD
GND                      U5D1             AK29     SKX_EXT_B_BGA1-IC,TBD
GND                      U5D1             AK31     SKX_EXT_B_BGA1-IC,TBD
GND                      U5D1             AK33     SKX_EXT_B_BGA1-IC,TBD
GND                      U5D1             AK55     SKX_EXT_B_BGA1-IC,TBD
GND                      U5D1             AK65     SKX_EXT_B_BGA1-IC,TBD
GND                      U5D1             AK67     SKX_EXT_B_BGA1-IC,TBD
GND                      U5D1             AK73     SKX_EXT_B_BGA1-IC,TBD
GND                      U5D1             AK79     SKX_EXT_B_BGA1-IC,TBD
GND                      U5D1             AK81     SKX_EXT_B_BGA1-IC,TBD
GND                      U5D1             AK83     SKX_EXT_B_BGA1-IC,TBD
GND                      U5D1             AK85     SKX_EXT_B_BGA1-IC,TBD
GND                      U5D1             AL4      SKX_EXT_B_BGA1-IC,TBD
GND                      U5D1             AL10     SKX_EXT_B_BGA1-IC,TBD
GND                      U5D1             AL24     SKX_EXT_B_BGA1-IC,TBD
GND                      U5D1             AL30     SKX_EXT_B_BGA1-IC,TBD
GND                      U5D1             AL32     SKX_EXT_B_BGA1-IC,TBD
GND                      U5D1             AL56     SKX_EXT_B_BGA1-IC,TBD
GND                      U5D1             AL64     SKX_EXT_B_BGA1-IC,TBD
GND                      U5D1             AL68     SKX_EXT_B_BGA1-IC,TBD
GND                      U5D1             AL76     SKX_EXT_B_BGA1-IC,TBD
GND                      U5D1             AL78     SKX_EXT_B_BGA1-IC,TBD
GND                      U5D1             AL80     SKX_EXT_B_BGA1-IC,TBD
GND                      U5D1             AL82     SKX_EXT_B_BGA1-IC,TBD
GND                      U5D1             AL86     SKX_EXT_B_BGA1-IC,TBD
GND                      U5D1             AM1      SKX_EXT_B_BGA1-IC,TBD
GND                      U5D1             AM31     SKX_EXT_B_BGA1-IC,TBD
GND                      U5D1             AM57     SKX_EXT_B_BGA1-IC,TBD
GND                      U5D1             AM63     SKX_EXT_B_BGA1-IC,TBD
GND                      U5D1             AM69     SKX_EXT_B_BGA1-IC,TBD
GND                      U5D1             AM73     SKX_EXT_B_BGA1-IC,TBD
GND                      U5D1             AM79     SKX_EXT_B_BGA1-IC,TBD
GND                      U5D1             AM83     SKX_EXT_B_BGA1-IC,TBD
GND                      U5D1             AN2      SKX_EXT_B_BGA1-IC,TBD
GND                      U5D1             AN6      SKX_EXT_B_BGA1-IC,TBD
GND                      U5D1             AN28     SKX_EXT_B_BGA1-IC,TBD
GND                      U5D1             AN58     SKX_EXT_B_BGA1-IC,TBD
GND                      U5D1             AN78     SKX_EXT_B_BGA1-IC,TBD
GND                      U5D1             AP5      SKX_EXT_B_BGA1-IC,TBD
GND                      U5D1             AP9      SKX_EXT_B_BGA1-IC,TBD
GND                      U5D1             AP13     SKX_EXT_B_BGA1-IC,TBD
GND                      U5D1             AP19     SKX_EXT_B_BGA1-IC,TBD
GND                      U5D1             AP31     SKX_EXT_B_BGA1-IC,TBD
GND                      U5D1             AP59     SKX_EXT_B_BGA1-IC,TBD
GND                      U5D1             AP63     SKX_EXT_B_BGA1-IC,TBD
GND                      U5D1             AP65     SKX_EXT_B_BGA1-IC,TBD
GND                      U5D1             AP67     SKX_EXT_B_BGA1-IC,TBD
GND                      U5D1             AP69     SKX_EXT_B_BGA1-IC,TBD
GND                      U5D1             AP73     SKX_EXT_B_BGA1-IC,TBD
GND                      U5D1             AP75     SKX_EXT_B_BGA1-IC,TBD
GND                      U5D1             AP81     SKX_EXT_B_BGA1-IC,TBD
GND                      U5D1             AP83     SKX_EXT_B_BGA1-IC,TBD
GND                      U5D1             AP85     SKX_EXT_B_BGA1-IC,TBD
GND                      U5D1             AR6      SKX_EXT_B_BGA1-IC,TBD
GND                      U5D1             AR10     SKX_EXT_B_BGA1-IC,TBD
GND                      U5D1             AR24     SKX_EXT_B_BGA1-IC,TBD
GND                      U5D1             AR30     SKX_EXT_B_BGA1-IC,TBD
GND                      U5D1             AR60     SKX_EXT_B_BGA1-IC,TBD
GND                      U5D1             AR72     SKX_EXT_B_BGA1-IC,TBD
GND                      U5D1             AR78     SKX_EXT_B_BGA1-IC,TBD
GND                      U5D1             AT15     SKX_EXT_B_BGA1-IC,TBD
GND                      U5D1             AT17     SKX_EXT_B_BGA1-IC,TBD
GND                      U5D1             AT21     SKX_EXT_B_BGA1-IC,TBD
GND                      U5D1             AT27     SKX_EXT_B_BGA1-IC,TBD
GND                      U5D1             AT61     SKX_EXT_B_BGA1-IC,TBD
GND                      U5D1             AT63     SKX_EXT_B_BGA1-IC,TBD
GND                      U5D1             AT69     SKX_EXT_B_BGA1-IC,TBD
GND                      U5D1             AT73     SKX_EXT_B_BGA1-IC,TBD
GND                      U5D1             AT77     SKX_EXT_B_BGA1-IC,TBD
GND                      U5D1             AT83     SKX_EXT_B_BGA1-IC,TBD
GND                      U5D1             AT85     SKX_EXT_B_BGA1-IC,TBD
GND                      U5D1             AU2      SKX_EXT_B_BGA1-IC,TBD
GND                      U5D1             AU6      SKX_EXT_B_BGA1-IC,TBD
GND                      U5D1             AU26     SKX_EXT_B_BGA1-IC,TBD
GND                      U5D1             AU28     SKX_EXT_B_BGA1-IC,TBD
GND                      U5D1             AU62     SKX_EXT_B_BGA1-IC,TBD
GND                      U5D1             AU64     SKX_EXT_B_BGA1-IC,TBD
GND                      U5D1             AU68     SKX_EXT_B_BGA1-IC,TBD
GND                      U5D1             AU74     SKX_EXT_B_BGA1-IC,TBD
GND                      U5D1             AU76     SKX_EXT_B_BGA1-IC,TBD
GND                      U5D1             AU78     SKX_EXT_B_BGA1-IC,TBD
GND                      U5D1             AU80     SKX_EXT_B_BGA1-IC,TBD
GND                      U5D1             AU84     SKX_EXT_B_BGA1-IC,TBD
GND                      U5D1             AU86     SKX_EXT_B_BGA1-IC,TBD
GND                      U5D1             AV1      SKX_EXT_B_BGA1-IC,TBD
GND                      U5D1             AV3      SKX_EXT_B_BGA1-IC,TBD
GND                      U5D1             AV7      SKX_EXT_B_BGA1-IC,TBD
GND                      U5D1             AV11     SKX_EXT_B_BGA1-IC,TBD
GND                      U5D1             AV13     SKX_EXT_B_BGA1-IC,TBD
GND                      U5D1             AV19     SKX_EXT_B_BGA1-IC,TBD
GND                      U5D1             AV23     SKX_EXT_B_BGA1-IC,TBD
GND                      U5D1             AV25     SKX_EXT_B_BGA1-IC,TBD
GND                      U5D1             AV63     SKX_EXT_B_BGA1-IC,TBD
GND                      U5D1             AV65     SKX_EXT_B_BGA1-IC,TBD
GND                      U5D1             AV67     SKX_EXT_B_BGA1-IC,TBD
GND                      U5D1             AV75     SKX_EXT_B_BGA1-IC,TBD
GND                      U5D1             AV83     SKX_EXT_B_BGA1-IC,TBD
GND                      U5D1             AW2      SKX_EXT_B_BGA1-IC,TBD
GND                      U5D1             AW10     SKX_EXT_B_BGA1-IC,TBD
GND                      U5D1             AW62     SKX_EXT_B_BGA1-IC,TBD
GND                      U5D1             AW66     SKX_EXT_B_BGA1-IC,TBD
GND                      U5D1             AW68     SKX_EXT_B_BGA1-IC,TBD
GND                      U5D1             AW70     SKX_EXT_B_BGA1-IC,TBD
GND                      U5D1             AW72     SKX_EXT_B_BGA1-IC,TBD
GND                      U5D1             AW74     SKX_EXT_B_BGA1-IC,TBD
GND                      U5D1             AW78     SKX_EXT_B_BGA1-IC,TBD
GND                      U5D1             AW82     SKX_EXT_B_BGA1-IC,TBD
GND                      U5D1             AW84     SKX_EXT_B_BGA1-IC,TBD
GND                      U5D1             AY5      SKX_EXT_B_BGA1-IC,TBD
GND                      U5D1             AY15     SKX_EXT_B_BGA1-IC,TBD
GND                      U5D1             AY17     SKX_EXT_B_BGA1-IC,TBD
GND                      U5D1             AY21     SKX_EXT_B_BGA1-IC,TBD
GND                      U5D1             AY23     SKX_EXT_B_BGA1-IC,TBD
GND                      U5D1             AY25     SKX_EXT_B_BGA1-IC,TBD
GND                      U5D1             AY63     SKX_EXT_B_BGA1-IC,TBD
GND                      U5D1             AY79     SKX_EXT_B_BGA1-IC,TBD
GND                      U5D1             AY81     SKX_EXT_B_BGA1-IC,TBD
GND                      U5D1             B5       SKX_EXT_B_BGA1-IC,TBD
GND                      U5D1             B9       SKX_EXT_B_BGA1-IC,TBD
GND                      U5D1             B25      SKX_EXT_B_BGA1-IC,TBD
GND                      U5D1             B31      SKX_EXT_B_BGA1-IC,TBD
GND                      U5D1             B37      SKX_EXT_B_BGA1-IC,TBD
GND                      U5D1             B43      SKX_EXT_B_BGA1-IC,TBD
GND                      U5D1             B71      SKX_EXT_B_BGA1-IC,TBD
GND                      U5D1             B75      SKX_EXT_B_BGA1-IC,TBD
GND                      U5D1             B79      SKX_EXT_B_BGA1-IC,TBD
GND                      U5D1             BA2      SKX_EXT_B_BGA1-IC,TBD
GND                      U5D1             BA6      SKX_EXT_B_BGA1-IC,TBD
GND                      U5D1             BA12     SKX_EXT_B_BGA1-IC,TBD
GND                      U5D1             BA62     SKX_EXT_B_BGA1-IC,TBD
GND                      U5D1             BA68     SKX_EXT_B_BGA1-IC,TBD
GND                      U5D1             BA74     SKX_EXT_B_BGA1-IC,TBD
GND                      U5D1             BA80     SKX_EXT_B_BGA1-IC,TBD
GND                      U5D1             BA84     SKX_EXT_B_BGA1-IC,TBD
GND                      U5D1             BB19     SKX_EXT_B_BGA1-IC,TBD
GND                      U5D1             BB23     SKX_EXT_B_BGA1-IC,TBD
GND                      U5D1             BB63     SKX_EXT_B_BGA1-IC,TBD
GND                      U5D1             BB69     SKX_EXT_B_BGA1-IC,TBD
GND                      U5D1             BB73     SKX_EXT_B_BGA1-IC,TBD
GND                      U5D1             BB75     SKX_EXT_B_BGA1-IC,TBD
GND                      U5D1             BB77     SKX_EXT_B_BGA1-IC,TBD
GND                      U5D1             BB79     SKX_EXT_B_BGA1-IC,TBD
GND                      U5D1             BB81     SKX_EXT_B_BGA1-IC,TBD
GND                      U5D1             BB83     SKX_EXT_B_BGA1-IC,TBD
GND                      U5D1             BC4      SKX_EXT_B_BGA1-IC,TBD
GND                      U5D1             BC8      SKX_EXT_B_BGA1-IC,TBD
GND                      U5D1             BC12     SKX_EXT_B_BGA1-IC,TBD
GND                      U5D1             BC16     SKX_EXT_B_BGA1-IC,TBD
GND                      U5D1             BC70     SKX_EXT_B_BGA1-IC,TBD
GND                      U5D1             BC72     SKX_EXT_B_BGA1-IC,TBD
GND                      U5D1             BC74     SKX_EXT_B_BGA1-IC,TBD
GND                      U5D1             BC76     SKX_EXT_B_BGA1-IC,TBD
GND                      U5D1             BC78     SKX_EXT_B_BGA1-IC,TBD
GND                      U5D1             BC80     SKX_EXT_B_BGA1-IC,TBD
GND                      U5D1             BC82     SKX_EXT_B_BGA1-IC,TBD
GND                      U5D1             BD5      SKX_EXT_B_BGA1-IC,TBD
GND                      U5D1             BD11     SKX_EXT_B_BGA1-IC,TBD
GND                      U5D1             BD15     SKX_EXT_B_BGA1-IC,TBD
GND                      U5D1             BD21     SKX_EXT_B_BGA1-IC,TBD
GND                      U5D1             BD27     SKX_EXT_B_BGA1-IC,TBD
GND                      U5D1             BD63     SKX_EXT_B_BGA1-IC,TBD
GND                      U5D1             BD71     SKX_EXT_B_BGA1-IC,TBD
GND                      U5D1             BE4      SKX_EXT_B_BGA1-IC,TBD
GND                      U5D1             BE6      SKX_EXT_B_BGA1-IC,TBD
GND                      U5D1             BE8      SKX_EXT_B_BGA1-IC,TBD
GND                      U5D1             BE10     SKX_EXT_B_BGA1-IC,TBD
GND                      U5D1             BE26     SKX_EXT_B_BGA1-IC,TBD
GND                      U5D1             BE64     SKX_EXT_B_BGA1-IC,TBD
GND                      U5D1             BE66     SKX_EXT_B_BGA1-IC,TBD
GND                      U5D1             BE68     SKX_EXT_B_BGA1-IC,TBD
GND                      U5D1             BE70     SKX_EXT_B_BGA1-IC,TBD
GND                      U5D1             BF9      SKX_EXT_B_BGA1-IC,TBD
GND                      U5D1             BF15     SKX_EXT_B_BGA1-IC,TBD
GND                      U5D1             BF17     SKX_EXT_B_BGA1-IC,TBD
GND                      U5D1             BF19     SKX_EXT_B_BGA1-IC,TBD
GND                      U5D1             BF25     SKX_EXT_B_BGA1-IC,TBD
GND                      U5D1             BF63     SKX_EXT_B_BGA1-IC,TBD
GND                      U5D1             BF65     SKX_EXT_B_BGA1-IC,TBD
GND                      U5D1             BF67     SKX_EXT_B_BGA1-IC,TBD
GND                      U5D1             BF69     SKX_EXT_B_BGA1-IC,TBD
GND                      U5D1             BF71     SKX_EXT_B_BGA1-IC,TBD
GND                      U5D1             BG6      SKX_EXT_B_BGA1-IC,TBD
GND                      U5D1             BG8      SKX_EXT_B_BGA1-IC,TBD
GND                      U5D1             BG10     SKX_EXT_B_BGA1-IC,TBD
GND                      U5D1             BG22     SKX_EXT_B_BGA1-IC,TBD
GND                      U5D1             BG24     SKX_EXT_B_BGA1-IC,TBD
GND                      U5D1             BG72     SKX_EXT_B_BGA1-IC,TBD
GND                      U5D1             BG74     SKX_EXT_B_BGA1-IC,TBD
GND                      U5D1             BG76     SKX_EXT_B_BGA1-IC,TBD
GND                      U5D1             BG78     SKX_EXT_B_BGA1-IC,TBD
GND                      U5D1             BG80     SKX_EXT_B_BGA1-IC,TBD
GND                      U5D1             BG82     SKX_EXT_B_BGA1-IC,TBD
GND                      U5D1             BH7      SKX_EXT_B_BGA1-IC,TBD
GND                      U5D1             BH9      SKX_EXT_B_BGA1-IC,TBD
GND                      U5D1             BH11     SKX_EXT_B_BGA1-IC,TBD
GND                      U5D1             BH15     SKX_EXT_B_BGA1-IC,TBD
GND                      U5D1             BH17     SKX_EXT_B_BGA1-IC,TBD
GND                      U5D1             BH21     SKX_EXT_B_BGA1-IC,TBD
GND                      U5D1             BJ4      SKX_EXT_B_BGA1-IC,TBD
GND                      U5D1             BJ6      SKX_EXT_B_BGA1-IC,TBD
GND                      U5D1             BK3      SKX_EXT_B_BGA1-IC,TBD
GND                      U5D1             BK7      SKX_EXT_B_BGA1-IC,TBD
GND                      U5D1             BK11     SKX_EXT_B_BGA1-IC,TBD
GND                      U5D1             BK19     SKX_EXT_B_BGA1-IC,TBD
GND                      U5D1             BL6      SKX_EXT_B_BGA1-IC,TBD
GND                      U5D1             BL10     SKX_EXT_B_BGA1-IC,TBD
GND                      U5D1             BL12     SKX_EXT_B_BGA1-IC,TBD
GND                      U5D1             BL22     SKX_EXT_B_BGA1-IC,TBD
GND                      U5D1             BL24     SKX_EXT_B_BGA1-IC,TBD
GND                      U5D1             BL64     SKX_EXT_B_BGA1-IC,TBD
GND                      U5D1             BL66     SKX_EXT_B_BGA1-IC,TBD
GND                      U5D1             BL68     SKX_EXT_B_BGA1-IC,TBD
GND                      U5D1             BL70     SKX_EXT_B_BGA1-IC,TBD
GND                      U5D1             BL72     SKX_EXT_B_BGA1-IC,TBD
GND                      U5D1             BL74     SKX_EXT_B_BGA1-IC,TBD
GND                      U5D1             BL76     SKX_EXT_B_BGA1-IC,TBD
GND                      U5D1             BL78     SKX_EXT_B_BGA1-IC,TBD
GND                      U5D1             BL80     SKX_EXT_B_BGA1-IC,TBD
GND                      U5D1             BL82     SKX_EXT_B_BGA1-IC,TBD
GND                      U5D1             BM9      SKX_EXT_B_BGA1-IC,TBD
GND                      U5D1             BM13     SKX_EXT_B_BGA1-IC,TBD
GND                      U5D1             BM15     SKX_EXT_B_BGA1-IC,TBD
GND                      U5D1             BM25     SKX_EXT_B_BGA1-IC,TBD
GND                      U5D1             BN6      SKX_EXT_B_BGA1-IC,TBD
GND                      U5D1             BN10     SKX_EXT_B_BGA1-IC,TBD
GND                      U5D1             BN20     SKX_EXT_B_BGA1-IC,TBD
GND                      U5D1             BN26     SKX_EXT_B_BGA1-IC,TBD
GND                      U5D1             BP3      SKX_EXT_B_BGA1-IC,TBD
GND                      U5D1             BP27     SKX_EXT_B_BGA1-IC,TBD
GND                      U5D1             BR6      SKX_EXT_B_BGA1-IC,TBD
GND                      U5D1             BR10     SKX_EXT_B_BGA1-IC,TBD
GND                      U5D1             BR16     SKX_EXT_B_BGA1-IC,TBD
GND                      U5D1             BR18     SKX_EXT_B_BGA1-IC,TBD
GND                      U5D1             BR26     SKX_EXT_B_BGA1-IC,TBD
GND                      U5D1             BR64     SKX_EXT_B_BGA1-IC,TBD
GND                      U5D1             BR66     SKX_EXT_B_BGA1-IC,TBD
GND                      U5D1             BR68     SKX_EXT_B_BGA1-IC,TBD
GND                      U5D1             BR70     SKX_EXT_B_BGA1-IC,TBD
GND                      U5D1             BR72     SKX_EXT_B_BGA1-IC,TBD
GND                      U5D1             BR74     SKX_EXT_B_BGA1-IC,TBD
GND                      U5D1             BR76     SKX_EXT_B_BGA1-IC,TBD
GND                      U5D1             BR78     SKX_EXT_B_BGA1-IC,TBD
GND                      U5D1             BR80     SKX_EXT_B_BGA1-IC,TBD
GND                      U5D1             BR82     SKX_EXT_B_BGA1-IC,TBD
GND                      U5D1             BT3      SKX_EXT_B_BGA1-IC,TBD
GND                      U5D1             BT5      SKX_EXT_B_BGA1-IC,TBD
GND                      U5D1             BT9      SKX_EXT_B_BGA1-IC,TBD
GND                      U5D1             BT21     SKX_EXT_B_BGA1-IC,TBD
GND                      U5D1             BT23     SKX_EXT_B_BGA1-IC,TBD
GND                      U5D1             BT25     SKX_EXT_B_BGA1-IC,TBD
GND                      U5D1             BU8      SKX_EXT_B_BGA1-IC,TBD
GND                      U5D1             BU10     SKX_EXT_B_BGA1-IC,TBD
GND                      U5D1             BV5      SKX_EXT_B_BGA1-IC,TBD
GND                      U5D1             BV17     SKX_EXT_B_BGA1-IC,TBD
GND                      U5D1             BV25     SKX_EXT_B_BGA1-IC,TBD
GND                      U5D1             BW6      SKX_EXT_B_BGA1-IC,TBD
GND                      U5D1             BW12     SKX_EXT_B_BGA1-IC,TBD
GND                      U5D1             BW14     SKX_EXT_B_BGA1-IC,TBD
GND                      U5D1             BW16     SKX_EXT_B_BGA1-IC,TBD
GND                      U5D1             BW18     SKX_EXT_B_BGA1-IC,TBD
GND                      U5D1             BW26     SKX_EXT_B_BGA1-IC,TBD
GND                      U5D1             BW72     SKX_EXT_B_BGA1-IC,TBD
GND                      U5D1             BW74     SKX_EXT_B_BGA1-IC,TBD
GND                      U5D1             BW76     SKX_EXT_B_BGA1-IC,TBD
GND                      U5D1             BW78     SKX_EXT_B_BGA1-IC,TBD
GND                      U5D1             BW80     SKX_EXT_B_BGA1-IC,TBD
GND                      U5D1             BW82     SKX_EXT_B_BGA1-IC,TBD
GND                      U5D1             BY11     SKX_EXT_B_BGA1-IC,TBD
GND                      U5D1             BY13     SKX_EXT_B_BGA1-IC,TBD
GND                      U5D1             BY15     SKX_EXT_B_BGA1-IC,TBD
GND                      U5D1             BY17     SKX_EXT_B_BGA1-IC,TBD
GND                      U5D1             BY23     SKX_EXT_B_BGA1-IC,TBD
GND                      U5D1             BY63     SKX_EXT_B_BGA1-IC,TBD
GND                      U5D1             BY65     SKX_EXT_B_BGA1-IC,TBD
GND                      U5D1             BY67     SKX_EXT_B_BGA1-IC,TBD
GND                      U5D1             BY69     SKX_EXT_B_BGA1-IC,TBD
GND                      U5D1             BY71     SKX_EXT_B_BGA1-IC,TBD
GND                      U5D1             C4       SKX_EXT_B_BGA1-IC,TBD
GND                      U5D1             C8       SKX_EXT_B_BGA1-IC,TBD
GND                      U5D1             C10      SKX_EXT_B_BGA1-IC,TBD
GND                      U5D1             C12      SKX_EXT_B_BGA1-IC,TBD
GND                      U5D1             C14      SKX_EXT_B_BGA1-IC,TBD
GND                      U5D1             C16      SKX_EXT_B_BGA1-IC,TBD
GND                      U5D1             C76      SKX_EXT_B_BGA1-IC,TBD
GND                      U5D1             C78      SKX_EXT_B_BGA1-IC,TBD
GND                      U5D1             C80      SKX_EXT_B_BGA1-IC,TBD
GND                      U5D1             CA2      SKX_EXT_B_BGA1-IC,TBD
GND                      U5D1             CA6      SKX_EXT_B_BGA1-IC,TBD
GND                      U5D1             CA8      SKX_EXT_B_BGA1-IC,TBD
GND                      U5D1             CA10     SKX_EXT_B_BGA1-IC,TBD
GND                      U5D1             CA14     SKX_EXT_B_BGA1-IC,TBD
GND                      U5D1             CA16     SKX_EXT_B_BGA1-IC,TBD
GND                      U5D1             CA18     SKX_EXT_B_BGA1-IC,TBD
GND                      U5D1             CA20     SKX_EXT_B_BGA1-IC,TBD
GND                      U5D1             CA26     SKX_EXT_B_BGA1-IC,TBD
GND                      U5D1             CA64     SKX_EXT_B_BGA1-IC,TBD
GND                      U5D1             CA66     SKX_EXT_B_BGA1-IC,TBD
GND                      U5D1             CA68     SKX_EXT_B_BGA1-IC,TBD
GND                      U5D1             CA70     SKX_EXT_B_BGA1-IC,TBD
GND                      U5D1             CB7      SKX_EXT_B_BGA1-IC,TBD
GND                      U5D1             CB9      SKX_EXT_B_BGA1-IC,TBD
GND                      U5D1             CB15     SKX_EXT_B_BGA1-IC,TBD
GND                      U5D1             CB27     SKX_EXT_B_BGA1-IC,TBD
GND                      U5D1             CB63     SKX_EXT_B_BGA1-IC,TBD
GND                      U5D1             CB71     SKX_EXT_B_BGA1-IC,TBD
GND                      U5D1             CC4      SKX_EXT_B_BGA1-IC,TBD
GND                      U5D1             CC14     SKX_EXT_B_BGA1-IC,TBD
GND                      U5D1             CC16     SKX_EXT_B_BGA1-IC,TBD
GND                      U5D1             CC18     SKX_EXT_B_BGA1-IC,TBD
GND                      U5D1             CC24     SKX_EXT_B_BGA1-IC,TBD
GND                      U5D1             CC64     SKX_EXT_B_BGA1-IC,TBD
GND                      U5D1             CC72     SKX_EXT_B_BGA1-IC,TBD
GND                      U5D1             CC74     SKX_EXT_B_BGA1-IC,TBD
GND                      U5D1             CC76     SKX_EXT_B_BGA1-IC,TBD
GND                      U5D1             CC78     SKX_EXT_B_BGA1-IC,TBD
GND                      U5D1             CC80     SKX_EXT_B_BGA1-IC,TBD
GND                      U5D1             CC82     SKX_EXT_B_BGA1-IC,TBD
GND                      U5D1             CD5      SKX_EXT_B_BGA1-IC,TBD
GND                      U5D1             CD13     SKX_EXT_B_BGA1-IC,TBD
GND                      U5D1             CD15     SKX_EXT_B_BGA1-IC,TBD
GND                      U5D1             CD17     SKX_EXT_B_BGA1-IC,TBD
GND                      U5D1             CD63     SKX_EXT_B_BGA1-IC,TBD
GND                      U5D1             CD73     SKX_EXT_B_BGA1-IC,TBD
GND                      U5D1             CD75     SKX_EXT_B_BGA1-IC,TBD
GND                      U5D1             CD77     SKX_EXT_B_BGA1-IC,TBD
GND                      U5D1             CD79     SKX_EXT_B_BGA1-IC,TBD
GND                      U5D1             CD81     SKX_EXT_B_BGA1-IC,TBD
GND                      U5D1             CE10     SKX_EXT_B_BGA1-IC,TBD
GND                      U5D1             CE14     SKX_EXT_B_BGA1-IC,TBD
GND                      U5D1             CE16     SKX_EXT_B_BGA1-IC,TBD
GND                      U5D1             CE20     SKX_EXT_B_BGA1-IC,TBD
GND                      U5D1             CE26     SKX_EXT_B_BGA1-IC,TBD
GND                      U5D1             CE62     SKX_EXT_B_BGA1-IC,TBD
GND                      U5D1             CE70     SKX_EXT_B_BGA1-IC,TBD
GND                      U5D1             CE82     SKX_EXT_B_BGA1-IC,TBD
GND                      U5D1             CF9      SKX_EXT_B_BGA1-IC,TBD
GND                      U5D1             CF15     SKX_EXT_B_BGA1-IC,TBD
GND                      U5D1             CF17     SKX_EXT_B_BGA1-IC,TBD
GND                      U5D1             CF63     SKX_EXT_B_BGA1-IC,TBD
GND                      U5D1             CF69     SKX_EXT_B_BGA1-IC,TBD
GND                      U5D1             CF71     SKX_EXT_B_BGA1-IC,TBD
GND                      U5D1             CF77     SKX_EXT_B_BGA1-IC,TBD
GND                      U5D1             CF83     SKX_EXT_B_BGA1-IC,TBD
GND                      U5D1             CG6      SKX_EXT_B_BGA1-IC,TBD
GND                      U5D1             CG16     SKX_EXT_B_BGA1-IC,TBD
GND                      U5D1             CG18     SKX_EXT_B_BGA1-IC,TBD
GND                      U5D1             CG22     SKX_EXT_B_BGA1-IC,TBD
GND                      U5D1             CG62     SKX_EXT_B_BGA1-IC,TBD
GND                      U5D1             CG68     SKX_EXT_B_BGA1-IC,TBD
GND                      U5D1             CG72     SKX_EXT_B_BGA1-IC,TBD
GND                      U5D1             CG80     SKX_EXT_B_BGA1-IC,TBD
GND                      U5D1             CH1      SKX_EXT_B_BGA1-IC,TBD
GND                      U5D1             CH3      SKX_EXT_B_BGA1-IC,TBD
GND                      U5D1             CH15     SKX_EXT_B_BGA1-IC,TBD
GND                      U5D1             CH17     SKX_EXT_B_BGA1-IC,TBD
GND                      U5D1             CH19     SKX_EXT_B_BGA1-IC,TBD
GND                      U5D1             CH63     SKX_EXT_B_BGA1-IC,TBD
GND                      U5D1             CH67     SKX_EXT_B_BGA1-IC,TBD
GND                      U5D1             CH73     SKX_EXT_B_BGA1-IC,TBD
GND                      U5D1             CH79     SKX_EXT_B_BGA1-IC,TBD
GND                      U5D1             CH81     SKX_EXT_B_BGA1-IC,TBD
GND                      U5D1             CH83     SKX_EXT_B_BGA1-IC,TBD
GND                      U5D1             CJ2      SKX_EXT_B_BGA1-IC,TBD
GND                      U5D1             CJ6      SKX_EXT_B_BGA1-IC,TBD
GND                      U5D1             CJ8      SKX_EXT_B_BGA1-IC,TBD
GND                      U5D1             CJ10     SKX_EXT_B_BGA1-IC,TBD
GND                      U5D1             CJ12     SKX_EXT_B_BGA1-IC,TBD
GND                      U5D1             CJ16     SKX_EXT_B_BGA1-IC,TBD
GND                      U5D1             CJ18     SKX_EXT_B_BGA1-IC,TBD
GND                      U5D1             CJ62     SKX_EXT_B_BGA1-IC,TBD
GND                      U5D1             CJ74     SKX_EXT_B_BGA1-IC,TBD
GND                      U5D1             CJ76     SKX_EXT_B_BGA1-IC,TBD
GND                      U5D1             CJ78     SKX_EXT_B_BGA1-IC,TBD
GND                      U5D1             CJ82     SKX_EXT_B_BGA1-IC,TBD
GND                      U5D1             CJ84     SKX_EXT_B_BGA1-IC,TBD
GND                      U5D1             CJ86     SKX_EXT_B_BGA1-IC,TBD
GND                      U5D1             CK11     SKX_EXT_B_BGA1-IC,TBD
GND                      U5D1             CK15     SKX_EXT_B_BGA1-IC,TBD
GND                      U5D1             CK17     SKX_EXT_B_BGA1-IC,TBD
GND                      U5D1             CK21     SKX_EXT_B_BGA1-IC,TBD
GND                      U5D1             CK27     SKX_EXT_B_BGA1-IC,TBD
GND                      U5D1             CK63     SKX_EXT_B_BGA1-IC,TBD
GND                      U5D1             CK65     SKX_EXT_B_BGA1-IC,TBD
GND                      U5D1             CK67     SKX_EXT_B_BGA1-IC,TBD
GND                      U5D1             CK69     SKX_EXT_B_BGA1-IC,TBD
GND                      U5D1             CK71     SKX_EXT_B_BGA1-IC,TBD
GND                      U5D1             CK73     SKX_EXT_B_BGA1-IC,TBD
GND                      U5D1             CK75     SKX_EXT_B_BGA1-IC,TBD
GND                      U5D1             CK83     SKX_EXT_B_BGA1-IC,TBD
GND                      U5D1             CK85     SKX_EXT_B_BGA1-IC,TBD
GND                      U5D1             CL8      SKX_EXT_B_BGA1-IC,TBD
GND                      U5D1             CL14     SKX_EXT_B_BGA1-IC,TBD
GND                      U5D1             CL16     SKX_EXT_B_BGA1-IC,TBD
GND                      U5D1             CL18     SKX_EXT_B_BGA1-IC,TBD
GND                      U5D1             CL22     SKX_EXT_B_BGA1-IC,TBD
GND                      U5D1             CL62     SKX_EXT_B_BGA1-IC,TBD
GND                      U5D1             CL64     SKX_EXT_B_BGA1-IC,TBD
GND                      U5D1             CL66     SKX_EXT_B_BGA1-IC,TBD
GND                      U5D1             CL74     SKX_EXT_B_BGA1-IC,TBD
GND                      U5D1             CL76     SKX_EXT_B_BGA1-IC,TBD
GND                      U5D1             CL78     SKX_EXT_B_BGA1-IC,TBD
GND                      U5D1             CL80     SKX_EXT_B_BGA1-IC,TBD
GND                      U5D1             CM5      SKX_EXT_B_BGA1-IC,TBD
GND                      U5D1             CM19     SKX_EXT_B_BGA1-IC,TBD
GND                      U5D1             CM21     SKX_EXT_B_BGA1-IC,TBD
GND                      U5D1             CM27     SKX_EXT_B_BGA1-IC,TBD
GND                      U5D1             CM29     SKX_EXT_B_BGA1-IC,TBD
GND                      U5D1             CM31     SKX_EXT_B_BGA1-IC,TBD
GND                      U5D1             CM61     SKX_EXT_B_BGA1-IC,TBD
GND                      U5D1             CM63     SKX_EXT_B_BGA1-IC,TBD
GND                      U5D1             CM67     SKX_EXT_B_BGA1-IC,TBD
GND                      U5D1             CM73     SKX_EXT_B_BGA1-IC,TBD
GND                      U5D1             CM77     SKX_EXT_B_BGA1-IC,TBD
GND                      U5D1             CM83     SKX_EXT_B_BGA1-IC,TBD
GND                      U5D1             CM85     SKX_EXT_B_BGA1-IC,TBD
GND                      U5D1             CN2      SKX_EXT_B_BGA1-IC,TBD
GND                      U5D1             CN12     SKX_EXT_B_BGA1-IC,TBD
GND                      U5D1             CN14     SKX_EXT_B_BGA1-IC,TBD
GND                      U5D1             CN18     SKX_EXT_B_BGA1-IC,TBD
GND                      U5D1             CN20     SKX_EXT_B_BGA1-IC,TBD
GND                      U5D1             CN26     SKX_EXT_B_BGA1-IC,TBD
GND                      U5D1             CN32     SKX_EXT_B_BGA1-IC,TBD
GND                      U5D1             CN60     SKX_EXT_B_BGA1-IC,TBD
GND                      U5D1             CN62     SKX_EXT_B_BGA1-IC,TBD
GND                      U5D1             CN68     SKX_EXT_B_BGA1-IC,TBD
GND                      U5D1             CN78     SKX_EXT_B_BGA1-IC,TBD
GND                      U5D1             CP1      SKX_EXT_B_BGA1-IC,TBD
GND                      U5D1             CP19     SKX_EXT_B_BGA1-IC,TBD
GND                      U5D1             CP21     SKX_EXT_B_BGA1-IC,TBD
GND                      U5D1             CP25     SKX_EXT_B_BGA1-IC,TBD
GND                      U5D1             CP59     SKX_EXT_B_BGA1-IC,TBD
GND                      U5D1             CP69     SKX_EXT_B_BGA1-IC,TBD
GND                      U5D1             CP73     SKX_EXT_B_BGA1-IC,TBD
GND                      U5D1             CP75     SKX_EXT_B_BGA1-IC,TBD
GND                      U5D1             CP81     SKX_EXT_B_BGA1-IC,TBD
GND                      U5D1             CP83     SKX_EXT_B_BGA1-IC,TBD
GND                      U5D1             CR6      SKX_EXT_B_BGA1-IC,TBD
GND                      U5D1             CR10     SKX_EXT_B_BGA1-IC,TBD
GND                      U5D1             CR18     SKX_EXT_B_BGA1-IC,TBD
GND                      U5D1             CR20     SKX_EXT_B_BGA1-IC,TBD
GND                      U5D1             CR22     SKX_EXT_B_BGA1-IC,TBD
GND                      U5D1             CR24     SKX_EXT_B_BGA1-IC,TBD
GND                      U5D1             CR32     SKX_EXT_B_BGA1-IC,TBD
GND                      U5D1             CR58     SKX_EXT_B_BGA1-IC,TBD
GND                      U5D1             CR62     SKX_EXT_B_BGA1-IC,TBD
GND                      U5D1             CR64     SKX_EXT_B_BGA1-IC,TBD
GND                      U5D1             CR66     SKX_EXT_B_BGA1-IC,TBD
GND                      U5D1             CR68     SKX_EXT_B_BGA1-IC,TBD
GND                      U5D1             CR78     SKX_EXT_B_BGA1-IC,TBD
GND                      U5D1             CR86     SKX_EXT_B_BGA1-IC,TBD
GND                      U5D1             CT7      SKX_EXT_B_BGA1-IC,TBD
GND                      U5D1             CT13     SKX_EXT_B_BGA1-IC,TBD
GND                      U5D1             CT19     SKX_EXT_B_BGA1-IC,TBD
GND                      U5D1             CT21     SKX_EXT_B_BGA1-IC,TBD
GND                      U5D1             CT27     SKX_EXT_B_BGA1-IC,TBD
GND                      U5D1             CT29     SKX_EXT_B_BGA1-IC,TBD
GND                      U5D1             CT33     SKX_EXT_B_BGA1-IC,TBD
GND                      U5D1             CT35     SKX_EXT_B_BGA1-IC,TBD
GND                      U5D1             CT57     SKX_EXT_B_BGA1-IC,TBD
GND                      U5D1             CT73     SKX_EXT_B_BGA1-IC,TBD
GND                      U5D1             CT79     SKX_EXT_B_BGA1-IC,TBD
GND                      U5D1             CT83     SKX_EXT_B_BGA1-IC,TBD
GND                      U5D1             CT85     SKX_EXT_B_BGA1-IC,TBD
GND                      U5D1             CU4      SKX_EXT_B_BGA1-IC,TBD
GND                      U5D1             CU20     SKX_EXT_B_BGA1-IC,TBD
GND                      U5D1             CU22     SKX_EXT_B_BGA1-IC,TBD
GND                      U5D1             CU28     SKX_EXT_B_BGA1-IC,TBD
GND                      U5D1             CU30     SKX_EXT_B_BGA1-IC,TBD
GND                      U5D1             CU34     SKX_EXT_B_BGA1-IC,TBD
GND                      U5D1             CU36     SKX_EXT_B_BGA1-IC,TBD
GND                      U5D1             CU56     SKX_EXT_B_BGA1-IC,TBD
GND                      U5D1             CU62     SKX_EXT_B_BGA1-IC,TBD
GND                      U5D1             CU68     SKX_EXT_B_BGA1-IC,TBD
GND                      U5D1             CU76     SKX_EXT_B_BGA1-IC,TBD
GND                      U5D1             CU78     SKX_EXT_B_BGA1-IC,TBD
GND                      U5D1             CU80     SKX_EXT_B_BGA1-IC,TBD
GND                      U5D1             CU82     SKX_EXT_B_BGA1-IC,TBD
GND                      U5D1             CU86     SKX_EXT_B_BGA1-IC,TBD
GND                      U5D1             CV1      SKX_EXT_B_BGA1-IC,TBD
GND                      U5D1             CV17     SKX_EXT_B_BGA1-IC,TBD
GND                      U5D1             CV19     SKX_EXT_B_BGA1-IC,TBD
GND                      U5D1             CV25     SKX_EXT_B_BGA1-IC,TBD
GND                      U5D1             CV27     SKX_EXT_B_BGA1-IC,TBD
GND                      U5D1             CV31     SKX_EXT_B_BGA1-IC,TBD
GND                      U5D1             CV33     SKX_EXT_B_BGA1-IC,TBD
GND                      U5D1             CV37     SKX_EXT_B_BGA1-IC,TBD
GND                      U5D1             CV39     SKX_EXT_B_BGA1-IC,TBD
GND                      U5D1             CV41     SKX_EXT_B_BGA1-IC,TBD
GND                      U5D1             CV53     SKX_EXT_B_BGA1-IC,TBD
GND                      U5D1             CV55     SKX_EXT_B_BGA1-IC,TBD
GND                      U5D1             CV63     SKX_EXT_B_BGA1-IC,TBD
GND                      U5D1             CV67     SKX_EXT_B_BGA1-IC,TBD
GND                      U5D1             CV73     SKX_EXT_B_BGA1-IC,TBD
GND                      U5D1             CV79     SKX_EXT_B_BGA1-IC,TBD
GND                      U5D1             CV81     SKX_EXT_B_BGA1-IC,TBD
GND                      U5D1             CV83     SKX_EXT_B_BGA1-IC,TBD
GND                      U5D1             CW6      SKX_EXT_B_BGA1-IC,TBD
GND                      U5D1             CW12     SKX_EXT_B_BGA1-IC,TBD
GND                      U5D1             CW18     SKX_EXT_B_BGA1-IC,TBD
GND                      U5D1             CW20     SKX_EXT_B_BGA1-IC,TBD
GND                      U5D1             CW26     SKX_EXT_B_BGA1-IC,TBD
GND                      U5D1             CW32     SKX_EXT_B_BGA1-IC,TBD
GND                      U5D1             CW38     SKX_EXT_B_BGA1-IC,TBD
GND                      U5D1             CW40     SKX_EXT_B_BGA1-IC,TBD
GND                      U5D1             CW42     SKX_EXT_B_BGA1-IC,TBD
GND                      U5D1             CW52     SKX_EXT_B_BGA1-IC,TBD
GND                      U5D1             CW54     SKX_EXT_B_BGA1-IC,TBD
GND                      U5D1             CW64     SKX_EXT_B_BGA1-IC,TBD
GND                      U5D1             CW66     SKX_EXT_B_BGA1-IC,TBD
GND                      U5D1             CW68     SKX_EXT_B_BGA1-IC,TBD
GND                      U5D1             CW74     SKX_EXT_B_BGA1-IC,TBD
GND                      U5D1             CW78     SKX_EXT_B_BGA1-IC,TBD
GND                      U5D1             CW82     SKX_EXT_B_BGA1-IC,TBD
GND                      U5D1             CY1      SKX_EXT_B_BGA1-IC,TBD
GND                      U5D1             CY9      SKX_EXT_B_BGA1-IC,TBD
GND                      U5D1             CY13     SKX_EXT_B_BGA1-IC,TBD
GND                      U5D1             CY15     SKX_EXT_B_BGA1-IC,TBD
GND                      U5D1             CY19     SKX_EXT_B_BGA1-IC,TBD
GND                      U5D1             CY21     SKX_EXT_B_BGA1-IC,TBD
GND                      U5D1             CY41     SKX_EXT_B_BGA1-IC,TBD
GND                      U5D1             CY45     SKX_EXT_B_BGA1-IC,TBD
GND                      U5D1             CY51     SKX_EXT_B_BGA1-IC,TBD
GND                      U5D1             CY59     SKX_EXT_B_BGA1-IC,TBD
GND                      U5D1             CY61     SKX_EXT_B_BGA1-IC,TBD
GND                      U5D1             CY65     SKX_EXT_B_BGA1-IC,TBD
GND                      U5D1             CY69     SKX_EXT_B_BGA1-IC,TBD
GND                      U5D1             CY75     SKX_EXT_B_BGA1-IC,TBD
GND                      U5D1             CY77     SKX_EXT_B_BGA1-IC,TBD
GND                      U5D1             CY83     SKX_EXT_B_BGA1-IC,TBD
GND                      U5D1             CY85     SKX_EXT_B_BGA1-IC,TBD
GND                      U5D1             D3       SKX_EXT_B_BGA1-IC,TBD
GND                      U5D1             D11      SKX_EXT_B_BGA1-IC,TBD
GND                      U5D1             D13      SKX_EXT_B_BGA1-IC,TBD
GND                      U5D1             D25      SKX_EXT_B_BGA1-IC,TBD
GND                      U5D1             D27      SKX_EXT_B_BGA1-IC,TBD
GND                      U5D1             D29      SKX_EXT_B_BGA1-IC,TBD
GND                      U5D1             D31      SKX_EXT_B_BGA1-IC,TBD
GND                      U5D1             D33      SKX_EXT_B_BGA1-IC,TBD
GND                      U5D1             D35      SKX_EXT_B_BGA1-IC,TBD
GND                      U5D1             D37      SKX_EXT_B_BGA1-IC,TBD
GND                      U5D1             D39      SKX_EXT_B_BGA1-IC,TBD
GND                      U5D1             D41      SKX_EXT_B_BGA1-IC,TBD
GND                      U5D1             D43      SKX_EXT_B_BGA1-IC,TBD
GND                      U5D1             D77      SKX_EXT_B_BGA1-IC,TBD
GND                      U5D1             D81      SKX_EXT_B_BGA1-IC,TBD
GND                      U5D1             DA6      SKX_EXT_B_BGA1-IC,TBD
GND                      U5D1             DA18     SKX_EXT_B_BGA1-IC,TBD
GND                      U5D1             DA20     SKX_EXT_B_BGA1-IC,TBD
GND                      U5D1             DA22     SKX_EXT_B_BGA1-IC,TBD
GND                      U5D1             DA26     SKX_EXT_B_BGA1-IC,TBD
GND                      U5D1             DA28     SKX_EXT_B_BGA1-IC,TBD
GND                      U5D1             DA30     SKX_EXT_B_BGA1-IC,TBD
GND                      U5D1             DA32     SKX_EXT_B_BGA1-IC,TBD
GND                      U5D1             DA34     SKX_EXT_B_BGA1-IC,TBD
GND                      U5D1             DA36     SKX_EXT_B_BGA1-IC,TBD
GND                      U5D1             DA38     SKX_EXT_B_BGA1-IC,TBD
GND                      U5D1             DA44     SKX_EXT_B_BGA1-IC,TBD
GND                      U5D1             DA46     SKX_EXT_B_BGA1-IC,TBD
GND                      U5D1             DA48     SKX_EXT_B_BGA1-IC,TBD
GND                      U5D1             DA50     SKX_EXT_B_BGA1-IC,TBD
GND                      U5D1             DA64     SKX_EXT_B_BGA1-IC,TBD
GND                      U5D1             DA70     SKX_EXT_B_BGA1-IC,TBD
GND                      U5D1             DA74     SKX_EXT_B_BGA1-IC,TBD
GND                      U5D1             DA76     SKX_EXT_B_BGA1-IC,TBD
GND                      U5D1             DA78     SKX_EXT_B_BGA1-IC,TBD
GND                      U5D1             DA80     SKX_EXT_B_BGA1-IC,TBD
GND                      U5D1             DB3      SKX_EXT_B_BGA1-IC,TBD
GND                      U5D1             DB7      SKX_EXT_B_BGA1-IC,TBD
GND                      U5D1             DB13     SKX_EXT_B_BGA1-IC,TBD
GND                      U5D1             DB17     SKX_EXT_B_BGA1-IC,TBD
GND                      U5D1             DB19     SKX_EXT_B_BGA1-IC,TBD
GND                      U5D1             DB21     SKX_EXT_B_BGA1-IC,TBD
GND                      U5D1             DB23     SKX_EXT_B_BGA1-IC,TBD
GND                      U5D1             DB25     SKX_EXT_B_BGA1-IC,TBD
GND                      U5D1             DB39     SKX_EXT_B_BGA1-IC,TBD
GND                      U5D1             DB41     SKX_EXT_B_BGA1-IC,TBD
GND                      U5D1             DB47     SKX_EXT_B_BGA1-IC,TBD
GND                      U5D1             DB49     SKX_EXT_B_BGA1-IC,TBD
GND                      U5D1             DB73     SKX_EXT_B_BGA1-IC,TBD
GND                      U5D1             DB77     SKX_EXT_B_BGA1-IC,TBD
GND                      U5D1             DB83     SKX_EXT_B_BGA1-IC,TBD
GND                      U5D1             DB85     SKX_EXT_B_BGA1-IC,TBD
GND                      U5D1             DC14     SKX_EXT_B_BGA1-IC,TBD
GND                      U5D1             DC20     SKX_EXT_B_BGA1-IC,TBD
GND                      U5D1             DC22     SKX_EXT_B_BGA1-IC,TBD
GND                      U5D1             DC24     SKX_EXT_B_BGA1-IC,TBD
GND                      U5D1             DC26     SKX_EXT_B_BGA1-IC,TBD
GND                      U5D1             DC32     SKX_EXT_B_BGA1-IC,TBD
GND                      U5D1             DC38     SKX_EXT_B_BGA1-IC,TBD
GND                      U5D1             DC42     SKX_EXT_B_BGA1-IC,TBD
GND                      U5D1             DC64     SKX_EXT_B_BGA1-IC,TBD
GND                      U5D1             DC66     SKX_EXT_B_BGA1-IC,TBD
GND                      U5D1             DC68     SKX_EXT_B_BGA1-IC,TBD
GND                      U5D1             DC70     SKX_EXT_B_BGA1-IC,TBD
GND                      U5D1             DC78     SKX_EXT_B_BGA1-IC,TBD
GND                      U5D1             DC84     SKX_EXT_B_BGA1-IC,TBD
GND                      U5D1             DC86     SKX_EXT_B_BGA1-IC,TBD
GND                      U5D1             DD11     SKX_EXT_B_BGA1-IC,TBD
GND                      U5D1             DD19     SKX_EXT_B_BGA1-IC,TBD
GND                      U5D1             DD21     SKX_EXT_B_BGA1-IC,TBD
GND                      U5D1             DD23     SKX_EXT_B_BGA1-IC,TBD
GND                      U5D1             DD27     SKX_EXT_B_BGA1-IC,TBD
GND                      U5D1             DD31     SKX_EXT_B_BGA1-IC,TBD
GND                      U5D1             DD33     SKX_EXT_B_BGA1-IC,TBD
GND                      U5D1             DD37     SKX_EXT_B_BGA1-IC,TBD
GND                      U5D1             DD71     SKX_EXT_B_BGA1-IC,TBD
GND                      U5D1             DD73     SKX_EXT_B_BGA1-IC,TBD
GND                      U5D1             DD75     SKX_EXT_B_BGA1-IC,TBD
GND                      U5D1             DD81     SKX_EXT_B_BGA1-IC,TBD
GND                      U5D1             DD83     SKX_EXT_B_BGA1-IC,TBD
GND                      U5D1             DE6      SKX_EXT_B_BGA1-IC,TBD
GND                      U5D1             DE8      SKX_EXT_B_BGA1-IC,TBD
GND                      U5D1             DE18     SKX_EXT_B_BGA1-IC,TBD
GND                      U5D1             DE20     SKX_EXT_B_BGA1-IC,TBD
GND                      U5D1             DE22     SKX_EXT_B_BGA1-IC,TBD
GND                      U5D1             DE24     SKX_EXT_B_BGA1-IC,TBD
GND                      U5D1             DE28     SKX_EXT_B_BGA1-IC,TBD
GND                      U5D1             DE30     SKX_EXT_B_BGA1-IC,TBD
GND                      U5D1             DE34     SKX_EXT_B_BGA1-IC,TBD
GND                      U5D1             DE36     SKX_EXT_B_BGA1-IC,TBD
GND                      U5D1             DE48     SKX_EXT_B_BGA1-IC,TBD
GND                      U5D1             DE50     SKX_EXT_B_BGA1-IC,TBD
GND                      U5D1             DE52     SKX_EXT_B_BGA1-IC,TBD
GND                      U5D1             DE54     SKX_EXT_B_BGA1-IC,TBD
GND                      U5D1             DE56     SKX_EXT_B_BGA1-IC,TBD
GND                      U5D1             DE58     SKX_EXT_B_BGA1-IC,TBD
GND                      U5D1             DE60     SKX_EXT_B_BGA1-IC,TBD
GND                      U5D1             DE62     SKX_EXT_B_BGA1-IC,TBD
GND                      U5D1             DE64     SKX_EXT_B_BGA1-IC,TBD
GND                      U5D1             DE70     SKX_EXT_B_BGA1-IC,TBD
GND                      U5D1             DE72     SKX_EXT_B_BGA1-IC,TBD
GND                      U5D1             DE78     SKX_EXT_B_BGA1-IC,TBD
GND                      U5D1             DF5      SKX_EXT_B_BGA1-IC,TBD
GND                      U5D1             DF7      SKX_EXT_B_BGA1-IC,TBD
GND                      U5D1             DF19     SKX_EXT_B_BGA1-IC,TBD
GND                      U5D1             DF23     SKX_EXT_B_BGA1-IC,TBD
GND                      U5D1             DF29     SKX_EXT_B_BGA1-IC,TBD
GND                      U5D1             DF35     SKX_EXT_B_BGA1-IC,TBD
GND                      U5D1             DF37     SKX_EXT_B_BGA1-IC,TBD
GND                      U5D1             DF39     SKX_EXT_B_BGA1-IC,TBD
GND                      U5D1             DF41     SKX_EXT_B_BGA1-IC,TBD
GND                      U5D1             DF65     SKX_EXT_B_BGA1-IC,TBD
GND                      U5D1             DF69     SKX_EXT_B_BGA1-IC,TBD
GND                      U5D1             DF73     SKX_EXT_B_BGA1-IC,TBD
GND                      U5D1             DF79     SKX_EXT_B_BGA1-IC,TBD
GND                      U5D1             DF83     SKX_EXT_B_BGA1-IC,TBD
GND                      U5D1             DF85     SKX_EXT_B_BGA1-IC,TBD
GND                      U5D1             DG2      SKX_EXT_B_BGA1-IC,TBD
GND                      U5D1             DG14     SKX_EXT_B_BGA1-IC,TBD
GND                      U5D1             DG16     SKX_EXT_B_BGA1-IC,TBD
GND                      U5D1             DG22     SKX_EXT_B_BGA1-IC,TBD
GND                      U5D1             DG24     SKX_EXT_B_BGA1-IC,TBD
GND                      U5D1             DG66     SKX_EXT_B_BGA1-IC,TBD
GND                      U5D1             DG68     SKX_EXT_B_BGA1-IC,TBD
GND                      U5D1             DG76     SKX_EXT_B_BGA1-IC,TBD
GND                      U5D1             DG78     SKX_EXT_B_BGA1-IC,TBD
GND                      U5D1             DG80     SKX_EXT_B_BGA1-IC,TBD
GND                      U5D1             DG82     SKX_EXT_B_BGA1-IC,TBD
GND                      U5D1             DH13     SKX_EXT_B_BGA1-IC,TBD
GND                      U5D1             DH15     SKX_EXT_B_BGA1-IC,TBD
GND                      U5D1             DH21     SKX_EXT_B_BGA1-IC,TBD
GND                      U5D1             DH23     SKX_EXT_B_BGA1-IC,TBD
GND                      U5D1             DH25     SKX_EXT_B_BGA1-IC,TBD
GND                      U5D1             DH27     SKX_EXT_B_BGA1-IC,TBD
GND                      U5D1             DH29     SKX_EXT_B_BGA1-IC,TBD
GND                      U5D1             DH31     SKX_EXT_B_BGA1-IC,TBD
GND                      U5D1             DH33     SKX_EXT_B_BGA1-IC,TBD
GND                      U5D1             DH35     SKX_EXT_B_BGA1-IC,TBD
GND                      U5D1             DH37     SKX_EXT_B_BGA1-IC,TBD
GND                      U5D1             DH41     SKX_EXT_B_BGA1-IC,TBD
GND                      U5D1             DH67     SKX_EXT_B_BGA1-IC,TBD
GND                      U5D1             DH71     SKX_EXT_B_BGA1-IC,TBD
GND                      U5D1             DH73     SKX_EXT_B_BGA1-IC,TBD
GND                      U5D1             DH79     SKX_EXT_B_BGA1-IC,TBD
GND                      U5D1             DH81     SKX_EXT_B_BGA1-IC,TBD
GND                      U5D1             DH83     SKX_EXT_B_BGA1-IC,TBD
GND                      U5D1             DJ2      SKX_EXT_B_BGA1-IC,TBD
GND                      U5D1             DJ10     SKX_EXT_B_BGA1-IC,TBD
GND                      U5D1             DJ22     SKX_EXT_B_BGA1-IC,TBD
GND                      U5D1             DJ38     SKX_EXT_B_BGA1-IC,TBD
GND                      U5D1             DJ42     SKX_EXT_B_BGA1-IC,TBD
GND                      U5D1             DJ68     SKX_EXT_B_BGA1-IC,TBD
GND                      U5D1             DJ74     SKX_EXT_B_BGA1-IC,TBD
GND                      U5D1             DJ78     SKX_EXT_B_BGA1-IC,TBD
GND                      U5D1             DJ82     SKX_EXT_B_BGA1-IC,TBD
GND                      U5D1             DJ84     SKX_EXT_B_BGA1-IC,TBD
GND                      U5D1             DK7      SKX_EXT_B_BGA1-IC,TBD
GND                      U5D1             DK23     SKX_EXT_B_BGA1-IC,TBD
GND                      U5D1             DK29     SKX_EXT_B_BGA1-IC,TBD
GND                      U5D1             DK35     SKX_EXT_B_BGA1-IC,TBD
GND                      U5D1             DK39     SKX_EXT_B_BGA1-IC,TBD
GND                      U5D1             DK41     SKX_EXT_B_BGA1-IC,TBD
GND                      U5D1             DK73     SKX_EXT_B_BGA1-IC,TBD
GND                      U5D1             DK75     SKX_EXT_B_BGA1-IC,TBD
GND                      U5D1             DK77     SKX_EXT_B_BGA1-IC,TBD
GND                      U5D1             DK83     SKX_EXT_B_BGA1-IC,TBD
GND                      U5D1             DK85     SKX_EXT_B_BGA1-IC,TBD
GND                      U5D1             DL4      SKX_EXT_B_BGA1-IC,TBD
GND                      U5D1             DL8      SKX_EXT_B_BGA1-IC,TBD
GND                      U5D1             DL16     SKX_EXT_B_BGA1-IC,TBD
GND                      U5D1             DL18     SKX_EXT_B_BGA1-IC,TBD
GND                      U5D1             DL22     SKX_EXT_B_BGA1-IC,TBD
GND                      U5D1             DL24     SKX_EXT_B_BGA1-IC,TBD
GND                      U5D1             DL28     SKX_EXT_B_BGA1-IC,TBD
GND                      U5D1             DL30     SKX_EXT_B_BGA1-IC,TBD
GND                      U5D1             DL34     SKX_EXT_B_BGA1-IC,TBD
GND                      U5D1             DL36     SKX_EXT_B_BGA1-IC,TBD
GND                      U5D1             DL40     SKX_EXT_B_BGA1-IC,TBD
GND                      U5D1             DL68     SKX_EXT_B_BGA1-IC,TBD
GND                      U5D1             DL70     SKX_EXT_B_BGA1-IC,TBD
GND                      U5D1             DL74     SKX_EXT_B_BGA1-IC,TBD
GND                      U5D1             DL76     SKX_EXT_B_BGA1-IC,TBD
GND                      U5D1             DL78     SKX_EXT_B_BGA1-IC,TBD
GND                      U5D1             DL80     SKX_EXT_B_BGA1-IC,TBD
GND                      U5D1             DM15     SKX_EXT_B_BGA1-IC,TBD
GND                      U5D1             DM19     SKX_EXT_B_BGA1-IC,TBD
GND                      U5D1             DM25     SKX_EXT_B_BGA1-IC,TBD
GND                      U5D1             DM27     SKX_EXT_B_BGA1-IC,TBD
GND                      U5D1             DM31     SKX_EXT_B_BGA1-IC,TBD
GND                      U5D1             DM33     SKX_EXT_B_BGA1-IC,TBD
GND                      U5D1             DM37     SKX_EXT_B_BGA1-IC,TBD
GND                      U5D1             DM39     SKX_EXT_B_BGA1-IC,TBD
GND                      U5D1             DM65     SKX_EXT_B_BGA1-IC,TBD
GND                      U5D1             DM73     SKX_EXT_B_BGA1-IC,TBD
GND                      U5D1             DM77     SKX_EXT_B_BGA1-IC,TBD
GND                      U5D1             DM83     SKX_EXT_B_BGA1-IC,TBD
GND                      U5D1             DN2      SKX_EXT_B_BGA1-IC,TBD
GND                      U5D1             DN12     SKX_EXT_B_BGA1-IC,TBD
GND                      U5D1             DN18     SKX_EXT_B_BGA1-IC,TBD
GND                      U5D1             DN22     SKX_EXT_B_BGA1-IC,TBD
GND                      U5D1             DN26     SKX_EXT_B_BGA1-IC,TBD
GND                      U5D1             DN32     SKX_EXT_B_BGA1-IC,TBD
GND                      U5D1             DN38     SKX_EXT_B_BGA1-IC,TBD
GND                      U5D1             DN44     SKX_EXT_B_BGA1-IC,TBD
GND                      U5D1             DN68     SKX_EXT_B_BGA1-IC,TBD
GND                      U5D1             DN72     SKX_EXT_B_BGA1-IC,TBD
GND                      U5D1             DN78     SKX_EXT_B_BGA1-IC,TBD
GND                      U5D1             DP9      SKX_EXT_B_BGA1-IC,TBD
GND                      U5D1             DP45     SKX_EXT_B_BGA1-IC,TBD
GND                      U5D1             DP47     SKX_EXT_B_BGA1-IC,TBD
GND                      U5D1             DP49     SKX_EXT_B_BGA1-IC,TBD
GND                      U5D1             DP51     SKX_EXT_B_BGA1-IC,TBD
GND                      U5D1             DP53     SKX_EXT_B_BGA1-IC,TBD
GND                      U5D1             DP55     SKX_EXT_B_BGA1-IC,TBD
GND                      U5D1             DP57     SKX_EXT_B_BGA1-IC,TBD
GND                      U5D1             DP59     SKX_EXT_B_BGA1-IC,TBD
GND                      U5D1             DP61     SKX_EXT_B_BGA1-IC,TBD
GND                      U5D1             DP63     SKX_EXT_B_BGA1-IC,TBD
GND                      U5D1             DP67     SKX_EXT_B_BGA1-IC,TBD
GND                      U5D1             DP69     SKX_EXT_B_BGA1-IC,TBD
GND                      U5D1             DP71     SKX_EXT_B_BGA1-IC,TBD
GND                      U5D1             DP81     SKX_EXT_B_BGA1-IC,TBD
GND                      U5D1             DP83     SKX_EXT_B_BGA1-IC,TBD
GND                      U5D1             DR6      SKX_EXT_B_BGA1-IC,TBD
GND                      U5D1             DR20     SKX_EXT_B_BGA1-IC,TBD
GND                      U5D1             DR22     SKX_EXT_B_BGA1-IC,TBD
GND                      U5D1             DR24     SKX_EXT_B_BGA1-IC,TBD
GND                      U5D1             DR26     SKX_EXT_B_BGA1-IC,TBD
GND                      U5D1             DR28     SKX_EXT_B_BGA1-IC,TBD
GND                      U5D1             DR30     SKX_EXT_B_BGA1-IC,TBD
GND                      U5D1             DR32     SKX_EXT_B_BGA1-IC,TBD
GND                      U5D1             DR34     SKX_EXT_B_BGA1-IC,TBD
GND                      U5D1             DR36     SKX_EXT_B_BGA1-IC,TBD
GND                      U5D1             DR38     SKX_EXT_B_BGA1-IC,TBD
GND                      U5D1             DR40     SKX_EXT_B_BGA1-IC,TBD
GND                      U5D1             DR42     SKX_EXT_B_BGA1-IC,TBD
GND                      U5D1             DR66     SKX_EXT_B_BGA1-IC,TBD
GND                      U5D1             DR68     SKX_EXT_B_BGA1-IC,TBD
GND                      U5D1             DR70     SKX_EXT_B_BGA1-IC,TBD
GND                      U5D1             DR72     SKX_EXT_B_BGA1-IC,TBD
GND                      U5D1             DR74     SKX_EXT_B_BGA1-IC,TBD
GND                      U5D1             DR76     SKX_EXT_B_BGA1-IC,TBD
GND                      U5D1             DR78     SKX_EXT_B_BGA1-IC,TBD
GND                      U5D1             DT3      SKX_EXT_B_BGA1-IC,TBD
GND                      U5D1             DT17     SKX_EXT_B_BGA1-IC,TBD
GND                      U5D1             DT65     SKX_EXT_B_BGA1-IC,TBD
GND                      U5D1             DT69     SKX_EXT_B_BGA1-IC,TBD
GND                      U5D1             DT79     SKX_EXT_B_BGA1-IC,TBD
GND                      U5D1             DT83     SKX_EXT_B_BGA1-IC,TBD
GND                      U5D1             DT85     SKX_EXT_B_BGA1-IC,TBD
GND                      U5D1             DU10     SKX_EXT_B_BGA1-IC,TBD
GND                      U5D1             DU14     SKX_EXT_B_BGA1-IC,TBD
GND                      U5D1             DU22     SKX_EXT_B_BGA1-IC,TBD
GND                      U5D1             DU26     SKX_EXT_B_BGA1-IC,TBD
GND                      U5D1             DU32     SKX_EXT_B_BGA1-IC,TBD
GND                      U5D1             DU38     SKX_EXT_B_BGA1-IC,TBD
GND                      U5D1             DU70     SKX_EXT_B_BGA1-IC,TBD
GND                      U5D1             DU72     SKX_EXT_B_BGA1-IC,TBD
GND                      U5D1             DU78     SKX_EXT_B_BGA1-IC,TBD
GND                      U5D1             DU80     SKX_EXT_B_BGA1-IC,TBD
GND                      U5D1             DU82     SKX_EXT_B_BGA1-IC,TBD
GND                      U5D1             DU84     SKX_EXT_B_BGA1-IC,TBD
GND                      U5D1             DV19     SKX_EXT_B_BGA1-IC,TBD
GND                      U5D1             DV21     SKX_EXT_B_BGA1-IC,TBD
GND                      U5D1             DV25     SKX_EXT_B_BGA1-IC,TBD
GND                      U5D1             DV27     SKX_EXT_B_BGA1-IC,TBD
GND                      U5D1             DV31     SKX_EXT_B_BGA1-IC,TBD
GND                      U5D1             DV33     SKX_EXT_B_BGA1-IC,TBD
GND                      U5D1             DV37     SKX_EXT_B_BGA1-IC,TBD
GND                      U5D1             DV39     SKX_EXT_B_BGA1-IC,TBD
GND                      U5D1             DV73     SKX_EXT_B_BGA1-IC,TBD
GND                      U5D1             DV77     SKX_EXT_B_BGA1-IC,TBD
GND                      U5D1             DV81     SKX_EXT_B_BGA1-IC,TBD
GND                      U5D1             DW2      SKX_EXT_B_BGA1-IC,TBD
GND                      U5D1             DW8      SKX_EXT_B_BGA1-IC,TBD
GND                      U5D1             DW12     SKX_EXT_B_BGA1-IC,TBD
GND                      U5D1             DW20     SKX_EXT_B_BGA1-IC,TBD
GND                      U5D1             DW24     SKX_EXT_B_BGA1-IC,TBD
GND                      U5D1             DW28     SKX_EXT_B_BGA1-IC,TBD
GND                      U5D1             DW30     SKX_EXT_B_BGA1-IC,TBD
GND                      U5D1             DW34     SKX_EXT_B_BGA1-IC,TBD
GND                      U5D1             DW36     SKX_EXT_B_BGA1-IC,TBD
GND                      U5D1             DW40     SKX_EXT_B_BGA1-IC,TBD
GND                      U5D1             DW64     SKX_EXT_B_BGA1-IC,TBD
GND                      U5D1             DW66     SKX_EXT_B_BGA1-IC,TBD
GND                      U5D1             DW68     SKX_EXT_B_BGA1-IC,TBD
GND                      U5D1             DW70     SKX_EXT_B_BGA1-IC,TBD
GND                      U5D1             DW72     SKX_EXT_B_BGA1-IC,TBD
GND                      U5D1             DW74     SKX_EXT_B_BGA1-IC,TBD
GND                      U5D1             DW76     SKX_EXT_B_BGA1-IC,TBD
GND                      U5D1             DW82     SKX_EXT_B_BGA1-IC,TBD
GND                      U5D1             DW84     SKX_EXT_B_BGA1-IC,TBD
GND                      U5D1             DY5      SKX_EXT_B_BGA1-IC,TBD
GND                      U5D1             DY19     SKX_EXT_B_BGA1-IC,TBD
GND                      U5D1             DY23     SKX_EXT_B_BGA1-IC,TBD
GND                      U5D1             DY29     SKX_EXT_B_BGA1-IC,TBD
GND                      U5D1             DY35     SKX_EXT_B_BGA1-IC,TBD
GND                      U5D1             DY41     SKX_EXT_B_BGA1-IC,TBD
GND                      U5D1             DY45     SKX_EXT_B_BGA1-IC,TBD
GND                      U5D1             DY47     SKX_EXT_B_BGA1-IC,TBD
GND                      U5D1             DY49     SKX_EXT_B_BGA1-IC,TBD
GND                      U5D1             DY51     SKX_EXT_B_BGA1-IC,TBD
GND                      U5D1             DY53     SKX_EXT_B_BGA1-IC,TBD
GND                      U5D1             DY55     SKX_EXT_B_BGA1-IC,TBD
GND                      U5D1             DY57     SKX_EXT_B_BGA1-IC,TBD
GND                      U5D1             DY59     SKX_EXT_B_BGA1-IC,TBD
GND                      U5D1             DY61     SKX_EXT_B_BGA1-IC,TBD
GND                      U5D1             DY63     SKX_EXT_B_BGA1-IC,TBD
GND                      U5D1             DY71     SKX_EXT_B_BGA1-IC,TBD
GND                      U5D1             DY75     SKX_EXT_B_BGA1-IC,TBD
GND                      U5D1             DY85     SKX_EXT_B_BGA1-IC,TBD
GND                      U5D1             E6       SKX_EXT_B_BGA1-IC,TBD
GND                      U5D1             E8       SKX_EXT_B_BGA1-IC,TBD
GND                      U5D1             E16      SKX_EXT_B_BGA1-IC,TBD
GND                      U5D1             E18      SKX_EXT_B_BGA1-IC,TBD
GND                      U5D1             E20      SKX_EXT_B_BGA1-IC,TBD
GND                      U5D1             E22      SKX_EXT_B_BGA1-IC,TBD
GND                      U5D1             E66      SKX_EXT_B_BGA1-IC,TBD
GND                      U5D1             E72      SKX_EXT_B_BGA1-IC,TBD
GND                      U5D1             E74      SKX_EXT_B_BGA1-IC,TBD
GND                      U5D1             E76      SKX_EXT_B_BGA1-IC,TBD
GND                      U5D1             E82      SKX_EXT_B_BGA1-IC,TBD
GND                      U5D1             EA6      SKX_EXT_B_BGA1-IC,TBD
GND                      U5D1             EA14     SKX_EXT_B_BGA1-IC,TBD
GND                      U5D1             EA16     SKX_EXT_B_BGA1-IC,TBD
GND                      U5D1             EA20     SKX_EXT_B_BGA1-IC,TBD
GND                      U5D1             EA22     SKX_EXT_B_BGA1-IC,TBD
GND                      U5D1             EA42     SKX_EXT_B_BGA1-IC,TBD
GND                      U5D1             EA64     SKX_EXT_B_BGA1-IC,TBD
GND                      U5D1             EA70     SKX_EXT_B_BGA1-IC,TBD
GND                      U5D1             EA76     SKX_EXT_B_BGA1-IC,TBD
GND                      U5D1             EA78     SKX_EXT_B_BGA1-IC,TBD
GND                      U5D1             EA80     SKX_EXT_B_BGA1-IC,TBD
GND                      U5D1             EA82     SKX_EXT_B_BGA1-IC,TBD
GND                      U5D1             EA84     SKX_EXT_B_BGA1-IC,TBD
GND                      U5D1             EB13     SKX_EXT_B_BGA1-IC,TBD
GND                      U5D1             EB23     SKX_EXT_B_BGA1-IC,TBD
GND                      U5D1             EB25     SKX_EXT_B_BGA1-IC,TBD
GND                      U5D1             EB27     SKX_EXT_B_BGA1-IC,TBD
GND                      U5D1             EB29     SKX_EXT_B_BGA1-IC,TBD
GND                      U5D1             EB31     SKX_EXT_B_BGA1-IC,TBD
GND                      U5D1             EB33     SKX_EXT_B_BGA1-IC,TBD
GND                      U5D1             EB35     SKX_EXT_B_BGA1-IC,TBD
GND                      U5D1             EB37     SKX_EXT_B_BGA1-IC,TBD
GND                      U5D1             EB39     SKX_EXT_B_BGA1-IC,TBD
GND                      U5D1             EB41     SKX_EXT_B_BGA1-IC,TBD
GND                      U5D1             EB65     SKX_EXT_B_BGA1-IC,TBD
GND                      U5D1             EB69     SKX_EXT_B_BGA1-IC,TBD
GND                      U5D1             EB83     SKX_EXT_B_BGA1-IC,TBD
GND                      U5D1             EC6      SKX_EXT_B_BGA1-IC,TBD
GND                      U5D1             EC10     SKX_EXT_B_BGA1-IC,TBD
GND                      U5D1             EC42     SKX_EXT_B_BGA1-IC,TBD
GND                      U5D1             EC70     SKX_EXT_B_BGA1-IC,TBD
GND                      U5D1             EC72     SKX_EXT_B_BGA1-IC,TBD
GND                      U5D1             EC74     SKX_EXT_B_BGA1-IC,TBD
GND                      U5D1             EC76     SKX_EXT_B_BGA1-IC,TBD
GND                      U5D1             EC82     SKX_EXT_B_BGA1-IC,TBD
GND                      U5D1             ED7      SKX_EXT_B_BGA1-IC,TBD
GND                      U5D1             ED11     SKX_EXT_B_BGA1-IC,TBD
GND                      U5D1             ED15     SKX_EXT_B_BGA1-IC,TBD
GND                      U5D1             ED23     SKX_EXT_B_BGA1-IC,TBD
GND                      U5D1             ED29     SKX_EXT_B_BGA1-IC,TBD
GND                      U5D1             ED35     SKX_EXT_B_BGA1-IC,TBD
GND                      U5D1             ED41     SKX_EXT_B_BGA1-IC,TBD
GND                      U5D1             ED69     SKX_EXT_B_BGA1-IC,TBD
GND                      U5D1             ED77     SKX_EXT_B_BGA1-IC,TBD
GND                      U5D1             ED81     SKX_EXT_B_BGA1-IC,TBD
GND                      U5D1             EE8      SKX_EXT_B_BGA1-IC,TBD
GND                      U5D1             EE24     SKX_EXT_B_BGA1-IC,TBD
GND                      U5D1             EE28     SKX_EXT_B_BGA1-IC,TBD
GND                      U5D1             EE30     SKX_EXT_B_BGA1-IC,TBD
GND                      U5D1             EE34     SKX_EXT_B_BGA1-IC,TBD
GND                      U5D1             EE36     SKX_EXT_B_BGA1-IC,TBD
GND                      U5D1             EE40     SKX_EXT_B_BGA1-IC,TBD
GND                      U5D1             EE70     SKX_EXT_B_BGA1-IC,TBD
GND                      U5D1             EE76     SKX_EXT_B_BGA1-IC,TBD
GND                      U5D1             EE78     SKX_EXT_B_BGA1-IC,TBD
GND                      U5D1             EE80     SKX_EXT_B_BGA1-IC,TBD
GND                      U5D1             EF71     SKX_EXT_B_BGA1-IC,TBD
GND                      U5D1             EF75     SKX_EXT_B_BGA1-IC,TBD
GND                      U5D1             EF79     SKX_EXT_B_BGA1-IC,TBD
GND                      U5D1             F5       SKX_EXT_B_BGA1-IC,TBD
GND                      U5D1             F17      SKX_EXT_B_BGA1-IC,TBD
GND                      U5D1             F19      SKX_EXT_B_BGA1-IC,TBD
GND                      U5D1             F25      SKX_EXT_B_BGA1-IC,TBD
GND                      U5D1             F31      SKX_EXT_B_BGA1-IC,TBD
GND                      U5D1             F37      SKX_EXT_B_BGA1-IC,TBD
GND                      U5D1             F43      SKX_EXT_B_BGA1-IC,TBD
GND                      U5D1             F67      SKX_EXT_B_BGA1-IC,TBD
GND                      U5D1             F69      SKX_EXT_B_BGA1-IC,TBD
GND                      U5D1             G4       SKX_EXT_B_BGA1-IC,TBD
GND                      U5D1             G8       SKX_EXT_B_BGA1-IC,TBD
GND                      U5D1             G22      SKX_EXT_B_BGA1-IC,TBD
GND                      U5D1             G24      SKX_EXT_B_BGA1-IC,TBD
GND                      U5D1             G26      SKX_EXT_B_BGA1-IC,TBD
GND                      U5D1             G30      SKX_EXT_B_BGA1-IC,TBD
GND                      U5D1             G32      SKX_EXT_B_BGA1-IC,TBD
GND                      U5D1             G36      SKX_EXT_B_BGA1-IC,TBD
GND                      U5D1             G38      SKX_EXT_B_BGA1-IC,TBD
GND                      U5D1             G42      SKX_EXT_B_BGA1-IC,TBD
GND                      U5D1             G66      SKX_EXT_B_BGA1-IC,TBD
GND                      U5D1             G70      SKX_EXT_B_BGA1-IC,TBD
GND                      U5D1             G76      SKX_EXT_B_BGA1-IC,TBD
GND                      U5D1             G78      SKX_EXT_B_BGA1-IC,TBD
GND                      U5D1             G80      SKX_EXT_B_BGA1-IC,TBD
GND                      U5D1             G82      SKX_EXT_B_BGA1-IC,TBD
GND                      U5D1             H3       SKX_EXT_B_BGA1-IC,TBD
GND                      U5D1             H11      SKX_EXT_B_BGA1-IC,TBD
GND                      U5D1             H25      SKX_EXT_B_BGA1-IC,TBD
GND                      U5D1             H27      SKX_EXT_B_BGA1-IC,TBD
GND                      U5D1             H29      SKX_EXT_B_BGA1-IC,TBD
GND                      U5D1             H31      SKX_EXT_B_BGA1-IC,TBD
GND                      U5D1             H33      SKX_EXT_B_BGA1-IC,TBD
GND                      U5D1             H35      SKX_EXT_B_BGA1-IC,TBD
GND                      U5D1             H37      SKX_EXT_B_BGA1-IC,TBD
GND                      U5D1             H39      SKX_EXT_B_BGA1-IC,TBD
GND                      U5D1             H41      SKX_EXT_B_BGA1-IC,TBD
GND                      U5D1             H45      SKX_EXT_B_BGA1-IC,TBD
GND                      U5D1             H47      SKX_EXT_B_BGA1-IC,TBD
GND                      U5D1             H49      SKX_EXT_B_BGA1-IC,TBD
GND                      U5D1             H51      SKX_EXT_B_BGA1-IC,TBD
GND                      U5D1             H53      SKX_EXT_B_BGA1-IC,TBD
GND                      U5D1             H55      SKX_EXT_B_BGA1-IC,TBD
GND                      U5D1             H57      SKX_EXT_B_BGA1-IC,TBD
GND                      U5D1             H59      SKX_EXT_B_BGA1-IC,TBD
GND                      U5D1             H61      SKX_EXT_B_BGA1-IC,TBD
GND                      U5D1             H63      SKX_EXT_B_BGA1-IC,TBD
GND                      U5D1             H65      SKX_EXT_B_BGA1-IC,TBD
GND                      U5D1             H71      SKX_EXT_B_BGA1-IC,TBD
GND                      U5D1             H75      SKX_EXT_B_BGA1-IC,TBD
GND                      U5D1             J4       SKX_EXT_B_BGA1-IC,TBD
GND                      U5D1             J12      SKX_EXT_B_BGA1-IC,TBD
GND                      U5D1             J14      SKX_EXT_B_BGA1-IC,TBD
GND                      U5D1             J16      SKX_EXT_B_BGA1-IC,TBD
GND                      U5D1             J22      SKX_EXT_B_BGA1-IC,TBD
GND                      U5D1             J26      SKX_EXT_B_BGA1-IC,TBD
GND                      U5D1             J28      SKX_EXT_B_BGA1-IC,TBD
GND                      U5D1             J32      SKX_EXT_B_BGA1-IC,TBD
GND                      U5D1             J34      SKX_EXT_B_BGA1-IC,TBD
GND                      U5D1             J38      SKX_EXT_B_BGA1-IC,TBD
GND                      U5D1             J40      SKX_EXT_B_BGA1-IC,TBD
GND                      U5D1             J72      SKX_EXT_B_BGA1-IC,TBD
GND                      U5D1             J74      SKX_EXT_B_BGA1-IC,TBD
GND                      U5D1             J76      SKX_EXT_B_BGA1-IC,TBD
GND                      U5D1             J82      SKX_EXT_B_BGA1-IC,TBD
GND                      U5D1             J84      SKX_EXT_B_BGA1-IC,TBD
GND                      U5D1             J86      SKX_EXT_B_BGA1-IC,TBD
GND                      U5D1             K1       SKX_EXT_B_BGA1-IC,TBD
GND                      U5D1             K11      SKX_EXT_B_BGA1-IC,TBD
GND                      U5D1             K13      SKX_EXT_B_BGA1-IC,TBD
GND                      U5D1             K17      SKX_EXT_B_BGA1-IC,TBD
GND                      U5D1             K27      SKX_EXT_B_BGA1-IC,TBD
GND                      U5D1             K33      SKX_EXT_B_BGA1-IC,TBD
GND                      U5D1             K39      SKX_EXT_B_BGA1-IC,TBD
GND                      U5D1             K65      SKX_EXT_B_BGA1-IC,TBD
GND                      U5D1             K67      SKX_EXT_B_BGA1-IC,TBD
GND                      U5D1             K69      SKX_EXT_B_BGA1-IC,TBD
GND                      U5D1             K71      SKX_EXT_B_BGA1-IC,TBD
GND                      U5D1             K73      SKX_EXT_B_BGA1-IC,TBD
GND                      U5D1             K77      SKX_EXT_B_BGA1-IC,TBD
GND                      U5D1             K81      SKX_EXT_B_BGA1-IC,TBD
GND                      U5D1             K83      SKX_EXT_B_BGA1-IC,TBD
GND                      U5D1             K85      SKX_EXT_B_BGA1-IC,TBD
GND                      U5D1             L2       SKX_EXT_B_BGA1-IC,TBD
GND                      U5D1             L6       SKX_EXT_B_BGA1-IC,TBD
GND                      U5D1             L8       SKX_EXT_B_BGA1-IC,TBD
GND                      U5D1             L10      SKX_EXT_B_BGA1-IC,TBD
GND                      U5D1             L20      SKX_EXT_B_BGA1-IC,TBD
GND                      U5D1             L22      SKX_EXT_B_BGA1-IC,TBD
GND                      U5D1             L72      SKX_EXT_B_BGA1-IC,TBD
GND                      U5D1             L78      SKX_EXT_B_BGA1-IC,TBD
GND                      U5D1             L80      SKX_EXT_B_BGA1-IC,TBD
GND                      U5D1             L82      SKX_EXT_B_BGA1-IC,TBD
GND                      U5D1             M15      SKX_EXT_B_BGA1-IC,TBD
GND                      U5D1             M17      SKX_EXT_B_BGA1-IC,TBD
GND                      U5D1             M19      SKX_EXT_B_BGA1-IC,TBD
GND                      U5D1             M23      SKX_EXT_B_BGA1-IC,TBD
GND                      U5D1             M25      SKX_EXT_B_BGA1-IC,TBD
GND                      U5D1             M27      SKX_EXT_B_BGA1-IC,TBD
GND                      U5D1             M29      SKX_EXT_B_BGA1-IC,TBD
GND                      U5D1             M31      SKX_EXT_B_BGA1-IC,TBD
GND                      U5D1             M33      SKX_EXT_B_BGA1-IC,TBD
GND                      U5D1             M35      SKX_EXT_B_BGA1-IC,TBD
GND                      U5D1             M37      SKX_EXT_B_BGA1-IC,TBD
GND                      U5D1             M39      SKX_EXT_B_BGA1-IC,TBD
GND                      U5D1             M41      SKX_EXT_B_BGA1-IC,TBD
GND                      U5D1             M43      SKX_EXT_B_BGA1-IC,TBD
GND                      U5D1             M65      SKX_EXT_B_BGA1-IC,TBD
GND                      U5D1             M71      SKX_EXT_B_BGA1-IC,TBD
GND                      U5D1             M79      SKX_EXT_B_BGA1-IC,TBD
GND                      U5D1             M83      SKX_EXT_B_BGA1-IC,TBD
GND                      U5D1             M85      SKX_EXT_B_BGA1-IC,TBD
GND                      U5D1             N4       SKX_EXT_B_BGA1-IC,TBD
GND                      U5D1             N6       SKX_EXT_B_BGA1-IC,TBD
GND                      U5D1             N8       SKX_EXT_B_BGA1-IC,TBD
GND                      U5D1             N20      SKX_EXT_B_BGA1-IC,TBD
GND                      U5D1             N22      SKX_EXT_B_BGA1-IC,TBD
GND                      U5D1             N66      SKX_EXT_B_BGA1-IC,TBD
GND                      U5D1             N70      SKX_EXT_B_BGA1-IC,TBD
GND                      U5D1             N72      SKX_EXT_B_BGA1-IC,TBD
GND                      U5D1             N74      SKX_EXT_B_BGA1-IC,TBD
GND                      U5D1             N76      SKX_EXT_B_BGA1-IC,TBD
GND                      U5D1             N78      SKX_EXT_B_BGA1-IC,TBD
GND                      U5D1             P11      SKX_EXT_B_BGA1-IC,TBD
GND                      U5D1             P15      SKX_EXT_B_BGA1-IC,TBD
GND                      U5D1             P27      SKX_EXT_B_BGA1-IC,TBD
GND                      U5D1             P33      SKX_EXT_B_BGA1-IC,TBD
GND                      U5D1             P39      SKX_EXT_B_BGA1-IC,TBD
GND                      U5D1             P45      SKX_EXT_B_BGA1-IC,TBD
GND                      U5D1             P47      SKX_EXT_B_BGA1-IC,TBD
GND                      U5D1             P49      SKX_EXT_B_BGA1-IC,TBD
GND                      U5D1             P51      SKX_EXT_B_BGA1-IC,TBD
GND                      U5D1             P53      SKX_EXT_B_BGA1-IC,TBD
GND                      U5D1             P55      SKX_EXT_B_BGA1-IC,TBD
GND                      U5D1             P57      SKX_EXT_B_BGA1-IC,TBD
GND                      U5D1             P59      SKX_EXT_B_BGA1-IC,TBD
GND                      U5D1             P61      SKX_EXT_B_BGA1-IC,TBD
GND                      U5D1             P63      SKX_EXT_B_BGA1-IC,TBD
GND                      U5D1             P67      SKX_EXT_B_BGA1-IC,TBD
GND                      U5D1             P69      SKX_EXT_B_BGA1-IC,TBD
GND                      U5D1             P71      SKX_EXT_B_BGA1-IC,TBD
GND                      U5D1             P81      SKX_EXT_B_BGA1-IC,TBD
GND                      U5D1             P83      SKX_EXT_B_BGA1-IC,TBD
GND                      U5D1             R2       SKX_EXT_B_BGA1-IC,TBD
GND                      U5D1             R4       SKX_EXT_B_BGA1-IC,TBD
GND                      U5D1             R14      SKX_EXT_B_BGA1-IC,TBD
GND                      U5D1             R18      SKX_EXT_B_BGA1-IC,TBD
GND                      U5D1             R22      SKX_EXT_B_BGA1-IC,TBD
GND                      U5D1             R26      SKX_EXT_B_BGA1-IC,TBD
GND                      U5D1             R28      SKX_EXT_B_BGA1-IC,TBD
GND                      U5D1             R32      SKX_EXT_B_BGA1-IC,TBD
GND                      U5D1             R34      SKX_EXT_B_BGA1-IC,TBD
GND                      U5D1             R38      SKX_EXT_B_BGA1-IC,TBD
GND                      U5D1             R40      SKX_EXT_B_BGA1-IC,TBD
GND                      U5D1             R68      SKX_EXT_B_BGA1-IC,TBD
GND                      U5D1             R72      SKX_EXT_B_BGA1-IC,TBD
GND                      U5D1             R78      SKX_EXT_B_BGA1-IC,TBD
GND                      U5D1             R86      SKX_EXT_B_BGA1-IC,TBD
GND                      U5D1             T13      SKX_EXT_B_BGA1-IC,TBD
GND                      U5D1             T17      SKX_EXT_B_BGA1-IC,TBD
GND                      U5D1             T25      SKX_EXT_B_BGA1-IC,TBD
GND                      U5D1             T29      SKX_EXT_B_BGA1-IC,TBD
GND                      U5D1             T31      SKX_EXT_B_BGA1-IC,TBD
GND                      U5D1             T35      SKX_EXT_B_BGA1-IC,TBD
GND                      U5D1             T37      SKX_EXT_B_BGA1-IC,TBD
GND                      U5D1             T41      SKX_EXT_B_BGA1-IC,TBD
GND                      U5D1             T65      SKX_EXT_B_BGA1-IC,TBD
GND                      U5D1             T73      SKX_EXT_B_BGA1-IC,TBD
GND                      U5D1             T77      SKX_EXT_B_BGA1-IC,TBD
GND                      U5D1             T83      SKX_EXT_B_BGA1-IC,TBD
GND                      U5D1             T85      SKX_EXT_B_BGA1-IC,TBD
GND                      U5D1             U2       SKX_EXT_B_BGA1-IC,TBD
GND                      U5D1             U4       SKX_EXT_B_BGA1-IC,TBD
GND                      U5D1             U6       SKX_EXT_B_BGA1-IC,TBD
GND                      U5D1             U20      SKX_EXT_B_BGA1-IC,TBD
GND                      U5D1             U22      SKX_EXT_B_BGA1-IC,TBD
GND                      U5D1             U24      SKX_EXT_B_BGA1-IC,TBD
GND                      U5D1             U30      SKX_EXT_B_BGA1-IC,TBD
GND                      U5D1             U36      SKX_EXT_B_BGA1-IC,TBD
GND                      U5D1             U42      SKX_EXT_B_BGA1-IC,TBD
GND                      U5D1             U68      SKX_EXT_B_BGA1-IC,TBD
GND                      U5D1             U70      SKX_EXT_B_BGA1-IC,TBD
GND                      U5D1             U74      SKX_EXT_B_BGA1-IC,TBD
GND                      U5D1             U76      SKX_EXT_B_BGA1-IC,TBD
GND                      U5D1             U78      SKX_EXT_B_BGA1-IC,TBD
GND                      U5D1             U80      SKX_EXT_B_BGA1-IC,TBD
GND                      U5D1             U86      SKX_EXT_B_BGA1-IC,TBD
GND                      U5D1             V1       SKX_EXT_B_BGA1-IC,TBD
GND                      U5D1             V5       SKX_EXT_B_BGA1-IC,TBD
GND                      U5D1             V9       SKX_EXT_B_BGA1-IC,TBD
GND                      U5D1             V11      SKX_EXT_B_BGA1-IC,TBD
GND                      U5D1             V13      SKX_EXT_B_BGA1-IC,TBD
GND                      U5D1             V15      SKX_EXT_B_BGA1-IC,TBD
GND                      U5D1             V21      SKX_EXT_B_BGA1-IC,TBD
GND                      U5D1             V23      SKX_EXT_B_BGA1-IC,TBD
GND                      U5D1             V43      SKX_EXT_B_BGA1-IC,TBD
GND                      U5D1             V73      SKX_EXT_B_BGA1-IC,TBD
GND                      U5D1             V75      SKX_EXT_B_BGA1-IC,TBD
GND                      U5D1             V77      SKX_EXT_B_BGA1-IC,TBD
GND                      U5D1             V83      SKX_EXT_B_BGA1-IC,TBD
GND                      U5D1             W8       SKX_EXT_B_BGA1-IC,TBD
GND                      U5D1             W12      SKX_EXT_B_BGA1-IC,TBD
GND                      U5D1             W22      SKX_EXT_B_BGA1-IC,TBD
GND                      U5D1             W24      SKX_EXT_B_BGA1-IC,TBD
GND                      U5D1             W26      SKX_EXT_B_BGA1-IC,TBD
GND                      U5D1             W28      SKX_EXT_B_BGA1-IC,TBD
GND                      U5D1             W30      SKX_EXT_B_BGA1-IC,TBD
GND                      U5D1             W32      SKX_EXT_B_BGA1-IC,TBD
GND                      U5D1             W34      SKX_EXT_B_BGA1-IC,TBD
GND                      U5D1             W36      SKX_EXT_B_BGA1-IC,TBD
GND                      U5D1             W38      SKX_EXT_B_BGA1-IC,TBD
GND                      U5D1             W40      SKX_EXT_B_BGA1-IC,TBD
GND                      U5D1             W42      SKX_EXT_B_BGA1-IC,TBD
GND                      U5D1             W68      SKX_EXT_B_BGA1-IC,TBD
GND                      U5D1             W74      SKX_EXT_B_BGA1-IC,TBD
GND                      U5D1             W78      SKX_EXT_B_BGA1-IC,TBD
GND                      U5D1             W82      SKX_EXT_B_BGA1-IC,TBD
GND                      U5D1             Y5       SKX_EXT_B_BGA1-IC,TBD
GND                      U5D1             Y7       SKX_EXT_B_BGA1-IC,TBD
GND                      U5D1             Y9       SKX_EXT_B_BGA1-IC,TBD
GND                      U5D1             Y15      SKX_EXT_B_BGA1-IC,TBD
GND                      U5D1             Y17      SKX_EXT_B_BGA1-IC,TBD
GND                      U5D1             Y67      SKX_EXT_B_BGA1-IC,TBD
GND                      U5D1             Y71      SKX_EXT_B_BGA1-IC,TBD
GND                      U5D1             Y73      SKX_EXT_B_BGA1-IC,TBD
GND                      U5D1             Y79      SKX_EXT_B_BGA1-IC,TBD
GND                      U5D1             Y81      SKX_EXT_B_BGA1-IC,TBD
GND                      U5D1             Y83      SKX_EXT_B_BGA1-IC,TBD
GND                      U5D1             Y85      SKX_EXT_B_BGA1-IC,TBD
GND                      U7C1             A5       LBG_CORE_QAT_EXT_D_BGA1-IC,H91A
GND                      U7C1             A7       LBG_CORE_QAT_EXT_D_BGA1-IC,H91A
GND                      U7C1             A9       LBG_CORE_QAT_EXT_D_BGA1-IC,H91A
GND                      U7C1             A18      LBG_CORE_QAT_EXT_D_BGA1-IC,H91A
GND                      U7C1             A22      LBG_CORE_QAT_EXT_D_BGA1-IC,H91A
GND                      U7C1             A30      LBG_CORE_QAT_EXT_D_BGA1-IC,H91A
GND                      U7C1             A34      LBG_CORE_QAT_EXT_D_BGA1-IC,H91A
GND                      U7C1             A37      LBG_CORE_QAT_EXT_D_BGA1-IC,H91A
GND                      U7C1             A41      LBG_CORE_QAT_EXT_D_BGA1-IC,H91A
GND                      U7C1             A65      LBG_CORE_QAT_EXT_D_BGA1-IC,H91A
GND                      U7C1             A66      LBG_CORE_QAT_EXT_D_BGA1-IC,H91A
GND                      U7C1             A68      LBG_CORE_QAT_EXT_D_BGA1-IC,H91A
GND                      U7C1             A70      LBG_CORE_QAT_EXT_D_BGA1-IC,H91A
GND                      U7C1             AA26     LBG_CORE_QAT_EXT_D_BGA1-IC,H91A
GND                      U7C1             AA27     LBG_CORE_QAT_EXT_D_BGA1-IC,H91A
GND                      U7C1             AA43     LBG_CORE_QAT_EXT_D_BGA1-IC,H91A
GND                      U7C1             AA48     LBG_CORE_QAT_EXT_D_BGA1-IC,H91A
GND                      U7C1             AA50     LBG_CORE_QAT_EXT_D_BGA1-IC,H91A
GND                      U7C1             AB5      LBG_CORE_QAT_EXT_D_BGA1-IC,H91A
GND                      U7C1             AB68     LBG_CORE_QAT_EXT_D_BGA1-IC,H91A
GND                      U7C1             AB70     LBG_CORE_QAT_EXT_D_BGA1-IC,H91A
GND                      U7C1             AB72     LBG_CORE_QAT_EXT_D_BGA1-IC,H91A
GND                      U7C1             AC7      LBG_CORE_QAT_EXT_D_BGA1-IC,H91A
GND                      U7C1             AC11     LBG_CORE_QAT_EXT_D_BGA1-IC,H91A
GND                      U7C1             AC15     LBG_CORE_QAT_EXT_D_BGA1-IC,H91A
GND                      U7C1             AC18     LBG_CORE_QAT_EXT_D_BGA1-IC,H91A
GND                      U7C1             AC22     LBG_CORE_QAT_EXT_D_BGA1-IC,H91A
GND                      U7C1             AC27     LBG_CORE_QAT_EXT_D_BGA1-IC,H91A
GND                      U7C1             AC43     LBG_CORE_QAT_EXT_D_BGA1-IC,H91A
GND                      U7C1             AC45     LBG_CORE_QAT_EXT_D_BGA1-IC,H91A
GND                      U7C1             AC46     LBG_CORE_QAT_EXT_D_BGA1-IC,H91A
GND                      U7C1             AC48     LBG_CORE_QAT_EXT_D_BGA1-IC,H91A
GND                      U7C1             AC52     LBG_CORE_QAT_EXT_D_BGA1-IC,H91A
GND                      U7C1             AC59     LBG_CORE_QAT_EXT_D_BGA1-IC,H91A
GND                      U7C1             AC63     LBG_CORE_QAT_EXT_D_BGA1-IC,H91A
GND                      U7C1             AC66     LBG_CORE_QAT_EXT_D_BGA1-IC,H91A
GND                      U7C1             AD5      LBG_CORE_QAT_EXT_D_BGA1-IC,H91A
GND                      U7C1             AD58     LBG_CORE_QAT_EXT_D_BGA1-IC,H91A
GND                      U7C1             AD65     LBG_CORE_QAT_EXT_D_BGA1-IC,H91A
GND                      U7C1             AD68     LBG_CORE_QAT_EXT_D_BGA1-IC,H91A
GND                      U7C1             AE22     LBG_CORE_QAT_EXT_D_BGA1-IC,H91A
GND                      U7C1             AE29     LBG_CORE_QAT_EXT_D_BGA1-IC,H91A
GND                      U7C1             AE43     LBG_CORE_QAT_EXT_D_BGA1-IC,H91A
GND                      U7C1             AE48     LBG_CORE_QAT_EXT_D_BGA1-IC,H91A
GND                      U7C1             AE52     LBG_CORE_QAT_EXT_D_BGA1-IC,H91A
GND                      U7C1             AE56     LBG_CORE_QAT_EXT_D_BGA1-IC,H91A
GND                      U7C1             AE59     LBG_CORE_QAT_EXT_D_BGA1-IC,H91A
GND                      U7C1             AE63     LBG_CORE_QAT_EXT_D_BGA1-IC,H91A
GND                      U7C1             AE66     LBG_CORE_QAT_EXT_D_BGA1-IC,H91A
GND                      U7C1             AF1      LBG_CORE_QAT_EXT_D_BGA1-IC,H91A
GND                      U7C1             AF3      LBG_CORE_QAT_EXT_D_BGA1-IC,H91A
GND                      U7C1             AF5      LBG_CORE_QAT_EXT_D_BGA1-IC,H91A
GND                      U7C1             AF9      LBG_CORE_QAT_EXT_D_BGA1-IC,H91A
GND                      U7C1             AF13     LBG_CORE_QAT_EXT_D_BGA1-IC,H91A
GND                      U7C1             AF17     LBG_CORE_QAT_EXT_D_BGA1-IC,H91A
GND                      U7C1             AF24     LBG_CORE_QAT_EXT_D_BGA1-IC,H91A
GND                      U7C1             AF50     LBG_CORE_QAT_EXT_D_BGA1-IC,H91A
GND                      U7C1             AF68     LBG_CORE_QAT_EXT_D_BGA1-IC,H91A
GND                      U7C1             AG26     LBG_CORE_QAT_EXT_D_BGA1-IC,H91A
GND                      U7C1             AG30     LBG_CORE_QAT_EXT_D_BGA1-IC,H91A
GND                      U7C1             AG41     LBG_CORE_QAT_EXT_D_BGA1-IC,H91A
GND                      U7C1             AG43     LBG_CORE_QAT_EXT_D_BGA1-IC,H91A
GND                      U7C1             AG46     LBG_CORE_QAT_EXT_D_BGA1-IC,H91A
GND                      U7C1             AG52     LBG_CORE_QAT_EXT_D_BGA1-IC,H91A
GND                      U7C1             AG56     LBG_CORE_QAT_EXT_D_BGA1-IC,H91A
GND                      U7C1             AG59     LBG_CORE_QAT_EXT_D_BGA1-IC,H91A
GND                      U7C1             AG66     LBG_CORE_QAT_EXT_D_BGA1-IC,H91A
GND                      U7C1             AH20     LBG_CORE_QAT_EXT_D_BGA1-IC,H91A
GND                      U7C1             AJ5      LBG_CORE_QAT_EXT_D_BGA1-IC,H91A
GND                      U7C1             AJ7      LBG_CORE_QAT_EXT_D_BGA1-IC,H91A
GND                      U7C1             AJ11     LBG_CORE_QAT_EXT_D_BGA1-IC,H91A
GND                      U7C1             AJ15     LBG_CORE_QAT_EXT_D_BGA1-IC,H91A
GND                      U7C1             AJ18     LBG_CORE_QAT_EXT_D_BGA1-IC,H91A
GND                      U7C1             AJ22     LBG_CORE_QAT_EXT_D_BGA1-IC,H91A
GND                      U7C1             AJ26     LBG_CORE_QAT_EXT_D_BGA1-IC,H91A
GND                      U7C1             AJ30     LBG_CORE_QAT_EXT_D_BGA1-IC,H91A
GND                      U7C1             AJ32     LBG_CORE_QAT_EXT_D_BGA1-IC,H91A
GND                      U7C1             AJ34     LBG_CORE_QAT_EXT_D_BGA1-IC,H91A
GND                      U7C1             AJ36     LBG_CORE_QAT_EXT_D_BGA1-IC,H91A
GND                      U7C1             AJ37     LBG_CORE_QAT_EXT_D_BGA1-IC,H91A
GND                      U7C1             AJ39     LBG_CORE_QAT_EXT_D_BGA1-IC,H91A
GND                      U7C1             AJ41     LBG_CORE_QAT_EXT_D_BGA1-IC,H91A
GND                      U7C1             AJ45     LBG_CORE_QAT_EXT_D_BGA1-IC,H91A
GND                      U7C1             AJ52     LBG_CORE_QAT_EXT_D_BGA1-IC,H91A
GND                      U7C1             AJ56     LBG_CORE_QAT_EXT_D_BGA1-IC,H91A
GND                      U7C1             AJ59     LBG_CORE_QAT_EXT_D_BGA1-IC,H91A
GND                      U7C1             AJ66     LBG_CORE_QAT_EXT_D_BGA1-IC,H91A
GND                      U7C1             AJ68     LBG_CORE_QAT_EXT_D_BGA1-IC,H91A
GND                      U7C1             AK26     LBG_CORE_QAT_EXT_D_BGA1-IC,H91A
GND                      U7C1             AK30     LBG_CORE_QAT_EXT_D_BGA1-IC,H91A
GND                      U7C1             AK41     LBG_CORE_QAT_EXT_D_BGA1-IC,H91A
GND                      U7C1             AK46     LBG_CORE_QAT_EXT_D_BGA1-IC,H91A
GND                      U7C1             AK48     LBG_CORE_QAT_EXT_D_BGA1-IC,H91A
GND                      U7C1             AK58     LBG_CORE_QAT_EXT_D_BGA1-IC,H91A
GND                      U7C1             AK61     LBG_CORE_QAT_EXT_D_BGA1-IC,H91A
GND                      U7C1             AK69     LBG_CORE_QAT_EXT_D_BGA1-IC,H91A
GND                      U7C1             AK71     LBG_CORE_QAT_EXT_D_BGA1-IC,H91A
GND                      U7C1             AL5      LBG_CORE_QAT_EXT_D_BGA1-IC,H91A
GND                      U7C1             AL22     LBG_CORE_QAT_EXT_D_BGA1-IC,H91A
GND                      U7C1             AL52     LBG_CORE_QAT_EXT_D_BGA1-IC,H91A
GND                      U7C1             AL59     LBG_CORE_QAT_EXT_D_BGA1-IC,H91A
GND                      U7C1             AL68     LBG_CORE_QAT_EXT_D_BGA1-IC,H91A
GND                      U7C1             AL70     LBG_CORE_QAT_EXT_D_BGA1-IC,H91A
GND                      U7C1             AL72     LBG_CORE_QAT_EXT_D_BGA1-IC,H91A
GND                      U7C1             AM26     LBG_CORE_QAT_EXT_D_BGA1-IC,H91A
GND                      U7C1             AM30     LBG_CORE_QAT_EXT_D_BGA1-IC,H91A
GND                      U7C1             AM41     LBG_CORE_QAT_EXT_D_BGA1-IC,H91A
GND                      U7C1             AM46     LBG_CORE_QAT_EXT_D_BGA1-IC,H91A
GND                      U7C1             AN5      LBG_CORE_QAT_EXT_D_BGA1-IC,H91A
GND                      U7C1             AN9      LBG_CORE_QAT_EXT_D_BGA1-IC,H91A
GND                      U7C1             AN13     LBG_CORE_QAT_EXT_D_BGA1-IC,H91A
GND                      U7C1             AN17     LBG_CORE_QAT_EXT_D_BGA1-IC,H91A
GND                      U7C1             AN20     LBG_CORE_QAT_EXT_D_BGA1-IC,H91A
GND                      U7C1             AN58     LBG_CORE_QAT_EXT_D_BGA1-IC,H91A
GND                      U7C1             AN68     LBG_CORE_QAT_EXT_D_BGA1-IC,H91A
GND                      U7C1             AP2      LBG_CORE_QAT_EXT_D_BGA1-IC,H91A
GND                      U7C1             AP4      LBG_CORE_QAT_EXT_D_BGA1-IC,H91A
GND                      U7C1             AP22     LBG_CORE_QAT_EXT_D_BGA1-IC,H91A
GND                      U7C1             AP26     LBG_CORE_QAT_EXT_D_BGA1-IC,H91A
GND                      U7C1             AP30     LBG_CORE_QAT_EXT_D_BGA1-IC,H91A
GND                      U7C1             AP41     LBG_CORE_QAT_EXT_D_BGA1-IC,H91A
GND                      U7C1             AP46     LBG_CORE_QAT_EXT_D_BGA1-IC,H91A
GND                      U7C1             AP52     LBG_CORE_QAT_EXT_D_BGA1-IC,H91A
GND                      U7C1             AP66     LBG_CORE_QAT_EXT_D_BGA1-IC,H91A
GND                      U7C1             AR5      LBG_CORE_QAT_EXT_D_BGA1-IC,H91A
GND                      U7C1             AR50     LBG_CORE_QAT_EXT_D_BGA1-IC,H91A
GND                      U7C1             AR58     LBG_CORE_QAT_EXT_D_BGA1-IC,H91A
GND                      U7C1             AR65     LBG_CORE_QAT_EXT_D_BGA1-IC,H91A
GND                      U7C1             AR68     LBG_CORE_QAT_EXT_D_BGA1-IC,H91A
GND                      U7C1             AR70     LBG_CORE_QAT_EXT_D_BGA1-IC,H91A
GND                      U7C1             AR72     LBG_CORE_QAT_EXT_D_BGA1-IC,H91A
GND                      U7C1             AT7      LBG_CORE_QAT_EXT_D_BGA1-IC,H91A
GND                      U7C1             AT11     LBG_CORE_QAT_EXT_D_BGA1-IC,H91A
GND                      U7C1             AT15     LBG_CORE_QAT_EXT_D_BGA1-IC,H91A
GND                      U7C1             AT18     LBG_CORE_QAT_EXT_D_BGA1-IC,H91A
GND                      U7C1             AT22     LBG_CORE_QAT_EXT_D_BGA1-IC,H91A
GND                      U7C1             AT26     LBG_CORE_QAT_EXT_D_BGA1-IC,H91A
GND                      U7C1             AT30     LBG_CORE_QAT_EXT_D_BGA1-IC,H91A
GND                      U7C1             AT37     LBG_CORE_QAT_EXT_D_BGA1-IC,H91A
GND                      U7C1             AT41     LBG_CORE_QAT_EXT_D_BGA1-IC,H91A
GND                      U7C1             AT46     LBG_CORE_QAT_EXT_D_BGA1-IC,H91A
GND                      U7C1             AT59     LBG_CORE_QAT_EXT_D_BGA1-IC,H91A
GND                      U7C1             AU26     LBG_CORE_QAT_EXT_D_BGA1-IC,H91A
GND                      U7C1             AU30     LBG_CORE_QAT_EXT_D_BGA1-IC,H91A
GND                      U7C1             AU41     LBG_CORE_QAT_EXT_D_BGA1-IC,H91A
GND                      U7C1             AU46     LBG_CORE_QAT_EXT_D_BGA1-IC,H91A
GND                      U7C1             AU50     LBG_CORE_QAT_EXT_D_BGA1-IC,H91A
GND                      U7C1             AU54     LBG_CORE_QAT_EXT_D_BGA1-IC,H91A
GND                      U7C1             AU61     LBG_CORE_QAT_EXT_D_BGA1-IC,H91A
GND                      U7C1             AV5      LBG_CORE_QAT_EXT_D_BGA1-IC,H91A
GND                      U7C1             AV22     LBG_CORE_QAT_EXT_D_BGA1-IC,H91A
GND                      U7C1             AV59     LBG_CORE_QAT_EXT_D_BGA1-IC,H91A
GND                      U7C1             AV68     LBG_CORE_QAT_EXT_D_BGA1-IC,H91A
GND                      U7C1             AW9      LBG_CORE_QAT_EXT_D_BGA1-IC,H91A
GND                      U7C1             AW13     LBG_CORE_QAT_EXT_D_BGA1-IC,H91A
GND                      U7C1             AW17     LBG_CORE_QAT_EXT_D_BGA1-IC,H91A
GND                      U7C1             AW26     LBG_CORE_QAT_EXT_D_BGA1-IC,H91A
GND                      U7C1             AW30     LBG_CORE_QAT_EXT_D_BGA1-IC,H91A
GND                      U7C1             AW32     LBG_CORE_QAT_EXT_D_BGA1-IC,H91A
GND                      U7C1             AW34     LBG_CORE_QAT_EXT_D_BGA1-IC,H91A
GND                      U7C1             AW36     LBG_CORE_QAT_EXT_D_BGA1-IC,H91A
GND                      U7C1             AW37     LBG_CORE_QAT_EXT_D_BGA1-IC,H91A
GND                      U7C1             AW39     LBG_CORE_QAT_EXT_D_BGA1-IC,H91A
GND                      U7C1             AW41     LBG_CORE_QAT_EXT_D_BGA1-IC,H91A
GND                      U7C1             AW46     LBG_CORE_QAT_EXT_D_BGA1-IC,H91A
GND                      U7C1             AW50     LBG_CORE_QAT_EXT_D_BGA1-IC,H91A
GND                      U7C1             AW58     LBG_CORE_QAT_EXT_D_BGA1-IC,H91A
GND                      U7C1             AW61     LBG_CORE_QAT_EXT_D_BGA1-IC,H91A
GND                      U7C1             AY5      LBG_CORE_QAT_EXT_D_BGA1-IC,H91A
GND                      U7C1             AY22     LBG_CORE_QAT_EXT_D_BGA1-IC,H91A
GND                      U7C1             AY56     LBG_CORE_QAT_EXT_D_BGA1-IC,H91A
GND                      U7C1             AY63     LBG_CORE_QAT_EXT_D_BGA1-IC,H91A
GND                      U7C1             AY68     LBG_CORE_QAT_EXT_D_BGA1-IC,H91A
GND                      U7C1             B12      LBG_CORE_QAT_EXT_D_BGA1-IC,H91A
GND                      U7C1             B19      LBG_CORE_QAT_EXT_D_BGA1-IC,H91A
GND                      U7C1             B25      LBG_CORE_QAT_EXT_D_BGA1-IC,H91A
GND                      U7C1             B27      LBG_CORE_QAT_EXT_D_BGA1-IC,H91A
GND                      U7C1             B47      LBG_CORE_QAT_EXT_D_BGA1-IC,H91A
GND                      U7C1             BA50     LBG_CORE_QAT_EXT_D_BGA1-IC,H91A
GND                      U7C1             BA54     LBG_CORE_QAT_EXT_D_BGA1-IC,H91A
GND                      U7C1             BA58     LBG_CORE_QAT_EXT_D_BGA1-IC,H91A
GND                      U7C1             BB5      LBG_CORE_QAT_EXT_D_BGA1-IC,H91A
GND                      U7C1             BB7      LBG_CORE_QAT_EXT_D_BGA1-IC,H91A
GND                      U7C1             BB11     LBG_CORE_QAT_EXT_D_BGA1-IC,H91A
GND                      U7C1             BB15     LBG_CORE_QAT_EXT_D_BGA1-IC,H91A
GND                      U7C1             BB18     LBG_CORE_QAT_EXT_D_BGA1-IC,H91A
GND                      U7C1             BB22     LBG_CORE_QAT_EXT_D_BGA1-IC,H91A
GND                      U7C1             BB44     LBG_CORE_QAT_EXT_D_BGA1-IC,H91A
GND                      U7C1             BB48     LBG_CORE_QAT_EXT_D_BGA1-IC,H91A
GND                      U7C1             BB59     LBG_CORE_QAT_EXT_D_BGA1-IC,H91A
GND                      U7C1             BB66     LBG_CORE_QAT_EXT_D_BGA1-IC,H91A
GND                      U7C1             BB68     LBG_CORE_QAT_EXT_D_BGA1-IC,H91A
GND                      U7C1             BB70     LBG_CORE_QAT_EXT_D_BGA1-IC,H91A
GND                      U7C1             BB72     LBG_CORE_QAT_EXT_D_BGA1-IC,H91A
GND                      U7C1             BC69     LBG_CORE_QAT_EXT_D_BGA1-IC,H91A
GND                      U7C1             BC71     LBG_CORE_QAT_EXT_D_BGA1-IC,H91A
GND                      U7C1             BD5      LBG_CORE_QAT_EXT_D_BGA1-IC,H91A
GND                      U7C1             BD24     LBG_CORE_QAT_EXT_D_BGA1-IC,H91A
GND                      U7C1             BD27     LBG_CORE_QAT_EXT_D_BGA1-IC,H91A
GND                      U7C1             BD31     LBG_CORE_QAT_EXT_D_BGA1-IC,H91A
GND                      U7C1             BD35     LBG_CORE_QAT_EXT_D_BGA1-IC,H91A
GND                      U7C1             BD50     LBG_CORE_QAT_EXT_D_BGA1-IC,H91A
GND                      U7C1             BD54     LBG_CORE_QAT_EXT_D_BGA1-IC,H91A
GND                      U7C1             BD68     LBG_CORE_QAT_EXT_D_BGA1-IC,H91A
GND                      U7C1             BE29     LBG_CORE_QAT_EXT_D_BGA1-IC,H91A
GND                      U7C1             BE33     LBG_CORE_QAT_EXT_D_BGA1-IC,H91A
GND                      U7C1             BE37     LBG_CORE_QAT_EXT_D_BGA1-IC,H91A
GND                      U7C1             BE56     LBG_CORE_QAT_EXT_D_BGA1-IC,H91A
GND                      U7C1             BE59     LBG_CORE_QAT_EXT_D_BGA1-IC,H91A
GND                      U7C1             BE63     LBG_CORE_QAT_EXT_D_BGA1-IC,H91A
GND                      U7C1             BE66     LBG_CORE_QAT_EXT_D_BGA1-IC,H91A
GND                      U7C1             BF5      LBG_CORE_QAT_EXT_D_BGA1-IC,H91A
GND                      U7C1             BF9      LBG_CORE_QAT_EXT_D_BGA1-IC,H91A
GND                      U7C1             BF13     LBG_CORE_QAT_EXT_D_BGA1-IC,H91A
GND                      U7C1             BF17     LBG_CORE_QAT_EXT_D_BGA1-IC,H91A
GND                      U7C1             BF20     LBG_CORE_QAT_EXT_D_BGA1-IC,H91A
GND                      U7C1             BF24     LBG_CORE_QAT_EXT_D_BGA1-IC,H91A
GND                      U7C1             BF27     LBG_CORE_QAT_EXT_D_BGA1-IC,H91A
GND                      U7C1             BF38     LBG_CORE_QAT_EXT_D_BGA1-IC,H91A
GND                      U7C1             BF42     LBG_CORE_QAT_EXT_D_BGA1-IC,H91A
GND                      U7C1             BF50     LBG_CORE_QAT_EXT_D_BGA1-IC,H91A
GND                      U7C1             BF54     LBG_CORE_QAT_EXT_D_BGA1-IC,H91A
GND                      U7C1             BF58     LBG_CORE_QAT_EXT_D_BGA1-IC,H91A
GND                      U7C1             BF61     LBG_CORE_QAT_EXT_D_BGA1-IC,H91A
GND                      U7C1             BF65     LBG_CORE_QAT_EXT_D_BGA1-IC,H91A
GND                      U7C1             BF68     LBG_CORE_QAT_EXT_D_BGA1-IC,H91A
GND                      U7C1             BG33     LBG_CORE_QAT_EXT_D_BGA1-IC,H91A
GND                      U7C1             BG44     LBG_CORE_QAT_EXT_D_BGA1-IC,H91A
GND                      U7C1             BG48     LBG_CORE_QAT_EXT_D_BGA1-IC,H91A
GND                      U7C1             BG59     LBG_CORE_QAT_EXT_D_BGA1-IC,H91A
GND                      U7C1             BG63     LBG_CORE_QAT_EXT_D_BGA1-IC,H91A
GND                      U7C1             BH27     LBG_CORE_QAT_EXT_D_BGA1-IC,H91A
GND                      U7C1             BH38     LBG_CORE_QAT_EXT_D_BGA1-IC,H91A
GND                      U7C1             BH42     LBG_CORE_QAT_EXT_D_BGA1-IC,H91A
GND                      U7C1             BH46     LBG_CORE_QAT_EXT_D_BGA1-IC,H91A
GND                      U7C1             BH54     LBG_CORE_QAT_EXT_D_BGA1-IC,H91A
GND                      U7C1             BJ1      LBG_CORE_QAT_EXT_D_BGA1-IC,H91A
GND                      U7C1             BJ3      LBG_CORE_QAT_EXT_D_BGA1-IC,H91A
GND                      U7C1             BJ5      LBG_CORE_QAT_EXT_D_BGA1-IC,H91A
GND                      U7C1             BJ7      LBG_CORE_QAT_EXT_D_BGA1-IC,H91A
GND                      U7C1             BJ11     LBG_CORE_QAT_EXT_D_BGA1-IC,H91A
GND                      U7C1             BJ15     LBG_CORE_QAT_EXT_D_BGA1-IC,H91A
GND                      U7C1             BJ18     LBG_CORE_QAT_EXT_D_BGA1-IC,H91A
GND                      U7C1             BJ26     LBG_CORE_QAT_EXT_D_BGA1-IC,H91A
GND                      U7C1             BJ33     LBG_CORE_QAT_EXT_D_BGA1-IC,H91A
GND                      U7C1             BJ52     LBG_CORE_QAT_EXT_D_BGA1-IC,H91A
GND                      U7C1             BJ68     LBG_CORE_QAT_EXT_D_BGA1-IC,H91A
GND                      U7C1             BK24     LBG_CORE_QAT_EXT_D_BGA1-IC,H91A
GND                      U7C1             BK27     LBG_CORE_QAT_EXT_D_BGA1-IC,H91A
GND                      U7C1             BK31     LBG_CORE_QAT_EXT_D_BGA1-IC,H91A
GND                      U7C1             BK35     LBG_CORE_QAT_EXT_D_BGA1-IC,H91A
GND                      U7C1             BK38     LBG_CORE_QAT_EXT_D_BGA1-IC,H91A
GND                      U7C1             BK42     LBG_CORE_QAT_EXT_D_BGA1-IC,H91A
GND                      U7C1             BK50     LBG_CORE_QAT_EXT_D_BGA1-IC,H91A
GND                      U7C1             BL5      LBG_CORE_QAT_EXT_D_BGA1-IC,H91A
GND                      U7C1             BL22     LBG_CORE_QAT_EXT_D_BGA1-IC,H91A
GND                      U7C1             BL37     LBG_CORE_QAT_EXT_D_BGA1-IC,H91A
GND                      U7C1             BL40     LBG_CORE_QAT_EXT_D_BGA1-IC,H91A
GND                      U7C1             BL63     LBG_CORE_QAT_EXT_D_BGA1-IC,H91A
GND                      U7C1             BL68     LBG_CORE_QAT_EXT_D_BGA1-IC,H91A
GND                      U7C1             BL70     LBG_CORE_QAT_EXT_D_BGA1-IC,H91A
GND                      U7C1             BL72     LBG_CORE_QAT_EXT_D_BGA1-IC,H91A
GND                      U7C1             BM9      LBG_CORE_QAT_EXT_D_BGA1-IC,H91A
GND                      U7C1             BM13     LBG_CORE_QAT_EXT_D_BGA1-IC,H91A
GND                      U7C1             BM17     LBG_CORE_QAT_EXT_D_BGA1-IC,H91A
GND                      U7C1             BM46     LBG_CORE_QAT_EXT_D_BGA1-IC,H91A
GND                      U7C1             BM50     LBG_CORE_QAT_EXT_D_BGA1-IC,H91A
GND                      U7C1             BM58     LBG_CORE_QAT_EXT_D_BGA1-IC,H91A
GND                      U7C1             BM69     LBG_CORE_QAT_EXT_D_BGA1-IC,H91A
GND                      U7C1             BM71     LBG_CORE_QAT_EXT_D_BGA1-IC,H91A
GND                      U7C1             BN1      LBG_CORE_QAT_EXT_D_BGA1-IC,H91A
GND                      U7C1             BN5      LBG_CORE_QAT_EXT_D_BGA1-IC,H91A
GND                      U7C1             BN22     LBG_CORE_QAT_EXT_D_BGA1-IC,H91A
GND                      U7C1             BN37     LBG_CORE_QAT_EXT_D_BGA1-IC,H91A
GND                      U7C1             BN52     LBG_CORE_QAT_EXT_D_BGA1-IC,H91A
GND                      U7C1             BN59     LBG_CORE_QAT_EXT_D_BGA1-IC,H91A
GND                      U7C1             BN66     LBG_CORE_QAT_EXT_D_BGA1-IC,H91A
GND                      U7C1             BN72     LBG_CORE_QAT_EXT_D_BGA1-IC,H91A
GND                      U7C1             BP69     LBG_CORE_QAT_EXT_D_BGA1-IC,H91A
GND                      U7C1             BR1      LBG_CORE_QAT_EXT_D_BGA1-IC,H91A
GND                      U7C1             BR3      LBG_CORE_QAT_EXT_D_BGA1-IC,H91A
GND                      U7C1             BR6      LBG_CORE_QAT_EXT_D_BGA1-IC,H91A
GND                      U7C1             BR20     LBG_CORE_QAT_EXT_D_BGA1-IC,H91A
GND                      U7C1             BR50     LBG_CORE_QAT_EXT_D_BGA1-IC,H91A
GND                      U7C1             BR54     LBG_CORE_QAT_EXT_D_BGA1-IC,H91A
GND                      U7C1             BR58     LBG_CORE_QAT_EXT_D_BGA1-IC,H91A
GND                      U7C1             BR70     LBG_CORE_QAT_EXT_D_BGA1-IC,H91A
GND                      U7C1             BR72     LBG_CORE_QAT_EXT_D_BGA1-IC,H91A
GND                      U7C1             BT8      LBG_CORE_QAT_EXT_D_BGA1-IC,H91A
GND                      U7C1             BT66     LBG_CORE_QAT_EXT_D_BGA1-IC,H91A
GND                      U7C1             BT69     LBG_CORE_QAT_EXT_D_BGA1-IC,H91A
GND                      U7C1             BU1      LBG_CORE_QAT_EXT_D_BGA1-IC,H91A
GND                      U7C1             BU3      LBG_CORE_QAT_EXT_D_BGA1-IC,H91A
GND                      U7C1             BU9      LBG_CORE_QAT_EXT_D_BGA1-IC,H91A
GND                      U7C1             BU11     LBG_CORE_QAT_EXT_D_BGA1-IC,H91A
GND                      U7C1             BU13     LBG_CORE_QAT_EXT_D_BGA1-IC,H91A
GND                      U7C1             BU15     LBG_CORE_QAT_EXT_D_BGA1-IC,H91A
GND                      U7C1             BU18     LBG_CORE_QAT_EXT_D_BGA1-IC,H91A
GND                      U7C1             BU20     LBG_CORE_QAT_EXT_D_BGA1-IC,H91A
GND                      U7C1             BU22     LBG_CORE_QAT_EXT_D_BGA1-IC,H91A
GND                      U7C1             BU24     LBG_CORE_QAT_EXT_D_BGA1-IC,H91A
GND                      U7C1             BU26     LBG_CORE_QAT_EXT_D_BGA1-IC,H91A
GND                      U7C1             BU28     LBG_CORE_QAT_EXT_D_BGA1-IC,H91A
GND                      U7C1             BU30     LBG_CORE_QAT_EXT_D_BGA1-IC,H91A
GND                      U7C1             BU32     LBG_CORE_QAT_EXT_D_BGA1-IC,H91A
GND                      U7C1             BU34     LBG_CORE_QAT_EXT_D_BGA1-IC,H91A
GND                      U7C1             BU37     LBG_CORE_QAT_EXT_D_BGA1-IC,H91A
GND                      U7C1             BU39     LBG_CORE_QAT_EXT_D_BGA1-IC,H91A
GND                      U7C1             BU41     LBG_CORE_QAT_EXT_D_BGA1-IC,H91A
GND                      U7C1             BU43     LBG_CORE_QAT_EXT_D_BGA1-IC,H91A
GND                      U7C1             BU45     LBG_CORE_QAT_EXT_D_BGA1-IC,H91A
GND                      U7C1             BU48     LBG_CORE_QAT_EXT_D_BGA1-IC,H91A
GND                      U7C1             BU50     LBG_CORE_QAT_EXT_D_BGA1-IC,H91A
GND                      U7C1             BU52     LBG_CORE_QAT_EXT_D_BGA1-IC,H91A
GND                      U7C1             BU54     LBG_CORE_QAT_EXT_D_BGA1-IC,H91A
GND                      U7C1             BU57     LBG_CORE_QAT_EXT_D_BGA1-IC,H91A
GND                      U7C1             BU59     LBG_CORE_QAT_EXT_D_BGA1-IC,H91A
GND                      U7C1             BU61     LBG_CORE_QAT_EXT_D_BGA1-IC,H91A
GND                      U7C1             BU63     LBG_CORE_QAT_EXT_D_BGA1-IC,H91A
GND                      U7C1             BU70     LBG_CORE_QAT_EXT_D_BGA1-IC,H91A
GND                      U7C1             BU72     LBG_CORE_QAT_EXT_D_BGA1-IC,H91A
GND                      U7C1             BV40     LBG_CORE_QAT_EXT_D_BGA1-IC,H91A
GND                      U7C1             BV49     LBG_CORE_QAT_EXT_D_BGA1-IC,H91A
GND                      U7C1             BW1      LBG_CORE_QAT_EXT_D_BGA1-IC,H91A
GND                      U7C1             BW15     LBG_CORE_QAT_EXT_D_BGA1-IC,H91A
GND                      U7C1             BW18     LBG_CORE_QAT_EXT_D_BGA1-IC,H91A
GND                      U7C1             BW26     LBG_CORE_QAT_EXT_D_BGA1-IC,H91A
GND                      U7C1             BW52     LBG_CORE_QAT_EXT_D_BGA1-IC,H91A
GND                      U7C1             BW70     LBG_CORE_QAT_EXT_D_BGA1-IC,H91A
GND                      U7C1             BW72     LBG_CORE_QAT_EXT_D_BGA1-IC,H91A
GND                      U7C1             BY40     LBG_CORE_QAT_EXT_D_BGA1-IC,H91A
GND                      U7C1             BY49     LBG_CORE_QAT_EXT_D_BGA1-IC,H91A
GND                      U7C1             C3       LBG_CORE_QAT_EXT_D_BGA1-IC,H91A
GND                      U7C1             C22      LBG_CORE_QAT_EXT_D_BGA1-IC,H91A
GND                      U7C1             C30      LBG_CORE_QAT_EXT_D_BGA1-IC,H91A
GND                      U7C1             C34      LBG_CORE_QAT_EXT_D_BGA1-IC,H91A
GND                      U7C1             C37      LBG_CORE_QAT_EXT_D_BGA1-IC,H91A
GND                      U7C1             C41      LBG_CORE_QAT_EXT_D_BGA1-IC,H91A
GND                      U7C1             C65      LBG_CORE_QAT_EXT_D_BGA1-IC,H91A
GND                      U7C1             C72      LBG_CORE_QAT_EXT_D_BGA1-IC,H91A
GND                      U7C1             CA3      LBG_CORE_QAT_EXT_D_BGA1-IC,H91A
GND                      U7C1             CA5      LBG_CORE_QAT_EXT_D_BGA1-IC,H91A
GND                      U7C1             CA7      LBG_CORE_QAT_EXT_D_BGA1-IC,H91A
GND                      U7C1             CA9      LBG_CORE_QAT_EXT_D_BGA1-IC,H91A
GND                      U7C1             CA15     LBG_CORE_QAT_EXT_D_BGA1-IC,H91A
GND                      U7C1             CA18     LBG_CORE_QAT_EXT_D_BGA1-IC,H91A
GND                      U7C1             CA26     LBG_CORE_QAT_EXT_D_BGA1-IC,H91A
GND                      U7C1             CA50     LBG_CORE_QAT_EXT_D_BGA1-IC,H91A
GND                      U7C1             CA52     LBG_CORE_QAT_EXT_D_BGA1-IC,H91A
GND                      U7C1             CA65     LBG_CORE_QAT_EXT_D_BGA1-IC,H91A
GND                      U7C1             CA66     LBG_CORE_QAT_EXT_D_BGA1-IC,H91A
GND                      U7C1             CA68     LBG_CORE_QAT_EXT_D_BGA1-IC,H91A
GND                      U7C1             CA70     LBG_CORE_QAT_EXT_D_BGA1-IC,H91A
GND                      U7C1             D12      LBG_CORE_QAT_EXT_D_BGA1-IC,H91A
GND                      U7C1             D16      LBG_CORE_QAT_EXT_D_BGA1-IC,H91A
GND                      U7C1             D19      LBG_CORE_QAT_EXT_D_BGA1-IC,H91A
GND                      U7C1             D25      LBG_CORE_QAT_EXT_D_BGA1-IC,H91A
GND                      U7C1             D27      LBG_CORE_QAT_EXT_D_BGA1-IC,H91A
GND                      U7C1             D47      LBG_CORE_QAT_EXT_D_BGA1-IC,H91A
GND                      U7C1             E1       LBG_CORE_QAT_EXT_D_BGA1-IC,H91A
GND                      U7C1             E3       LBG_CORE_QAT_EXT_D_BGA1-IC,H91A
GND                      U7C1             E6       LBG_CORE_QAT_EXT_D_BGA1-IC,H91A
GND                      U7C1             E9       LBG_CORE_QAT_EXT_D_BGA1-IC,H91A
GND                      U7C1             E11      LBG_CORE_QAT_EXT_D_BGA1-IC,H91A
GND                      U7C1             E13      LBG_CORE_QAT_EXT_D_BGA1-IC,H91A
GND                      U7C1             E15      LBG_CORE_QAT_EXT_D_BGA1-IC,H91A
GND                      U7C1             E20      LBG_CORE_QAT_EXT_D_BGA1-IC,H91A
GND                      U7C1             E22      LBG_CORE_QAT_EXT_D_BGA1-IC,H91A
GND                      U7C1             E24      LBG_CORE_QAT_EXT_D_BGA1-IC,H91A
GND                      U7C1             E26      LBG_CORE_QAT_EXT_D_BGA1-IC,H91A
GND                      U7C1             E28      LBG_CORE_QAT_EXT_D_BGA1-IC,H91A
GND                      U7C1             E30      LBG_CORE_QAT_EXT_D_BGA1-IC,H91A
GND                      U7C1             E32      LBG_CORE_QAT_EXT_D_BGA1-IC,H91A
GND                      U7C1             E34      LBG_CORE_QAT_EXT_D_BGA1-IC,H91A
GND                      U7C1             E37      LBG_CORE_QAT_EXT_D_BGA1-IC,H91A
GND                      U7C1             E39      LBG_CORE_QAT_EXT_D_BGA1-IC,H91A
GND                      U7C1             E41      LBG_CORE_QAT_EXT_D_BGA1-IC,H91A
GND                      U7C1             E43      LBG_CORE_QAT_EXT_D_BGA1-IC,H91A
GND                      U7C1             E45      LBG_CORE_QAT_EXT_D_BGA1-IC,H91A
GND                      U7C1             E48      LBG_CORE_QAT_EXT_D_BGA1-IC,H91A
GND                      U7C1             E50      LBG_CORE_QAT_EXT_D_BGA1-IC,H91A
GND                      U7C1             E52      LBG_CORE_QAT_EXT_D_BGA1-IC,H91A
GND                      U7C1             E54      LBG_CORE_QAT_EXT_D_BGA1-IC,H91A
GND                      U7C1             E57      LBG_CORE_QAT_EXT_D_BGA1-IC,H91A
GND                      U7C1             E59      LBG_CORE_QAT_EXT_D_BGA1-IC,H91A
GND                      U7C1             E61      LBG_CORE_QAT_EXT_D_BGA1-IC,H91A
GND                      U7C1             E63      LBG_CORE_QAT_EXT_D_BGA1-IC,H91A
GND                      U7C1             E65      LBG_CORE_QAT_EXT_D_BGA1-IC,H91A
GND                      U7C1             E70      LBG_CORE_QAT_EXT_D_BGA1-IC,H91A
GND                      U7C1             E72      LBG_CORE_QAT_EXT_D_BGA1-IC,H91A
GND                      U7C1             F3       LBG_CORE_QAT_EXT_D_BGA1-IC,H91A
GND                      U7C1             F70      LBG_CORE_QAT_EXT_D_BGA1-IC,H91A
GND                      U7C1             G1       LBG_CORE_QAT_EXT_D_BGA1-IC,H91A
GND                      U7C1             G6       LBG_CORE_QAT_EXT_D_BGA1-IC,H91A
GND                      U7C1             G22      LBG_CORE_QAT_EXT_D_BGA1-IC,H91A
GND                      U7C1             G29      LBG_CORE_QAT_EXT_D_BGA1-IC,H91A
GND                      U7C1             G37      LBG_CORE_QAT_EXT_D_BGA1-IC,H91A
GND                      U7C1             G48      LBG_CORE_QAT_EXT_D_BGA1-IC,H91A
GND                      U7C1             G59      LBG_CORE_QAT_EXT_D_BGA1-IC,H91A
GND                      U7C1             G63      LBG_CORE_QAT_EXT_D_BGA1-IC,H91A
GND                      U7C1             G66      LBG_CORE_QAT_EXT_D_BGA1-IC,H91A
GND                      U7C1             G72      LBG_CORE_QAT_EXT_D_BGA1-IC,H91A
GND                      U7C1             H58      LBG_CORE_QAT_EXT_D_BGA1-IC,H91A
GND                      U7C1             H65      LBG_CORE_QAT_EXT_D_BGA1-IC,H91A
GND                      U7C1             J1       LBG_CORE_QAT_EXT_D_BGA1-IC,H91A
GND                      U7C1             J5       LBG_CORE_QAT_EXT_D_BGA1-IC,H91A
GND                      U7C1             J7       LBG_CORE_QAT_EXT_D_BGA1-IC,H91A
GND                      U7C1             J11      LBG_CORE_QAT_EXT_D_BGA1-IC,H91A
GND                      U7C1             J15      LBG_CORE_QAT_EXT_D_BGA1-IC,H91A
GND                      U7C1             J18      LBG_CORE_QAT_EXT_D_BGA1-IC,H91A
GND                      U7C1             J22      LBG_CORE_QAT_EXT_D_BGA1-IC,H91A
GND                      U7C1             J29      LBG_CORE_QAT_EXT_D_BGA1-IC,H91A
GND                      U7C1             J37      LBG_CORE_QAT_EXT_D_BGA1-IC,H91A
GND                      U7C1             J44      LBG_CORE_QAT_EXT_D_BGA1-IC,H91A
GND                      U7C1             J59      LBG_CORE_QAT_EXT_D_BGA1-IC,H91A
GND                      U7C1             J68      LBG_CORE_QAT_EXT_D_BGA1-IC,H91A
GND                      U7C1             J70      LBG_CORE_QAT_EXT_D_BGA1-IC,H91A
GND                      U7C1             J72      LBG_CORE_QAT_EXT_D_BGA1-IC,H91A
GND                      U7C1             K54      LBG_CORE_QAT_EXT_D_BGA1-IC,H91A
GND                      U7C1             K69      LBG_CORE_QAT_EXT_D_BGA1-IC,H91A
GND                      U7C1             K71      LBG_CORE_QAT_EXT_D_BGA1-IC,H91A
GND                      U7C1             L5       LBG_CORE_QAT_EXT_D_BGA1-IC,H91A
GND                      U7C1             L68      LBG_CORE_QAT_EXT_D_BGA1-IC,H91A
GND                      U7C1             M2       LBG_CORE_QAT_EXT_D_BGA1-IC,H91A
GND                      U7C1             M4       LBG_CORE_QAT_EXT_D_BGA1-IC,H91A
GND                      U7C1             M22      LBG_CORE_QAT_EXT_D_BGA1-IC,H91A
GND                      U7C1             M26      LBG_CORE_QAT_EXT_D_BGA1-IC,H91A
GND                      U7C1             M29      LBG_CORE_QAT_EXT_D_BGA1-IC,H91A
GND                      U7C1             M33      LBG_CORE_QAT_EXT_D_BGA1-IC,H91A
GND                      U7C1             M37      LBG_CORE_QAT_EXT_D_BGA1-IC,H91A
GND                      U7C1             M40      LBG_CORE_QAT_EXT_D_BGA1-IC,H91A
GND                      U7C1             M44      LBG_CORE_QAT_EXT_D_BGA1-IC,H91A
GND                      U7C1             M48      LBG_CORE_QAT_EXT_D_BGA1-IC,H91A
GND                      U7C1             N5       LBG_CORE_QAT_EXT_D_BGA1-IC,H91A
GND                      U7C1             N9       LBG_CORE_QAT_EXT_D_BGA1-IC,H91A
GND                      U7C1             N13      LBG_CORE_QAT_EXT_D_BGA1-IC,H91A
GND                      U7C1             N17      LBG_CORE_QAT_EXT_D_BGA1-IC,H91A
GND                      U7C1             N20      LBG_CORE_QAT_EXT_D_BGA1-IC,H91A
GND                      U7C1             N24      LBG_CORE_QAT_EXT_D_BGA1-IC,H91A
GND                      U7C1             N27      LBG_CORE_QAT_EXT_D_BGA1-IC,H91A
GND                      U7C1             N31      LBG_CORE_QAT_EXT_D_BGA1-IC,H91A
GND                      U7C1             N35      LBG_CORE_QAT_EXT_D_BGA1-IC,H91A
GND                      U7C1             N38      LBG_CORE_QAT_EXT_D_BGA1-IC,H91A
GND                      U7C1             N42      LBG_CORE_QAT_EXT_D_BGA1-IC,H91A
GND                      U7C1             N46      LBG_CORE_QAT_EXT_D_BGA1-IC,H91A
GND                      U7C1             N50      LBG_CORE_QAT_EXT_D_BGA1-IC,H91A
GND                      U7C1             N68      LBG_CORE_QAT_EXT_D_BGA1-IC,H91A
GND                      U7C1             P63      LBG_CORE_QAT_EXT_D_BGA1-IC,H91A
GND                      U7C1             R5       LBG_CORE_QAT_EXT_D_BGA1-IC,H91A
GND                      U7C1             R27      LBG_CORE_QAT_EXT_D_BGA1-IC,H91A
GND                      U7C1             R38      LBG_CORE_QAT_EXT_D_BGA1-IC,H91A
GND                      U7C1             R50      LBG_CORE_QAT_EXT_D_BGA1-IC,H91A
GND                      U7C1             R54      LBG_CORE_QAT_EXT_D_BGA1-IC,H91A
GND                      U7C1             R58      LBG_CORE_QAT_EXT_D_BGA1-IC,H91A
GND                      U7C1             R68      LBG_CORE_QAT_EXT_D_BGA1-IC,H91A
GND                      U7C1             T7       LBG_CORE_QAT_EXT_D_BGA1-IC,H91A
GND                      U7C1             T11      LBG_CORE_QAT_EXT_D_BGA1-IC,H91A
GND                      U7C1             T15      LBG_CORE_QAT_EXT_D_BGA1-IC,H91A
GND                      U7C1             T18      LBG_CORE_QAT_EXT_D_BGA1-IC,H91A
GND                      U7C1             T22      LBG_CORE_QAT_EXT_D_BGA1-IC,H91A
GND                      U7C1             T26      LBG_CORE_QAT_EXT_D_BGA1-IC,H91A
GND                      U7C1             T29      LBG_CORE_QAT_EXT_D_BGA1-IC,H91A
GND                      U7C1             T33      LBG_CORE_QAT_EXT_D_BGA1-IC,H91A
GND                      U7C1             T37      LBG_CORE_QAT_EXT_D_BGA1-IC,H91A
GND                      U7C1             T40      LBG_CORE_QAT_EXT_D_BGA1-IC,H91A
GND                      U7C1             T48      LBG_CORE_QAT_EXT_D_BGA1-IC,H91A
GND                      U7C1             T52      LBG_CORE_QAT_EXT_D_BGA1-IC,H91A
GND                      U7C1             T56      LBG_CORE_QAT_EXT_D_BGA1-IC,H91A
GND                      U7C1             T66      LBG_CORE_QAT_EXT_D_BGA1-IC,H91A
GND                      U7C1             U42      LBG_CORE_QAT_EXT_D_BGA1-IC,H91A
GND                      U7C1             U58      LBG_CORE_QAT_EXT_D_BGA1-IC,H91A
GND                      U7C1             V5       LBG_CORE_QAT_EXT_D_BGA1-IC,H91A
GND                      U7C1             V26      LBG_CORE_QAT_EXT_D_BGA1-IC,H91A
GND                      U7C1             V48      LBG_CORE_QAT_EXT_D_BGA1-IC,H91A
GND                      U7C1             V52      LBG_CORE_QAT_EXT_D_BGA1-IC,H91A
GND                      U7C1             V66      LBG_CORE_QAT_EXT_D_BGA1-IC,H91A
GND                      U7C1             V68      LBG_CORE_QAT_EXT_D_BGA1-IC,H91A
GND                      U7C1             W9       LBG_CORE_QAT_EXT_D_BGA1-IC,H91A
GND                      U7C1             W13      LBG_CORE_QAT_EXT_D_BGA1-IC,H91A
GND                      U7C1             W17      LBG_CORE_QAT_EXT_D_BGA1-IC,H91A
GND                      U7C1             W20      LBG_CORE_QAT_EXT_D_BGA1-IC,H91A
GND                      U7C1             W24      LBG_CORE_QAT_EXT_D_BGA1-IC,H91A
GND                      U7C1             W58      LBG_CORE_QAT_EXT_D_BGA1-IC,H91A
GND                      U7C1             W61      LBG_CORE_QAT_EXT_D_BGA1-IC,H91A
GND                      U7C1             Y5       LBG_CORE_QAT_EXT_D_BGA1-IC,H91A
GND                      U7C1             Y22      LBG_CORE_QAT_EXT_D_BGA1-IC,H91A
GND                      U7C1             Y27      LBG_CORE_QAT_EXT_D_BGA1-IC,H91A
GND                      U7C1             Y43      LBG_CORE_QAT_EXT_D_BGA1-IC,H91A
GND                      U7C1             Y48      LBG_CORE_QAT_EXT_D_BGA1-IC,H91A
GND                      U7C1             Y52      LBG_CORE_QAT_EXT_D_BGA1-IC,H91A
GND                      U7C1             Y59      LBG_CORE_QAT_EXT_D_BGA1-IC,H91A
GND                      U7C1             Y63      LBG_CORE_QAT_EXT_D_BGA1-IC,H91A
GND                      U7C1             Y68      LBG_CORE_QAT_EXT_D_BGA1-IC,H91A
GND                      U7C1             Y70      LBG_CORE_QAT_EXT_D_BGA1-IC,H91A
GND                      U7C1             Y72      LBG_CORE_QAT_EXT_D_BGA1-IC,H91A
GND                      U7D2             7        GTL2014_SM-IC,D66151-001
GND                      U7D2             8        GTL2014_SM-IC,D66151-001
GND                      U7D2             11       GTL2014_SM-IC,D66151-001
GND                      U7D3             2        ADM1085_SMT-IC,H46130-001
GND                      U7F1             10       W25Q256_XSOI-IC,H25002-001
GND                      U8D4             1        AT24C64_SOICLF-IC,C47049-001-GA
GND                      U8D4             2        AT24C64_SOICLF-IC,C47049-001-GA
GND                      U8D7             B2       LCMXO2_A_256BGA-IC,H63395-001
GND                      U8D7             B15      LCMXO2_A_256BGA-IC,H63395-001
GND                      U8D7             C3       LCMXO2_A_256BGA-IC,H63395-001
GND                      U8D7             C14      LCMXO2_A_256BGA-IC,H63395-001
GND                      U8D7             D4       LCMXO2_A_256BGA-IC,H63395-001
GND                      U8D7             D13      LCMXO2_A_256BGA-IC,H63395-001
GND                      U8D7             E5       LCMXO2_A_256BGA-IC,H63395-001
GND                      U8D7             E12      LCMXO2_A_256BGA-IC,H63395-001
GND                      U8D7             F6       LCMXO2_A_256BGA-IC,H63395-001
GND                      U8D7             F11      LCMXO2_A_256BGA-IC,H63395-001
GND                      U8D7             H8       LCMXO2_A_256BGA-IC,H63395-001
GND                      U8D7             H9       LCMXO2_A_256BGA-IC,H63395-001
GND                      U8D7             J8       LCMXO2_A_256BGA-IC,H63395-001
GND                      U8D7             J9       LCMXO2_A_256BGA-IC,H63395-001
GND                      U8D7             L6       LCMXO2_A_256BGA-IC,H63395-001
GND                      U8D7             L11      LCMXO2_A_256BGA-IC,H63395-001
GND                      U8D7             M5       LCMXO2_A_256BGA-IC,H63395-001
GND                      U8D7             M12      LCMXO2_A_256BGA-IC,H63395-001
GND                      U8D7             N4       LCMXO2_A_256BGA-IC,H63395-001
GND                      U8D7             N13      LCMXO2_A_256BGA-IC,H63395-001
GND                      U8D7             P3       LCMXO2_A_256BGA-IC,H63395-001
GND                      U8D7             P14      LCMXO2_A_256BGA-IC,H63395-001
GND                      U8D7             R2       LCMXO2_A_256BGA-IC,H63395-001
GND                      U8D7             R15      LCMXO2_A_256BGA-IC,H63395-001
GND                      U8D8             5        TPS3700_SM-IC,H69492-001
GND                      U8F1             8        PI3B3257A_TSSOPLF-IC,E16801-001
GND                      U8F1             15       PI3B3257A_TSSOPLF-IC,E16801-001
GND                      U8F2             10       W25Q128_SKT16-IC,H12709-001
GND                      U9A5             4        74CBTLV1G125_SMLF-IC,C88177-00A
GND                      U9B4             5        TMP421_TSSOP-IC,G62962-001
GND                      U9E1             4        M25PE16_SM-IC,H77797-001
GND                      U9F1             4        FSA3357_SM-IC,C63273-001
GND                      U9F2             4        FSA3357_SM-IC,C63273-001
GND                      U9F4             AA18     AST1250_BGA-IC,G85138-002
GND                      U9F4             AA19     AST1250_BGA-IC,G85138-002
GND                      U9F4             B8       AST1250_BGA-IC,G85138-002
GND                      U9F4             B9       AST1250_BGA-IC,G85138-002
GND                      U9F4             D11      AST1250_BGA-IC,G85138-002
GND                      U9F4             D21      AST1250_BGA-IC,G85138-002
GND                      U9F4             D22      AST1250_BGA-IC,G85138-002
GND                      U9F4             H21      AST1250_BGA-IC,G85138-002
GND                      U9F4             H22      AST1250_BGA-IC,G85138-002
GND                      U9F4             J9       AST1250_BGA-IC,G85138-002
GND                      U9F4             J10      AST1250_BGA-IC,G85138-002
GND                      U9F4             J11      AST1250_BGA-IC,G85138-002
GND                      U9F4             J12      AST1250_BGA-IC,G85138-002
GND                      U9F4             J13      AST1250_BGA-IC,G85138-002
GND                      U9F4             J14      AST1250_BGA-IC,G85138-002
GND                      U9F4             K9       AST1250_BGA-IC,G85138-002
GND                      U9F4             K10      AST1250_BGA-IC,G85138-002
GND                      U9F4             K11      AST1250_BGA-IC,G85138-002
GND                      U9F4             K12      AST1250_BGA-IC,G85138-002
GND                      U9F4             K13      AST1250_BGA-IC,G85138-002
GND                      U9F4             K14      AST1250_BGA-IC,G85138-002
GND                      U9F4             L9       AST1250_BGA-IC,G85138-002
GND                      U9F4             L10      AST1250_BGA-IC,G85138-002
GND                      U9F4             L11      AST1250_BGA-IC,G85138-002
GND                      U9F4             L12      AST1250_BGA-IC,G85138-002
GND                      U9F4             L13      AST1250_BGA-IC,G85138-002
GND                      U9F4             L14      AST1250_BGA-IC,G85138-002
GND                      U9F4             M1       AST1250_BGA-IC,G85138-002
GND                      U9F4             M2       AST1250_BGA-IC,G85138-002
GND                      U9F4             M9       AST1250_BGA-IC,G85138-002
GND                      U9F4             M10      AST1250_BGA-IC,G85138-002
GND                      U9F4             M11      AST1250_BGA-IC,G85138-002
GND                      U9F4             M12      AST1250_BGA-IC,G85138-002
GND                      U9F4             M13      AST1250_BGA-IC,G85138-002
GND                      U9F4             M14      AST1250_BGA-IC,G85138-002
GND                      U9F4             N1       AST1250_BGA-IC,G85138-002
GND                      U9F4             N2       AST1250_BGA-IC,G85138-002
GND                      U9F4             N3       AST1250_BGA-IC,G85138-002
GND                      U9F4             N4       AST1250_BGA-IC,G85138-002
GND                      U9F4             N5       AST1250_BGA-IC,G85138-002
GND                      U9F4             N9       AST1250_BGA-IC,G85138-002
GND                      U9F4             N10      AST1250_BGA-IC,G85138-002
GND                      U9F4             N11      AST1250_BGA-IC,G85138-002
GND                      U9F4             N12      AST1250_BGA-IC,G85138-002
GND                      U9F4             N13      AST1250_BGA-IC,G85138-002
GND                      U9F4             N14      AST1250_BGA-IC,G85138-002
GND                      U9F4             P4       AST1250_BGA-IC,G85138-002
GND                      U9F4             P5       AST1250_BGA-IC,G85138-002
GND                      U9F4             P9       AST1250_BGA-IC,G85138-002
GND                      U9F4             P10      AST1250_BGA-IC,G85138-002
GND                      U9F4             P11      AST1250_BGA-IC,G85138-002
GND                      U9F4             P12      AST1250_BGA-IC,G85138-002
GND                      U9F4             P13      AST1250_BGA-IC,G85138-002
GND                      U9F4             P14      AST1250_BGA-IC,G85138-002
GND                      U9F4             R5       AST1250_BGA-IC,G85138-002
GND                      U9F4             V18      AST1250_BGA-IC,G85138-002
GND                      U9F4             Y19      AST1250_BGA-IC,G85138-002
GND                      U9F5             A9       K4B1G16_BGA1-IC,G38649-001
GND                      U9F5             B1       K4B1G16_BGA1-IC,G38649-001
GND                      U9F5             B3       K4B1G16_BGA1-IC,G38649-001
GND                      U9F5             B9       K4B1G16_BGA1-IC,G38649-001
GND                      U9F5             D1       K4B1G16_BGA1-IC,G38649-001
GND                      U9F5             D8       K4B1G16_BGA1-IC,G38649-001
GND                      U9F5             E1       K4B1G16_BGA1-IC,G38649-001
GND                      U9F5             E2       K4B1G16_BGA1-IC,G38649-001
GND                      U9F5             E8       K4B1G16_BGA1-IC,G38649-001
GND                      U9F5             F9       K4B1G16_BGA1-IC,G38649-001
GND                      U9F5             G1       K4B1G16_BGA1-IC,G38649-001
GND                      U9F5             G8       K4B1G16_BGA1-IC,G38649-001
GND                      U9F5             G9       K4B1G16_BGA1-IC,G38649-001
GND                      U9F5             J2       K4B1G16_BGA1-IC,G38649-001
GND                      U9F5             J8       K4B1G16_BGA1-IC,G38649-001
GND                      U9F5             M1       K4B1G16_BGA1-IC,G38649-001
GND                      U9F5             M9       K4B1G16_BGA1-IC,G38649-001
GND                      U9F5             P1       K4B1G16_BGA1-IC,G38649-001
GND                      U9F5             P9       K4B1G16_BGA1-IC,G38649-001
GND                      U9F5             T1       K4B1G16_BGA1-IC,G38649-001
GND                      U9F5             T9       K4B1G16_BGA1-IC,G38649-001
GND                      U9G1             7        GTL2014_SM-IC,D66151-001
GND                      U9G1             8        GTL2014_SM-IC,D66151-001
GND                      U9G1             11       GTL2014_SM-IC,D66151-001
GND                      U9P1             5        TPS3700_SM-IC,H69492-001
GND                      U9P2             5        TPS3700_SM-IC,H69492-001
GND                      VR1D1            2        ZENER_SM-13V,IC,H69095-001
GND                      XBT8G1           3        VERT_BATT_3PIN_PIP-3PVERT,C686A
GND                      Y3F1             3        OSC_C_6P10-156.25MHZ,OSC,G6383A
GND                      Y6F1             3        OSC_C_6P10-156.25MHZ,OSC,G6383A
GND                      Y9F2             2        OSC_C_SM4-24MHZ,OSC,D34520-021
GND_LAN_TRCT1234_C       C9G4             1        CAP_A_0402V-0.1UF,16V,10%,X7R,A
GND_LAN_TRCT1234_C       C9G5             1        CAP_0402-1.0UF,16V,10%,X7S,G71A
GND_LAN_TRCT1234_C       C9G6             1        CAP_A_0402V-0.1UF,16V,10%,X7R,A
GND_LAN_TRCT1234_C       JA9G1            R1       CONN17_H71061002_PIP1-CONN,H71A
GND_LAN_TRCT1234_C       JA9G1            R6       CONN17_H71061002_PIP1-CONN,H71A
GND_LAN_TRCT1234_C       JA9G1            R7       CONN17_H71061002_PIP1-CONN,H71A
GND_LAN_TRCT1234_C       JA9G1            R12      CONN17_H71061002_PIP1-CONN,H71A
GND_NIC                  JA9G1            MH1      CONN17_H71061002_PIP1-CONN,H71A
GND_NIC                  JA9G1            MH2      CONN17_H71061002_PIP1-CONN,H71A
GND_NIC                  R1U3             2        RES_0402-0.0,5%,1/16W,CHIP,G21A
GND_NIC                  R1U51            2        RES_0402-0.0,5%,1/16W,CHIP,G21A
H_CPU0_ABC_MEMHOT_LVT3_R_N R1U59            1        RES_0402-0.0,5%,1/16W,CHIP,G21A
H_CPU0_ABC_MEMHOT_LVT3_R_N U9G1             9        GTL2014_SM-IC,D66151-001
H_CPU0_BMCINIT           R6D7             2        RES_0402-240,1.0%,1/16W,EMPTY,A
H_CPU0_BMCINIT           R6D16            2        RES_0402-0.0,5%,1/16W,EMPTY,G2A
H_CPU0_BMCINIT           U5D1             BD23     SKX_EXT_B_BGA1-IC,TBD
H_CPU0_CATERR_G_N        R3P59            1        RES_0402-0.0,5%,1/16W,CHIP,G21A
H_CPU0_CATERR_G_N        R4R2             2        RES_0402-150.0,1%,1/16W,CHIP,GA
H_CPU0_CATERR_G_N        U5D1             AL14     SKX_EXT_B_BGA1-IC,TBD
H_CPU0_DEF_MEMHOT_LVT3_R_N R9G33            1        RES_0402-0.0,5%,1/16W,CHIP,G21A
H_CPU0_DEF_MEMHOT_LVT3_R_N U9G1             10       GTL2014_SM-IC,D66151-001
H_CPU0_ERR0_G_N          R2T17            1        RES_0402-0.0,5%,1/16W,CHIP,G21A
H_CPU0_ERR0_G_N          U5D1             AJ12     SKX_EXT_B_BGA1-IC,TBD
H_CPU0_ERR1_G_N          R2T32            1        RES_0402-0.0,5%,1/16W,CHIP,G21A
H_CPU0_ERR1_G_N          U5D1             AK11     SKX_EXT_B_BGA1-IC,TBD
H_CPU0_ERR2_G_N          R2T40            1        RES_0402-0.0,5%,1/16W,CHIP,G21A
H_CPU0_ERR2_G_N          U5D1             AL12     SKX_EXT_B_BGA1-IC,TBD
H_CPU0_FAST_WAKE         Q2T1             3        NPN_SM-MMBT3904,IC,C52245-001
H_CPU0_FAST_WAKE         Q2T2             1        FET_N_SOT23LF-2N7002,FET,C7925A
H_CPU0_FAST_WAKE         R2T5             2        RES_0402-1.00K,1%,1/16W,CHIP,GA
H_CPU0_FAST_WAKE_B_N     Q2T1             1        NPN_SM-MMBT3904,IC,C52245-001
H_CPU0_FAST_WAKE_B_N     R4R1             2        RES_0402-1.00K,1%,1/16W,CHIP,GA
H_CPU0_FAST_WAKE_LVT3_N  Q2T2             3        FET_N_SOT23LF-2N7002,FET,C7925A
H_CPU0_FAST_WAKE_LVT3_N  R2T7             2        RES_0402-1.00K,1%,1/16W,CHIP,GA
H_CPU0_FAST_WAKE_LVT3_N  U7C1             BV47     LBG_CORE_QAT_EXT_D_BGA1-IC,H91A
H_CPU0_FAST_WAKE_LVT3_N  U9F4             C17      AST1250_BGA-IC,G85138-002
H_CPU0_FAST_WAKE_N       R3D18            1        RES_0402-0.0,5%,1/16W,CHIP,G21A
H_CPU0_FAST_WAKE_N       R4R1             1        RES_0402-1.00K,1%,1/16W,CHIP,GA
H_CPU0_FAST_WAKE_N       R4R4             2        RES_0402-150.0,1%,1/16W,CHIP,GA
H_CPU0_FAST_WAKE_N       U5D1             AF15     SKX_EXT_B_BGA1-IC,TBD
H_CPU0_FIVR_FAULT_G      U5D1             AU14     SKX_EXT_B_BGA1-IC,TBD
H_CPU0_FIVR_FAULT_G      U7D2             3        GTL2014_SM-IC,D66151-001
H_CPU0_MEMABC_MEMHOT     Q3U1             5        FET_N_DUAL_SMLF-NTJD4001N,FET,A
H_CPU0_MEMABC_MEMHOT     Q3U1             6        FET_N_DUAL_SMLF-NTJD4001N,FET,A
H_CPU0_MEMABC_MEMHOT     R7G7             2        RES_0402-4.75K,1%,1/16W,CHIP,GA
H_CPU0_MEMABC_MEMHOT_G_N Q2U1             6        FET_N_DUAL_SMLF-NTJD4001N,FET,A
H_CPU0_MEMABC_MEMHOT_G_N Q3U1             3        FET_N_DUAL_SMLF-NTJD4001N,FET,A
H_CPU0_MEMABC_MEMHOT_G_N R2U40            2        RES_0402-150.0,1%,1/16W,CHIP,GA
H_CPU0_MEMABC_MEMHOT_G_N R2U51            2        RES_0402-0.0,5%,1/16W,EMPTY,G2A
H_CPU0_MEMABC_MEMHOT_G_N R4P17            1        RES_0402-150.0,1%,1/16W,CHIP,GA
H_CPU0_MEMABC_MEMHOT_G_N R9G34            1        RES_0402-0.0,5%,1/16W,CHIP,G21A
H_CPU0_MEMABC_MEMHOT_G_N U5D1             AH13     SKX_EXT_B_BGA1-IC,TBD
H_CPU0_MEMABC_MEMHOT_G_PCH_N R2U49            1        RES_0402-0.0,5%,1/16W,EMPTY,G2A
H_CPU0_MEMABC_MEMHOT_G_PCH_N R2U51            1        RES_0402-0.0,5%,1/16W,EMPTY,G2A
H_CPU0_MEMABC_MEMHOT_G_R_N R9G34            2        RES_0402-0.0,5%,1/16W,CHIP,G21A
H_CPU0_MEMABC_MEMHOT_G_R_N U9G1             6        GTL2014_SM-IC,D66151-001
H_CPU0_MEMABC_MEMHOT_LVT3_BMC_N R2U47            2        RES_0402-0.0,5%,1/16W,CHIP,G21A
H_CPU0_MEMABC_MEMHOT_LVT3_BMC_N U9F4             A2       AST1250_BGA-IC,G85138-002
H_CPU0_MEMABC_MEMHOT_LVT3_K_N R1U46            1        RES_0402-33.2,1%,1/16W,CHIP,G2A
H_CPU0_MEMABC_MEMHOT_LVT3_K_N R1U59            2        RES_0402-0.0,5%,1/16W,CHIP,G21A
H_CPU0_MEMABC_MEMHOT_LVT3_K_N R2U49            2        RES_0402-0.0,5%,1/16W,EMPTY,G2A
H_CPU0_MEMABC_MEMHOT_LVT3_N R1U46            2        RES_0402-33.2,1%,1/16W,CHIP,G2A
H_CPU0_MEMABC_MEMHOT_LVT3_N R2U47            1        RES_0402-0.0,5%,1/16W,CHIP,G21A
H_CPU0_MEMABC_MEMHOT_LVT3_N R3N30            1        RES_0402-0.0,5%,1/16W,EMPTY,G2A
H_CPU0_MEMABC_MEMHOT_PCH_N R3N30            2        RES_0402-0.0,5%,1/16W,EMPTY,G2A
H_CPU0_MEMABC_MEMHOT_PCH_N U7C1             Y15      LBG_CORE_QAT_EXT_D_BGA1-IC,H91A
H_CPU0_MEMDEF_MEMHOT     Q7E1             5        FET_N_DUAL_SMLF-NTJD4001N,FET,A
H_CPU0_MEMDEF_MEMHOT     Q7E1             6        FET_N_DUAL_SMLF-NTJD4001N,FET,A
H_CPU0_MEMDEF_MEMHOT     R3R4             2        RES_0402-4.75K,1%,1/16W,CHIP,GA
H_CPU0_MEMDEF_MEMHOT_G_N Q2U1             3        FET_N_DUAL_SMLF-NTJD4001N,FET,A
H_CPU0_MEMDEF_MEMHOT_G_N Q7E1             3        FET_N_DUAL_SMLF-NTJD4001N,FET,A
H_CPU0_MEMDEF_MEMHOT_G_N R1U56            2        RES_0402-0.0,5%,1/16W,EMPTY,G2A
H_CPU0_MEMDEF_MEMHOT_G_N R1U58            1        RES_0402-0.0,5%,1/16W,CHIP,G21A
H_CPU0_MEMDEF_MEMHOT_G_N R2U41            2        RES_0402-150.0,1%,1/16W,CHIP,GA
H_CPU0_MEMDEF_MEMHOT_G_N R4P20            1        RES_0402-150.0,1%,1/16W,CHIP,GA
H_CPU0_MEMDEF_MEMHOT_G_N U5D1             AF13     SKX_EXT_B_BGA1-IC,TBD
H_CPU0_MEMDEF_MEMHOT_G_PCH_N R1U56            1        RES_0402-0.0,5%,1/16W,EMPTY,G2A
H_CPU0_MEMDEF_MEMHOT_G_PCH_N R9G27            1        RES_0402-0.0,5%,1/16W,EMPTY,G2A
H_CPU0_MEMDEF_MEMHOT_G_R_N R1U58            2        RES_0402-0.0,5%,1/16W,CHIP,G21A
H_CPU0_MEMDEF_MEMHOT_G_R_N U9G1             5        GTL2014_SM-IC,D66151-001
H_CPU0_MEMDEF_MEMHOT_LVT3_BMC_N R9G29            2        RES_0402-0.0,5%,1/16W,CHIP,G21A
H_CPU0_MEMDEF_MEMHOT_LVT3_BMC_N U9F4             E5       AST1250_BGA-IC,G85138-002
H_CPU0_MEMDEF_MEMHOT_LVT3_K_N R9G27            2        RES_0402-0.0,5%,1/16W,EMPTY,G2A
H_CPU0_MEMDEF_MEMHOT_LVT3_K_N R9G31            1        RES_0402-33.2,1%,1/16W,CHIP,G2A
H_CPU0_MEMDEF_MEMHOT_LVT3_K_N R9G33            2        RES_0402-0.0,5%,1/16W,CHIP,G21A
H_CPU0_MEMDEF_MEMHOT_LVT3_N R9G29            1        RES_0402-0.0,5%,1/16W,CHIP,G21A
H_CPU0_MEMDEF_MEMHOT_LVT3_N R9G30            1        RES_0402-0.0,5%,1/16W,EMPTY,G2A
H_CPU0_MEMDEF_MEMHOT_LVT3_N R9G31            2        RES_0402-33.2,1%,1/16W,CHIP,G2A
H_CPU0_MEMDEF_MEMHOT_PCH_N R9G30            2        RES_0402-0.0,5%,1/16W,EMPTY,G2A
H_CPU0_MEMDEF_MEMHOT_PCH_N U7C1             AD13     LBG_CORE_QAT_EXT_D_BGA1-IC,H91A
H_CPU0_MSMI_G_N          R6D9             2        RES_0402-150.0,1%,1/16W,CHIP,GA
H_CPU0_MSMI_G_N          R7D27            1        RES_0402-0.0,5%,1/16W,CHIP,G21A
H_CPU0_MSMI_G_N          U5D1             AN20     SKX_EXT_B_BGA1-IC,TBD
H_CPU0_PROCHOT_G_N       Q7E3             6        FET_N_DUAL_SMLF-NTJD4001N,FET,A
H_CPU0_PROCHOT_G_N       Q7E5             3        FET_N_DUAL_SMLF-NTJD4001N,FET,A
H_CPU0_PROCHOT_G_N       R2T59            1        RES_0402-0.0,5%,1/16W,EMPTY,G2A
H_CPU0_PROCHOT_G_N       R2T60            1        RES_0402-0.0,5%,1/16W,CHIP,G21A
H_CPU0_PROCHOT_G_N       R2T72            2        RES_0402-150.0,1%,1/16W,CHIP,GA
H_CPU0_PROCHOT_G_N       R4R3             2        RES_0402-150.0,1%,1/16W,CHIP,GA
H_CPU0_PROCHOT_G_N       U5D1             AC16     SKX_EXT_B_BGA1-IC,TBD
H_CPU0_PROCHOT_G_PCH_N   R2T59            2        RES_0402-0.0,5%,1/16W,EMPTY,G2A
H_CPU0_PROCHOT_G_PCH_N   R2T71            2        RES_0402-0.0,5%,1/16W,EMPTY,G2A
H_CPU0_PROCHOT_G_R_N     R2T60            2        RES_0402-0.0,5%,1/16W,CHIP,G21A
H_CPU0_PROCHOT_G_R_N     U2T4             3        GTL2014_SM-IC,D66151-001
H_CPU0_THERMTRIP_G_N     R7E2             2        RES_0402-75,1.0%,1/16W,CHIP,G2A
H_CPU0_THERMTRIP_G_N     U5D1             AB15     SKX_EXT_B_BGA1-IC,TBD
H_CPU0_THERMTRIP_G_N     U7D2             6        GTL2014_SM-IC,D66151-001
H_CPU1_BMCINIT           R3D16            2        RES_0402-240,1.0%,1/16W,EMPTY,A
H_CPU1_BMCINIT           R3D31            2        RES_0402-0.0,5%,1/16W,EMPTY,G2A
H_CPU1_BMCINIT           U2D1             BD23     SKX_EXT_B_BGA1-IC,TBD
H_CPU1_CATERR_G_N        R3P58            1        RES_0402-0.0,5%,1/16W,CHIP,G21A
H_CPU1_CATERR_G_N        R7P18            2        RES_0402-150.0,1%,1/16W,CHIP,GA
H_CPU1_CATERR_G_N        U2D1             AL14     SKX_EXT_B_BGA1-IC,TBD
H_CPU1_ERR0_G_N          R2T20            1        RES_0402-0.0,5%,1/16W,CHIP,G21A
H_CPU1_ERR0_G_N          U2D1             AJ12     SKX_EXT_B_BGA1-IC,TBD
H_CPU1_ERR1_G_N          R2T27            1        RES_0402-0.0,5%,1/16W,CHIP,G21A
H_CPU1_ERR1_G_N          U2D1             AK11     SKX_EXT_B_BGA1-IC,TBD
H_CPU1_ERR2_G_N          R2T44            1        RES_0402-0.0,5%,1/16W,CHIP,G21A
H_CPU1_ERR2_G_N          U2D1             AL12     SKX_EXT_B_BGA1-IC,TBD
H_CPU1_FAST_WAKE_N       R3D18            2        RES_0402-0.0,5%,1/16W,CHIP,G21A
H_CPU1_FAST_WAKE_N       R7P20            2        RES_0402-150.0,1%,1/16W,CHIP,GA
H_CPU1_FAST_WAKE_N       U2D1             AF15     SKX_EXT_B_BGA1-IC,TBD
H_CPU1_FIVR_FAULT_G      R3R2             1        RES_0402-1.00K,1%,1/16W,CHIP,GA
H_CPU1_FIVR_FAULT_G      U2D1             AU14     SKX_EXT_B_BGA1-IC,TBD
H_CPU1_FIVR_FAULT_G      U3P2             3        GTL2014_SM-IC,D66151-001
H_CPU1_GHJ_MEMHOT_LVT3_R_N R9G32            1        RES_0402-0.0,5%,1/16W,CHIP,G21A
H_CPU1_GHJ_MEMHOT_LVT3_R_N U9G1             12       GTL2014_SM-IC,D66151-001
H_CPU1_KLM_MEMHOT_LVT3_R_N R9G28            1        RES_0402-0.0,5%,1/16W,CHIP,G21A
H_CPU1_KLM_MEMHOT_LVT3_R_N U9G1             13       GTL2014_SM-IC,D66151-001
H_CPU1_MEMGHJ_MEMHOT     Q7E2             5        FET_N_DUAL_SMLF-NTJD4001N,FET,A
H_CPU1_MEMGHJ_MEMHOT     Q7E2             6        FET_N_DUAL_SMLF-NTJD4001N,FET,A
H_CPU1_MEMGHJ_MEMHOT     R3R10            2        RES_0402-4.75K,1%,1/16W,CHIP,GA
H_CPU1_MEMGHJ_MEMHOT_G_N Q4B2             6        FET_N_DUAL_SMLF-NTJD4001N,FET,A
H_CPU1_MEMGHJ_MEMHOT_G_N Q7E2             3        FET_N_DUAL_SMLF-NTJD4001N,FET,A
H_CPU1_MEMGHJ_MEMHOT_G_N R1U41            2        RES_0402-150.0,1%,1/16W,CHIP,GA
H_CPU1_MEMGHJ_MEMHOT_G_N R1U53            1        RES_0402-0.0,5%,1/16W,CHIP,G21A
H_CPU1_MEMGHJ_MEMHOT_G_N R1U55            1        RES_0402-0.0,5%,1/16W,EMPTY,G2A
H_CPU1_MEMGHJ_MEMHOT_G_N R7P5             1        RES_0402-150.0,1%,1/16W,CHIP,GA
H_CPU1_MEMGHJ_MEMHOT_G_N U2D1             AH13     SKX_EXT_B_BGA1-IC,TBD
H_CPU1_MEMGHJ_MEMHOT_G_PCH_N R1U55            2        RES_0402-0.0,5%,1/16W,EMPTY,G2A
H_CPU1_MEMGHJ_MEMHOT_G_PCH_N R1U57            2        RES_0402-0.0,5%,1/16W,EMPTY,G2A
H_CPU1_MEMGHJ_MEMHOT_G_R_N R1U53            2        RES_0402-0.0,5%,1/16W,CHIP,G21A
H_CPU1_MEMGHJ_MEMHOT_G_R_N U9G1             3        GTL2014_SM-IC,D66151-001
H_CPU1_MEMGHJ_MEMHOT_LVT3_BMC_N R1U54            2        RES_0402-0.0,5%,1/16W,CHIP,G21A
H_CPU1_MEMGHJ_MEMHOT_LVT3_BMC_N U9F4             B2       AST1250_BGA-IC,G85138-002
H_CPU1_MEMGHJ_MEMHOT_LVT3_K_N R1U36            1        RES_0402-33.2,1%,1/16W,CHIP,G2A
H_CPU1_MEMGHJ_MEMHOT_LVT3_K_N R1U57            1        RES_0402-0.0,5%,1/16W,EMPTY,G2A
H_CPU1_MEMGHJ_MEMHOT_LVT3_K_N R9G32            2        RES_0402-0.0,5%,1/16W,CHIP,G21A
H_CPU1_MEMGHJ_MEMHOT_LVT3_N R1U36            2        RES_0402-33.2,1%,1/16W,CHIP,G2A
H_CPU1_MEMGHJ_MEMHOT_LVT3_N R1U54            1        RES_0402-0.0,5%,1/16W,CHIP,G21A
H_CPU1_MEMGHJ_MEMHOT_LVT3_N R3P63            1        RES_0402-0.0,5%,1/16W,EMPTY,G2A
H_CPU1_MEMGHJ_MEMHOT_PCH_N R3P63            2        RES_0402-0.0,5%,1/16W,EMPTY,G2A
H_CPU1_MEMGHJ_MEMHOT_PCH_N U7C1             AA13     LBG_CORE_QAT_EXT_D_BGA1-IC,H91A
H_CPU1_MEMKLM_MEMHOT     Q4B1             5        FET_N_DUAL_SMLF-NTJD4001N,FET,A
H_CPU1_MEMKLM_MEMHOT     Q4B1             6        FET_N_DUAL_SMLF-NTJD4001N,FET,A
H_CPU1_MEMKLM_MEMHOT     R6M4             2        RES_0402-4.75K,1%,1/16W,CHIP,GA
H_CPU1_MEMKLM_MEMHOT_G_N Q4B1             3        FET_N_DUAL_SMLF-NTJD4001N,FET,A
H_CPU1_MEMKLM_MEMHOT_G_N Q4B2             3        FET_N_DUAL_SMLF-NTJD4001N,FET,A
H_CPU1_MEMKLM_MEMHOT_G_N R1U35            2        RES_0402-150.0,1%,1/16W,CHIP,GA
H_CPU1_MEMKLM_MEMHOT_G_N R1U60            1        RES_0402-0.0,5%,1/16W,CHIP,G21A
H_CPU1_MEMKLM_MEMHOT_G_N R1U62            1        RES_0402-0.0,5%,1/16W,EMPTY,G2A
H_CPU1_MEMKLM_MEMHOT_G_N R7P21            1        RES_0402-150.0,1%,1/16W,CHIP,GA
H_CPU1_MEMKLM_MEMHOT_G_N U2D1             AF13     SKX_EXT_B_BGA1-IC,TBD
H_CPU1_MEMKLM_MEMHOT_G_PCH_N R1U61            2        RES_0402-0.0,5%,1/16W,EMPTY,G2A
H_CPU1_MEMKLM_MEMHOT_G_PCH_N R1U62            2        RES_0402-0.0,5%,1/16W,EMPTY,G2A
H_CPU1_MEMKLM_MEMHOT_G_R_N R1U60            2        RES_0402-0.0,5%,1/16W,CHIP,G21A
H_CPU1_MEMKLM_MEMHOT_G_R_N U9G1             2        GTL2014_SM-IC,D66151-001
H_CPU1_MEMKLM_MEMHOT_LVT3_BMC_N R2U46            2        RES_0402-0.0,5%,1/16W,CHIP,G21A
H_CPU1_MEMKLM_MEMHOT_LVT3_BMC_N U9F4             A1       AST1250_BGA-IC,G85138-002
H_CPU1_MEMKLM_MEMHOT_LVT3_K_N R1U34            1        RES_0402-33.2,1%,1/16W,CHIP,G2A
H_CPU1_MEMKLM_MEMHOT_LVT3_K_N R1U61            1        RES_0402-0.0,5%,1/16W,EMPTY,G2A
H_CPU1_MEMKLM_MEMHOT_LVT3_K_N R9G28            2        RES_0402-0.0,5%,1/16W,CHIP,G21A
H_CPU1_MEMKLM_MEMHOT_LVT3_N R1U34            2        RES_0402-33.2,1%,1/16W,CHIP,G2A
H_CPU1_MEMKLM_MEMHOT_LVT3_N R2U45            1        RES_0402-0.0,5%,1/16W,EMPTY,G2A
H_CPU1_MEMKLM_MEMHOT_LVT3_N R2U46            1        RES_0402-0.0,5%,1/16W,CHIP,G21A
H_CPU1_MEMKLM_MEMHOT_PCH_N R2U45            2        RES_0402-0.0,5%,1/16W,EMPTY,G2A
H_CPU1_MEMKLM_MEMHOT_PCH_N U7C1             Y11      LBG_CORE_QAT_EXT_D_BGA1-IC,H91A
H_CPU1_MSMI_G_N          R7D28            1        RES_0402-0.0,5%,1/16W,CHIP,G21A
H_CPU1_MSMI_G_N          R7P27            2        RES_0402-150.0,1%,1/16W,CHIP,GA
H_CPU1_MSMI_G_N          U2D1             AN20     SKX_EXT_B_BGA1-IC,TBD
H_CPU1_PROCHOT_G_N       Q7E3             3        FET_N_DUAL_SMLF-NTJD4001N,FET,A
H_CPU1_PROCHOT_G_N       Q7E6             3        FET_N_DUAL_SMLF-NTJD4001N,FET,A
H_CPU1_PROCHOT_G_N       R2T68            1        RES_0402-0.0,5%,1/16W,CHIP,G21A
H_CPU1_PROCHOT_G_N       R2T69            1        RES_0402-0.0,5%,1/16W,EMPTY,G2A
H_CPU1_PROCHOT_G_N       R2T73            2        RES_0402-150.0,1%,1/16W,CHIP,GA
H_CPU1_PROCHOT_G_N       R7P28            2        RES_0402-150.0,1%,1/16W,CHIP,GA
H_CPU1_PROCHOT_G_N       U2D1             AC16     SKX_EXT_B_BGA1-IC,TBD
H_CPU1_PROCHOT_G_PCH_N   R2T69            2        RES_0402-0.0,5%,1/16W,EMPTY,G2A
H_CPU1_PROCHOT_G_PCH_N   R7D43            2        RES_0402-0.0,5%,1/16W,EMPTY,G2A
H_CPU1_PROCHOT_G_R_N     R2T68            2        RES_0402-0.0,5%,1/16W,CHIP,G21A
H_CPU1_PROCHOT_G_R_N     U2T4             2        GTL2014_SM-IC,D66151-001
H_CPU1_THERMTRIP_G_N     R3P41            2        RES_0402-75,1.0%,1/16W,CHIP,G2A
H_CPU1_THERMTRIP_G_N     U2D1             AB15     SKX_EXT_B_BGA1-IC,TBD
H_CPU1_THERMTRIP_G_N     U3P2             6        GTL2014_SM-IC,D66151-001
H_CPU_CATERR_G_N         R3P58            2        RES_0402-0.0,5%,1/16W,CHIP,G21A
H_CPU_CATERR_G_N         R3P59            2        RES_0402-0.0,5%,1/16W,CHIP,G21A
H_CPU_CATERR_G_N         U3P2             5        GTL2014_SM-IC,D66151-001
H_CPU_ERR0_GTL_N         R2T16            2        RES_0402-75,1.0%,1/16W,CHIP,G2A
H_CPU_ERR0_GTL_N         U2T4             6        GTL2014_SM-IC,D66151-001
H_CPU_ERR0_GTL_R_N       R2T16            1        RES_0402-75,1.0%,1/16W,CHIP,G2A
H_CPU_ERR0_GTL_R_N       R2T17            2        RES_0402-0.0,5%,1/16W,CHIP,G21A
H_CPU_ERR0_GTL_R_N       R2T19            2        RES_0402-200.0,1%,1/16W,CHIP,GA
H_CPU_ERR0_GTL_R_N       R2T20            2        RES_0402-0.0,5%,1/16W,CHIP,G21A
H_CPU_ERR0_GTL_R_N       R2T57            2        RES_0402-0.0,5%,1/16W,EMPTY,G2A
H_CPU_ERR0_PCH_N         R2T57            1        RES_0402-0.0,5%,1/16W,EMPTY,G2A
H_CPU_ERR0_PCH_N         R2T58            1        RES_0402-0.0,5%,1/16W,EMPTY,G2A
H_CPU_ERR1_GTL_N         R2T31            2        RES_0402-75,1.0%,1/16W,CHIP,G2A
H_CPU_ERR1_GTL_N         U2T4             5        GTL2014_SM-IC,D66151-001
H_CPU_ERR1_GTL_R_N       R2T26            2        RES_0402-200.0,1%,1/16W,CHIP,GA
H_CPU_ERR1_GTL_R_N       R2T27            2        RES_0402-0.0,5%,1/16W,CHIP,G21A
H_CPU_ERR1_GTL_R_N       R2T31            1        RES_0402-75,1.0%,1/16W,CHIP,G2A
H_CPU_ERR1_GTL_R_N       R2T32            2        RES_0402-0.0,5%,1/16W,CHIP,G21A
H_CPU_ERR1_GTL_R_N       R2T61            2        RES_0402-0.0,5%,1/16W,EMPTY,G2A
H_CPU_ERR1_PCH_N         R2T61            1        RES_0402-0.0,5%,1/16W,EMPTY,G2A
H_CPU_ERR1_PCH_N         R2T62            1        RES_0402-0.0,5%,1/16W,EMPTY,G2A
H_CPU_ERR2_GTL_N         R2T43            2        RES_0402-75,1.0%,1/16W,CHIP,G2A
H_CPU_ERR2_GTL_N         U7D2             5        GTL2014_SM-IC,D66151-001
H_CPU_ERR2_G_R_N         R2T37            2        RES_0402-200.0,1%,1/16W,CHIP,GA
H_CPU_ERR2_G_R_N         R2T40            2        RES_0402-0.0,5%,1/16W,CHIP,G21A
H_CPU_ERR2_G_R_N         R2T43            1        RES_0402-75,1.0%,1/16W,CHIP,G2A
H_CPU_ERR2_G_R_N         R2T44            2        RES_0402-0.0,5%,1/16W,CHIP,G21A
H_CPU_MSMI_G_N           R7D27            2        RES_0402-0.0,5%,1/16W,CHIP,G21A
H_CPU_MSMI_G_N           R7D28            2        RES_0402-0.0,5%,1/16W,CHIP,G21A
H_CPU_MSMI_G_N           U7D2             2        GTL2014_SM-IC,D66151-001
H_PMSYNC_CLK_24M         R4P19            2        RES_0402-49.9,1%,1/16W,CHIP,G2A
H_PMSYNC_CLK_24M         R7P26            2        RES_0402-49.9,1%,1/16W,CHIP,G2A
H_PMSYNC_CLK_24M         R8B20            2        RES_0402-10.0,1%,1/16W,CHIP,G2A
H_PMSYNC_CLK_24M         R8B21            1        RES_0402-49.9,1%,1/16W,EMPTY,GA
H_PMSYNC_CLK_24M_CPU0    R4P19            1        RES_0402-49.9,1%,1/16W,CHIP,G2A
H_PMSYNC_CLK_24M_CPU0    U5D1             AT19     SKX_EXT_B_BGA1-IC,TBD
H_PMSYNC_CLK_24M_CPU1    R7P26            1        RES_0402-49.9,1%,1/16W,CHIP,G2A
H_PMSYNC_CLK_24M_CPU1    U2D1             AT19     SKX_EXT_B_BGA1-IC,TBD
H_PMSYNC_CLK_24M_R       R8B20            1        RES_0402-10.0,1%,1/16W,CHIP,G2A
H_PMSYNC_CLK_24M_R       U7C1             BY51     LBG_CORE_QAT_EXT_D_BGA1-IC,H91A
H_PM_SYNC1_GTL_R         R3N9             1        RES_0402-10.0,1%,1/16W,CHIP,G2A
H_PM_SYNC1_GTL_R         U7C1             U13      LBG_CORE_QAT_EXT_D_BGA1-IC,H91A
H_PM_SYNC_GTL            R3N9             2        RES_0402-10.0,1%,1/16W,CHIP,G2A
H_PM_SYNC_GTL            R3N14            1        RES_0402-49.9,1%,1/16W,EMPTY,GA
H_PM_SYNC_GTL            R4P18            2        RES_0402-49.9,1%,1/16W,CHIP,G2A
H_PM_SYNC_GTL            R7P25            2        RES_0402-49.9,1%,1/16W,CHIP,G2A
H_PM_SYNC_GTL_R1         R4P18            1        RES_0402-49.9,1%,1/16W,CHIP,G2A
H_PM_SYNC_GTL_R1         U5D1             AR14     SKX_EXT_B_BGA1-IC,TBD
H_PM_SYNC_GTL_R2         R7P25            1        RES_0402-49.9,1%,1/16W,CHIP,G2A
H_PM_SYNC_GTL_R2         U2D1             AR14     SKX_EXT_B_BGA1-IC,TBD
IRQ_BMC_PCH_NMI_STBY_N   R8E22            2        RES_0402-4.75K,1%,1/16W,CHIP,GA
IRQ_BMC_PCH_NMI_STBY_N   R8E24            1        RES_0402-33.2,1%,1/16W,CHIP,G2A
IRQ_BMC_PCH_NMI_STBY_N   U7C1             BB52     LBG_CORE_QAT_EXT_D_BGA1-IC,H91A
IRQ_BMC_PCH_NMI_STBY_N   U9F4             D16      AST1250_BGA-IC,G85138-002
IRQ_BMC_PCH_NMI_STBY_R_N R8E24            2        RES_0402-33.2,1%,1/16W,CHIP,G2A
IRQ_BMC_PCH_NMI_STBY_R_N U7C1             BR42     LBG_CORE_QAT_EXT_D_BGA1-IC,H91A
IRQ_BMC_PCH_SCI_LPC_N    R8C2             2        RES_0402-4.75K,1%,1/16W,CHIP,GA
IRQ_BMC_PCH_SCI_LPC_N    U7C1             BN48     LBG_CORE_QAT_EXT_D_BGA1-IC,H91A
IRQ_BMC_PCH_SCI_LPC_N    U7C1             BY38     LBG_CORE_QAT_EXT_D_BGA1-IC,H91A
IRQ_BMC_PCH_SCI_LPC_N    U9F4             E14      AST1250_BGA-IC,G85138-002
IRQ_BMC_PCH_SMI_LPC_N    R8C4             2        RES_0402-1.00K,1%,1/16W,CHIP,GA
IRQ_BMC_PCH_SMI_LPC_N    U7C1             AW54     LBG_CORE_QAT_EXT_D_BGA1-IC,H91A
IRQ_BMC_PCH_SMI_LPC_N    U7C1             CA34     LBG_CORE_QAT_EXT_D_BGA1-IC,H91A
IRQ_BMC_PCH_SMI_LPC_N    U9F4             D14      AST1250_BGA-IC,G85138-002
IRQ_BOARD_BMC_ALERT_N    J1C1             B5       CONN76_H22707001_THMT1-CONN,H2A
IRQ_BOARD_BMC_ALERT_N    R1C9             1        RES_0402-0.0,5%,1/16W,EMPTY,G2A
IRQ_BOARD_BMC_ALERT_N    R2N7             2        RES_0402-4.75K,1%,1/16W,CHIP,GA
IRQ_BOARD_BMC_ALERT_N    U7C1             BW24     LBG_CORE_QAT_EXT_D_BGA1-IC,H91A
IRQ_BOARD_BMC_ALERT_N    U9F4             Y1       AST1250_BGA-IC,G85138-002
IRQ_CPU0_PROCHOT_G_N     Q7E5             2        FET_N_DUAL_SMLF-NTJD4001N,FET,A
IRQ_CPU0_PROCHOT_G_N     U7E2             4        TTL1G08_SOTLF-NC7SZ08,IC,D1032B
IRQ_CPU0_VRHOT           Q7E5             5        FET_N_DUAL_SMLF-NTJD4001N,FET,A
IRQ_CPU0_VRHOT           Q7E5             6        FET_N_DUAL_SMLF-NTJD4001N,FET,A
IRQ_CPU0_VRHOT           R7E10            2        RES_0402-4.75K,1%,1/16W,CHIP,GA
IRQ_CPU1_PROCHOT_G_N     Q7E6             2        FET_N_DUAL_SMLF-NTJD4001N,FET,A
IRQ_CPU1_PROCHOT_G_N     U7E3             4        TTL1G08_SOTLF-NC7SZ08,IC,D1032B
IRQ_CPU1_VRHOT           Q7E6             5        FET_N_DUAL_SMLF-NTJD4001N,FET,A
IRQ_CPU1_VRHOT           Q7E6             6        FET_N_DUAL_SMLF-NTJD4001N,FET,A
IRQ_CPU1_VRHOT           R7E11            2        RES_0402-4.75K,1%,1/16W,CHIP,GA
IRQ_DIMM_SAVE_LVT3       Q8D1             2        NPN_DUAL_SSOPLF-MBT3904,XSTR,CA
IRQ_DIMM_SAVE_LVT3       Q8D1             3        NPN_DUAL_SSOPLF-MBT3904,XSTR,CA
IRQ_DIMM_SAVE_LVT3       R8D29            2        RES_0402-4.75K,1%,1/16W,CHIP,GA
IRQ_DIMM_SAVE_LVT3_N     Q8D1             6        NPN_DUAL_SSOPLF-MBT3904,XSTR,CA
IRQ_DIMM_SAVE_LVT3_N     R2P12            1        RES_0402-0.0,5%,1/16W,EMPTY,G2A
IRQ_DIMM_SAVE_LVT3_N     R8D31            2        RES_0402-4.75K,1%,1/16W,CHIP,GA
IRQ_DIMM_SAVE_LVT3_N     U7C1             BW20     LBG_CORE_QAT_EXT_D_BGA1-IC,H91A
IRQ_DIMM_SAVE_LVT3_N     U9F4             U18      AST1250_BGA-IC,G85138-002
IRQ_DIMM_SAVE_N          Q6F1             3        FET_N_SOT23-2N7002,FET,C79254-A
IRQ_DIMM_SAVE_N          R6F1             1        RES_0402-49.9,1%,1/16W,CHIP,G2A
IRQ_DIMM_SAVE_N          R6F2             1        RES_0402-49.9,1%,1/16W,CHIP,G2A
IRQ_DIMM_SAVE_N          R6F3             2        RES_0402-10.0K,1%,1/16W,CHIP,GA
IRQ_DIMM_SAVE_N          R6F4             1        RES_0402-49.9,1%,1/16W,CHIP,G2A
IRQ_DIMM_SAVE_N          R6F5             1        RES_0402-49.9,1%,1/16W,CHIP,G2A
IRQ_DIMM_SAVE_N          R8D30            1        RES_0402-10.0K,1%,1/16W,CHIP,GA
IRQ_DIMM_SAVE_R_N        Q8D1             5        NPN_DUAL_SSOPLF-MBT3904,XSTR,CA
IRQ_DIMM_SAVE_R_N        R8D30            2        RES_0402-10.0K,1%,1/16W,CHIP,GA
IRQ_FORCE_NM_THROTTLE_N  R2P4             2        RES_0402-33.2,1%,1/16W,CHIP,G2A
IRQ_FORCE_NM_THROTTLE_N  R2T41            1        RES_0402-22.1,1.0%,1/16W,CHIP,A
IRQ_FORCE_NM_THROTTLE_N  U7C1             BA17     LBG_CORE_QAT_EXT_D_BGA1-IC,H91A
IRQ_FORCE_NM_THROTTLE_N  U7C1             BY42     LBG_CORE_QAT_EXT_D_BGA1-IC,H91A
IRQ_FORCE_NM_THROTTLE_N  U8E1             1        TTL08_QFN15-74LVC08A,IC,D90404B
IRQ_FORCE_NM_THROTTLE_R_N R2P3             2        RES_0402-4.75K,1%,1/16W,CHIP,GA
IRQ_FORCE_NM_THROTTLE_R_N R2P4             1        RES_0402-33.2,1%,1/16W,CHIP,G2A
IRQ_FORCE_NM_THROTTLE_R_N U8D3             4        TTL1G07_A_SOP-74LVC1G07,IC,C88B
IRQ_HFI0_CPU0_LVT2_N     J8B1             8        SCONN24_H46321001_SM-SCONN,H46A
IRQ_HFI0_CPU0_LVT2_N     R8B10            2        RES_0402-4.75K,1%,1/16W,CHIP,GA
IRQ_HFI0_CPU0_LVT2_N     U5D1             BP19     SKX_EXT_B_BGA1-IC,TBD
IRQ_HFI1_CPU0_LVT2_N     J8B1             16       SCONN24_H46321001_SM-SCONN,H46A
IRQ_HFI1_CPU0_LVT2_N     R8B17            2        RES_0402-4.75K,1%,1/16W,CHIP,GA
IRQ_HFI1_CPU0_LVT2_N     U5D1             BM21     SKX_EXT_B_BGA1-IC,TBD
IRQ_HSC_FAULT_N          R1D30            2        RES_0402-33.2,1%,1/16W,CHIP,G2A
IRQ_HSC_FAULT_N          R2M4             2        RES_0402-1.00K,1%,1/16W,CHIP,GA
IRQ_HSC_FAULT_N          U7C1             BJ44     LBG_CORE_QAT_EXT_D_BGA1-IC,H91A
IRQ_HSC_FAULT_N          U9F4             A20      AST1250_BGA-IC,G85138-002
IRQ_HSC_FAULT_R_N        EU1D2            6        ADM1278_SM-IC,G99251-001
IRQ_HSC_FAULT_R_N        R1D30            1        RES_0402-33.2,1%,1/16W,CHIP,G2A
IRQ_LOM_ALERT_N          EU9E1            35       SPRINGVILLE_SM1-IC,G47144-004
IRQ_LOM_ALERT_N          R9E7             2        RES_0402-3.32K,1%,1/16W,CHIP,GA
IRQ_LOM_ALERT_N          U7C1             BY47     LBG_CORE_QAT_EXT_D_BGA1-IC,H91A
IRQ_LOM_ALERT_N          U9F4             E16      AST1250_BGA-IC,G85138-002
IRQ_LPC_SERIRQ_N         R2T24            1        RES_0402-33.2,1%,1/16W,CHIP,G2A
IRQ_LPC_SERIRQ_N         R7D3             2        RES_0402-4.75K,1%,1/16W,CHIP,GA
IRQ_LPC_SERIRQ_N         U7C1             P2       LBG_CORE_QAT_EXT_D_BGA1-IC,H91A
IRQ_LPC_SERIRQ_R         R2T24            2        RES_0402-33.2,1%,1/16W,CHIP,G2A
IRQ_LPC_SERIRQ_R         U9F4             E17      AST1250_BGA-IC,G85138-002
IRQ_LVC3_WAKE_N          R3N13            2        RES_0402-4.75K,1%,1/16W,CHIP,GA
IRQ_LVC3_WAKE_N          R8E17            2        RES_0402-33.2,1%,1/16W,CHIP,G2A
IRQ_LVC3_WAKE_N          U7C1             K9       LBG_CORE_QAT_EXT_D_BGA1-IC,H91A
IRQ_LVC3_WAKE_R_N        R8E17            1        RES_0402-33.2,1%,1/16W,CHIP,G2A
IRQ_LVC3_WAKE_R_N        U8E4             4        TTL1G126_A_SOT-74HC1G126,IC,A7B
IRQ_MEZZ_LAN_ALERT_N     J9B3             28       SCONN120_A28699018_SM-SCONN,A2A
IRQ_MEZZ_LAN_ALERT_N     R8F23            2        RES_0402-2.21K,1%,1/16W,CHIP,GA
IRQ_MEZZ_LAN_ALERT_N     U7C1             BW45     LBG_CORE_QAT_EXT_D_BGA1-IC,H91A
IRQ_MEZZ_LAN_ALERT_N     U9F4             A19      AST1250_BGA-IC,G85138-002
IRQ_OC_DETECT_N          R1D23            2        RES_0402-10.0K,1%,1/16W,CHIP,GA
IRQ_OC_DETECT_N          R9P15            2        RES_0402-0.0,5%,1/16W,EMPTY,G2A
IRQ_OC_DETECT_N          U1D1             2        TTL1G126_A_SOT-74HC1G126,IC,A7B
IRQ_OC_DETECT_N          U1D2             1        TPS3700_SM-IC,H69492-001
IRQ_OC_DETECT_N          U7C1             AG7      LBG_CORE_QAT_EXT_D_BGA1-IC,H91A
IRQ_OC_DETECT_N          U9F4             T5       AST1250_BGA-IC,G85138-002
IRQ_OOB_MGMT_RISER_ALERT_N J8G1             16       SCONN200_H68296001_SM-CONN,H68A
IRQ_OOB_MGMT_RISER_ALERT_N R2T29            2        RES_0402-2.21K,1%,1/16W,CHIP,GA
IRQ_OOB_MGMT_RISER_ALERT_N U7C1             BV42     LBG_CORE_QAT_EXT_D_BGA1-IC,H91A
IRQ_OOB_MGMT_RISER_ALERT_N U9F4             D17      AST1250_BGA-IC,G85138-002
IRQ_PCH_NIC_ALERT_N      R8C25            2        RES_0402-4.75K,1%,1/16W,CHIP,GA
IRQ_PCH_NIC_ALERT_N      U7C1             AR17     LBG_CORE_QAT_EXT_D_BGA1-IC,H91A
IRQ_PCH_NIC_ALERT_N      U7C1             BG22     LBG_CORE_QAT_EXT_D_BGA1-IC,H91A
IRQ_PCH_NIC_ALERT_N      U9F4             E13      AST1250_BGA-IC,G85138-002
IRQ_PIRQA_SPI_TPM_N      R7D7             2        RES_0402-1.00K,1%,1/16W,CHIP,GA
IRQ_PIRQA_SPI_TPM_N      R8E1             2        RES_0402-0.0,5%,1/16W,CHIP,G21A
IRQ_PIRQA_SPI_TPM_N      U7C1             AA2      LBG_CORE_QAT_EXT_D_BGA1-IC,H91A
IRQ_PVCCIN_CPU0_VRHOT_LVC3_N R6P45            2        RES_0402-33.2,1%,1/16W,CHIP,G2A
IRQ_PVCCIN_CPU0_VRHOT_LVC3_N U7C1             BA9      LBG_CORE_QAT_EXT_D_BGA1-IC,H91A
IRQ_PVCCIN_CPU0_VRHOT_LVC3_N U7E2             2        TTL1G08_SOTLF-NC7SZ08,IC,D1032B
IRQ_PVCCIN_CPU0_VRHOT_LVC3_N U9F4             AB6      AST1250_BGA-IC,G85138-002
IRQ_PVCCIN_CPU0_VRHOT_LVC3_R_N EU4D4            13       PXE1610B_QFN-IC,H79206-001
IRQ_PVCCIN_CPU0_VRHOT_LVC3_R_N R4E3             2        RES_0402-1.00K,1%,1/16W,CHIP,GA
IRQ_PVCCIN_CPU0_VRHOT_LVC3_R_N R6P45            1        RES_0402-33.2,1%,1/16W,CHIP,G2A
IRQ_PVCCIN_CPU1_VRHOT_LVC3_N R9P3             2        RES_0402-33.2,1%,1/16W,CHIP,G2A
IRQ_PVCCIN_CPU1_VRHOT_LVC3_N U7C1             AW20     LBG_CORE_QAT_EXT_D_BGA1-IC,H91A
IRQ_PVCCIN_CPU1_VRHOT_LVC3_N U7E3             2        TTL1G08_SOTLF-NC7SZ08,IC,D1032B
IRQ_PVCCIN_CPU1_VRHOT_LVC3_N U9F4             Y7       AST1250_BGA-IC,G85138-002
IRQ_PVCCIN_CPU1_VRHOT_LVC3_R_N EU1C2            13       PXE1610B_QFN-IC,H79206-001
IRQ_PVCCIN_CPU1_VRHOT_LVC3_R_N R1D6             2        RES_0402-1.00K,1%,1/16W,CHIP,GA
IRQ_PVCCIN_CPU1_VRHOT_LVC3_R_N R9P3             1        RES_0402-33.2,1%,1/16W,CHIP,G2A
IRQ_PVCCIO_CPU0_VRHOT_N  EU3P1            11       PXE1110B_QFN-IC,H89187-001
IRQ_PVCCIO_CPU0_VRHOT_N  R3P18            2        RES_0402-1.00K,1%,1/16W,CHIP,GA
IRQ_PVCCIO_CPU1_VRHOT_N  EU4D5            11       PXE1110B_QFN-IC,H89187-001
IRQ_PVCCIO_CPU1_VRHOT_N  R4D49            2        RES_0402-1.00K,1%,1/16W,CHIP,GA
IRQ_PVDDQ_ABC_VRHOT_LVT3_N Q3U1             2        FET_N_DUAL_SMLF-NTJD4001N,FET,A
IRQ_PVDDQ_ABC_VRHOT_LVT3_N R7F23            2        RES_0402-33.2,1%,1/16W,CHIP,G2A
IRQ_PVDDQ_ABC_VRHOT_LVT3_N U7C1             BN7      LBG_CORE_QAT_EXT_D_BGA1-IC,H91A
IRQ_PVDDQ_ABC_VRHOT_LVT3_N U9F4             C4       AST1250_BGA-IC,G85138-002
IRQ_PVDDQ_ABC_VRHOT_LVT3_R_N EU7G1            11       PXM1310B_QFN-IC,H89186-001
IRQ_PVDDQ_ABC_VRHOT_LVT3_R_N R7F23            1        RES_0402-33.2,1%,1/16W,CHIP,G2A
IRQ_PVDDQ_ABC_VRHOT_LVT3_R_N R7F27            2        RES_0402-1.00K,1%,1/16W,CHIP,GA
IRQ_PVDDQ_DEF_VRHOT_LVT3_N Q7E1             2        FET_N_DUAL_SMLF-NTJD4001N,FET,A
IRQ_PVDDQ_DEF_VRHOT_LVT3_N R7B1             2        RES_0402-33.2,1%,1/16W,CHIP,G2A
IRQ_PVDDQ_DEF_VRHOT_LVT3_N U7C1             BK17     LBG_CORE_QAT_EXT_D_BGA1-IC,H91A
IRQ_PVDDQ_DEF_VRHOT_LVT3_N U9F4             B3       AST1250_BGA-IC,G85138-002
IRQ_PVDDQ_DEF_VRHOT_LVT3_R_N EU7A5            11       PXM1310B_QFN-IC,H89186-001
IRQ_PVDDQ_DEF_VRHOT_LVT3_R_N R7B1             1        RES_0402-33.2,1%,1/16W,CHIP,G2A
IRQ_PVDDQ_DEF_VRHOT_LVT3_R_N R7B4             2        RES_0402-1.00K,1%,1/16W,CHIP,GA
IRQ_PVDDQ_GHJ_VRHOT_LVT3_N Q7E2             2        FET_N_DUAL_SMLF-NTJD4001N,FET,A
IRQ_PVDDQ_GHJ_VRHOT_LVT3_N R1G8             2        RES_0402-33.2,1%,1/16W,CHIP,G2A
IRQ_PVDDQ_GHJ_VRHOT_LVT3_N U7C1             BG18     LBG_CORE_QAT_EXT_D_BGA1-IC,H91A
IRQ_PVDDQ_GHJ_VRHOT_LVT3_N U9F4             D4       AST1250_BGA-IC,G85138-002
IRQ_PVDDQ_GHJ_VRHOT_LVT3_R_N EU1G2            11       PXM1310B_QFN-IC,H89186-001
IRQ_PVDDQ_GHJ_VRHOT_LVT3_R_N R1G8             1        RES_0402-33.2,1%,1/16W,CHIP,G2A
IRQ_PVDDQ_GHJ_VRHOT_LVT3_R_N R1G11            2        RES_0402-1.00K,1%,1/16W,CHIP,GA
IRQ_PVDDQ_KLM_VRHOT_LVT3_N Q4B1             2        FET_N_DUAL_SMLF-NTJD4001N,FET,A
IRQ_PVDDQ_KLM_VRHOT_LVT3_N R1B4             2        RES_0402-33.2,1%,1/16W,CHIP,G2A
IRQ_PVDDQ_KLM_VRHOT_LVT3_N U7C1             BR13     LBG_CORE_QAT_EXT_D_BGA1-IC,H91A
IRQ_PVDDQ_KLM_VRHOT_LVT3_N U9F4             C3       AST1250_BGA-IC,G85138-002
IRQ_PVDDQ_KLM_VRHOT_LVT3_R_N EU1B1            11       PXM1310B_QFN-IC,H89186-001
IRQ_PVDDQ_KLM_VRHOT_LVT3_R_N R1B1             2        RES_0402-1.00K,1%,1/16W,CHIP,GA
IRQ_PVDDQ_KLM_VRHOT_LVT3_R_N R1B4             1        RES_0402-33.2,1%,1/16W,CHIP,G2A
IRQ_PVNN_PCH_VRHOT_N     EU8A1            11       PXE1110B_QFN-IC,H89187-001
IRQ_PVNN_PCH_VRHOT_N     R8A5             2        RES_0402-1.00K,1%,1/16W,CHIP,GA
IRQ_SML0_ALERT_N         Q8E2             3        FET_N_SOT23LF-2N7002,FET,C7925A
IRQ_SML0_ALERT_N         R8C9             2        RES_0402-4.75K,1%,1/16W,CHIP,GA
IRQ_SML0_ALERT_N         U7C1             BW34     LBG_CORE_QAT_EXT_D_BGA1-IC,H91A
IRQ_SML0_ALERT_N         U9F4             D15      AST1250_BGA-IC,G85138-002
IRQ_SML1_PMBUS_ALERT_BUF_N R8D26            2        RES_0402-4.75K,1%,1/16W,CHIP,GA
IRQ_SML1_PMBUS_ALERT_BUF_N U8D3             2        TTL1G07_A_SOP-74LVC1G07,IC,C88B
IRQ_SML1_PMBUS_ALERT_BUF_N U8D5             4        TTL1G126_A_SOT-74HC1G126,IC,A7B
IRQ_SML1_PMBUS_ALERT_N   C8D3             1        CAP_0402LF-470PF,50V,10%,EMPTYA
IRQ_SML1_PMBUS_ALERT_N   R1D26            2        RES_0402-33.2,1%,1/16W,CHIP,G2A
IRQ_SML1_PMBUS_ALERT_N   R2P8             2        RES_0402-560,5%,1/16W,CHIP,G21A
IRQ_SML1_PMBUS_ALERT_N   U7C1             C13      LBG_CORE_QAT_EXT_D_BGA1-IC,H91A
IRQ_SML1_PMBUS_ALERT_N   U8D5             2        TTL1G126_A_SOT-74HC1G126,IC,A7B
IRQ_SML1_PMBUS_ALERT_N   U9F4             B18      AST1250_BGA-IC,G85138-002
IRQ_SML1_PMBUS_ALERT_R_N EU1D2            13       ADM1278_SM-IC,G99251-001
IRQ_SML1_PMBUS_ALERT_R_N J1F1             A6       CONN76_H22707001_THMT1-CONN,H2A
IRQ_SML1_PMBUS_ALERT_R_N J1F3             5        CONN8_H62179001_PIP-CONN,H6217A
IRQ_SML1_PMBUS_ALERT_R_N R1D26            1        RES_0402-33.2,1%,1/16W,CHIP,G2A
IRQ_SPI_TPM_N_R          J8E1             9        SCONN11_H67026001_SM-CONN,H670A
IRQ_SPI_TPM_N_R          R8E1             1        RES_0402-0.0,5%,1/16W,CHIP,G21A
IRQ_UV_DETECT_N          CR9P1            1        DIODE_SMLF-BAT54WS,IC,C73510-0A
IRQ_UV_DETECT_N          Q9P1             3        FET_N_DUAL_SMLF-2N7002DW,FET,DA
IRQ_UV_DETECT_N          R9P4             2        RES_0402-2.7K,1%,1/16W,CHIP,G2A
IRQ_UV_DETECT_N          U7C1             AU58     LBG_CORE_QAT_EXT_D_BGA1-IC,H91A
IRQ_UV_DETECT_N          U8E1             4        TTL08_QFN15-74LVC08A,IC,D90404B
IRQ_UV_DETECT_N          U9F4             U1       AST1250_BGA-IC,G85138-002
IRQ_VM_INT_N             R1U40            2        RES_0402-33.2,1%,1/16W,CHIP,G2A
IRQ_VM_INT_N             U7C1             AA4      LBG_CORE_QAT_EXT_D_BGA1-IC,H91A
IRQ_VM_INT_R_N           EU9G1            6        ADC128D818_SM-IC,H63642-001
IRQ_VM_INT_R_N           R1U40            1        RES_0402-33.2,1%,1/16W,CHIP,G2A
IRQ_VM_INT_R_N           R9G21            2        RES_0402-4.75K,1%,1/16W,CHIP,GA
ISENSE_P1V05_PCH_STBY_PH1_IMON EU7A2            38       IR354XX_SM-IR35412,IC,H73684-0A
ISENSE_P1V05_PCH_STBY_PH1_IMON EU8A1            26       PXE1110B_QFN-IC,H89187-001
ISENSE_PVCCIN_CPU0_PH1_IMON EU4D4            24       PXE1610B_QFN-IC,H79206-001
ISENSE_PVCCIN_CPU0_PH1_IMON EU4E1            38       IR354XX_SM-IR35411,IC,H73688-0A
ISENSE_PVCCIN_CPU0_PH2_IMON EU4D4            26       PXE1610B_QFN-IC,H79206-001
ISENSE_PVCCIN_CPU0_PH2_IMON EU4D6            38       IR354XX_SM-IR35411,IC,H73688-0A
ISENSE_PVCCIN_CPU0_PH3_IMON EU4D3            38       IR354XX_SM-IR35411,IC,H73688-0A
ISENSE_PVCCIN_CPU0_PH3_IMON EU4D4            28       PXE1610B_QFN-IC,H79206-001
ISENSE_PVCCIN_CPU0_PH4_IMON EU4D1            38       IR354XX_SM-IR35411,IC,H73688-0A
ISENSE_PVCCIN_CPU0_PH4_IMON EU4D4            30       PXE1610B_QFN-IC,H79206-001
ISENSE_PVCCIN_CPU0_PH5_IMON EU4C2            38       IR354XX_SM-IR35411,IC,H73688-0A
ISENSE_PVCCIN_CPU0_PH5_IMON EU4D4            32       PXE1610B_QFN-IC,H79206-001
ISENSE_PVCCIN_CPU1_PH1_IMON EU1C2            24       PXE1610B_QFN-IC,H79206-001
ISENSE_PVCCIN_CPU1_PH1_IMON EU1E2            38       IR354XX_SM-IR35411,IC,H73688-0A
ISENSE_PVCCIN_CPU1_PH2_IMON EU1C2            26       PXE1610B_QFN-IC,H79206-001
ISENSE_PVCCIN_CPU1_PH2_IMON EU1D4            38       IR354XX_SM-IR35411,IC,H73688-0A
ISENSE_PVCCIN_CPU1_PH3_IMON EU1C2            28       PXE1610B_QFN-IC,H79206-001
ISENSE_PVCCIN_CPU1_PH3_IMON EU1D3            38       IR354XX_SM-IR35411,IC,H73688-0A
ISENSE_PVCCIN_CPU1_PH4_IMON EU1C2            30       PXE1610B_QFN-IC,H79206-001
ISENSE_PVCCIN_CPU1_PH4_IMON EU1D1            38       IR354XX_SM-IR35411,IC,H73688-0A
ISENSE_PVCCIN_CPU1_PH5_IMON EU1C2            32       PXE1610B_QFN-IC,H79206-001
ISENSE_PVCCIN_CPU1_PH5_IMON EU1C3            38       IR354XX_SM-IR35411,IC,H73688-0A
ISENSE_PVCCIO_CPU0_PH1_IMON EU3P1            22       PXE1110B_QFN-IC,H89187-001
ISENSE_PVCCIO_CPU0_PH1_IMON EU7C1            38       IR354XX_SM-IR35412,IC,H73684-0A
ISENSE_PVCCIO_CPU1_PH1_IMON EU4D5            22       PXE1110B_QFN-IC,H89187-001
ISENSE_PVCCIO_CPU1_PH1_IMON EU4E2            38       IR354XX_SM-IR35412,IC,H73684-0A
ISENSE_PVDDQ_ABC_PH1_IMON EU7G1            22       PXM1310B_QFN-IC,H89186-001
ISENSE_PVDDQ_ABC_PH1_IMON EU7G2            38       IR354XX_SM-IR35411,IC,H73688-0A
ISENSE_PVDDQ_ABC_PH2_IMON EU7G1            24       PXM1310B_QFN-IC,H89186-001
ISENSE_PVDDQ_ABC_PH2_IMON EU7G3            38       IR354XX_SM-IR35411,IC,H73688-0A
ISENSE_PVDDQ_DEF_PH1_IMON EU7A1            38       IR354XX_SM-IR35411,IC,H73688-0A
ISENSE_PVDDQ_DEF_PH1_IMON EU7A5            22       PXM1310B_QFN-IC,H89186-001
ISENSE_PVDDQ_DEF_PH2_IMON EU7A4            38       IR354XX_SM-IR35411,IC,H73688-0A
ISENSE_PVDDQ_DEF_PH2_IMON EU7A5            24       PXM1310B_QFN-IC,H89186-001
ISENSE_PVDDQ_GHJ_PH1_IMON EU1G1            38       IR354XX_SM-IR35411,IC,H73688-0A
ISENSE_PVDDQ_GHJ_PH1_IMON EU1G2            22       PXM1310B_QFN-IC,H89186-001
ISENSE_PVDDQ_GHJ_PH2_IMON EU1F1            38       IR354XX_SM-IR35411,IC,H73688-0A
ISENSE_PVDDQ_GHJ_PH2_IMON EU1G2            24       PXM1310B_QFN-IC,H89186-001
ISENSE_PVDDQ_KLM_PH1_IMON EU1A2            38       IR354XX_SM-IR35411,IC,H73688-0A
ISENSE_PVDDQ_KLM_PH1_IMON EU1B1            22       PXM1310B_QFN-IC,H89186-001
ISENSE_PVDDQ_KLM_PH2_IMON EU1A1            38       IR354XX_SM-IR35411,IC,H73688-0A
ISENSE_PVDDQ_KLM_PH2_IMON EU1B1            24       PXM1310B_QFN-IC,H89186-001
ISENSE_PVNN_PCH_PH1_IMON EU7A3            38       IR354XX_SM-IR35412,IC,H73684-0A
ISENSE_PVNN_PCH_PH1_IMON EU8A1            22       PXE1110B_QFN-IC,H89187-001
ISENSE_PVSA_CPU0_IMON    EU4C1            38       IR354XX_SM-IR35412,IC,H73684-0A
ISENSE_PVSA_CPU0_IMON    EU4D4            38       PXE1610B_QFN-IC,H79206-001
ISENSE_PVSA_CPU1_IMON    EU1C1            38       IR354XX_SM-IR35412,IC,H73684-0A
ISENSE_PVSA_CPU1_IMON    EU1C2            38       PXE1610B_QFN-IC,H79206-001
ISENSE_TMP421_1_BC       Q9B1             1        PNP_TO92-MPS2907,IC,G73554-001
ISENSE_TMP421_1_BC       Q9B1             3        PNP_TO92-MPS2907,IC,G73554-001
ISENSE_TMP421_1_BC       R9B5             1        RES_0402-49.9,1%,1/16W,CHIP,G2A
ISENSE_TMP421_1_DXN      C1M4             2        CAP_0402LF-47.0PF,50V,5%,EMPTYA
ISENSE_TMP421_1_DXN      R9B5             2        RES_0402-49.9,1%,1/16W,CHIP,G2A
ISENSE_TMP421_1_DXN      U9B4             2        TMP421_TSSOP-IC,G62962-001
ISENSE_TMP421_1_DXP      C1M4             1        CAP_0402LF-47.0PF,50V,5%,EMPTYA
ISENSE_TMP421_1_DXP      R9B4             2        RES_0402-49.9,1%,1/16W,CHIP,G2A
ISENSE_TMP421_1_DXP      U9B4             1        TMP421_TSSOP-IC,G62962-001
ISENSE_TMP421_1_E        Q9B1             2        PNP_TO92-MPS2907,IC,G73554-001
ISENSE_TMP421_1_E        R9B4             1        RES_0402-49.9,1%,1/16W,CHIP,G2A
ISENSE_TMP421_2_BC       Q1E1             1        PNP_TO92-MPS2907,IC,G73554-001
ISENSE_TMP421_2_BC       Q1E1             3        PNP_TO92-MPS2907,IC,G73554-001
ISENSE_TMP421_2_BC       R9R6             1        RES_0402-49.9,1%,1/16W,CHIP,G2A
ISENSE_TMP421_2_DXN      C1E19            2        CAP_0402LF-47.0PF,50V,5%,EMPTYA
ISENSE_TMP421_2_DXN      R9R6             2        RES_0402-49.9,1%,1/16W,CHIP,G2A
ISENSE_TMP421_2_DXN      U1E1             2        TMP421_TSSOP-IC,G62962-001
ISENSE_TMP421_2_DXP      C1E19            1        CAP_0402LF-47.0PF,50V,5%,EMPTYA
ISENSE_TMP421_2_DXP      R9R5             2        RES_0402-49.9,1%,1/16W,CHIP,G2A
ISENSE_TMP421_2_DXP      U1E1             1        TMP421_TSSOP-IC,G62962-001
ISENSE_TMP421_2_E        Q1E1             2        PNP_TO92-MPS2907,IC,G73554-001
ISENSE_TMP421_2_E        R9R5             1        RES_0402-49.9,1%,1/16W,CHIP,G2A
JTAG_BMC_TCK             R8G17            1        RES_0402-0.0,5%,1/16W,CHIP,G21A
JTAG_BMC_TCK             U9F4             F2       AST1250_BGA-IC,G85138-002
JTAG_BMC_TDI             R8G8             1        RES_0402-0.0,5%,1/16W,CHIP,G21A
JTAG_BMC_TDI             U9F4             F1       AST1250_BGA-IC,G85138-002
JTAG_BMC_TDO             R7G17            1        RES_0402-0.0,5%,1/16W,CHIP,G21A
JTAG_BMC_TDO             U9F4             G3       AST1250_BGA-IC,G85138-002
JTAG_BMC_TMS             R8G14            1        RES_0402-0.0,5%,1/16W,CHIP,G21A
JTAG_BMC_TMS             U9F4             G2       AST1250_BGA-IC,G85138-002
JTAG_BMC_TRST_N          R8G10            1        RES_0402-0.0,5%,1/16W,CHIP,G21A
JTAG_BMC_TRST_N          U9F4             E1       AST1250_BGA-IC,G85138-002
JTAG_MCP_CPU0_TDI        R4R6             2        RES_0402-49.9,1%,1/16W,CHIP,G2A
JTAG_MCP_CPU0_TDI        U2M1             1        NC7SB3157_SMLF-IC,C99406-001
JTAG_MCP_CPU0_TDI        U5D1             BY21     SKX_EXT_B_BGA1-IC,TBD
JTAG_MCP_CPU0_TDI_R      C4R2             1        CAP_A_0402V-0.1UF,16V,10%,X7R,A
JTAG_MCP_CPU0_TDI_R      R4R6             1        RES_0402-49.9,1%,1/16W,CHIP,G2A
JTAG_MCP_CPU0_TDI_R      U4R1             4        74CBTLV1G125_SMLF-IC,C88177-00A
JTAG_MCP_CPU0_TDO        U1M2             1        NC7SB3157_SMLF-IC,C99406-001
JTAG_MCP_CPU0_TDO        U1M6             2        74CBTLV1G125_SMLF-IC,C88177-00A
JTAG_MCP_CPU0_TDO        U5D1             CC22     SKX_EXT_B_BGA1-IC,TBD
JTAG_MCP_CPU1_TDI        R6M8             2        RES_0402-49.9,1%,1/16W,CHIP,G2A
JTAG_MCP_CPU1_TDI        U1M6             4        74CBTLV1G125_SMLF-IC,C88177-00A
JTAG_MCP_CPU1_TDI        U2D1             BY21     SKX_EXT_B_BGA1-IC,TBD
JTAG_MCP_CPU1_TDI        U2M1             3        NC7SB3157_SMLF-IC,C99406-001
JTAG_MCP_CPU1_TDI_R      C6M6             1        CAP_A_0402V-0.1UF,16V,10%,X7R,A
JTAG_MCP_CPU1_TDI_R      R6M8             1        RES_0402-49.9,1%,1/16W,CHIP,G2A
JTAG_MCP_CPU1_TDI_R      U6M1             4        74CBTLV1G125_SMLF-IC,C88177-00A
JTAG_MCP_CPU1_TDO        U1M2             3        NC7SB3157_SMLF-IC,C99406-001
JTAG_MCP_CPU1_TDO        U2D1             CC22     SKX_EXT_B_BGA1-IC,TBD
JTAG_MCP_MUX_TDI         J9B4             9        SCONN10_C12536004_SMLF-CONN,C1A
JTAG_MCP_MUX_TDI         R1M20            2        RES_0402-1.00K,1%,1/16W,CHIP,GA
JTAG_MCP_MUX_TDI         U2M1             4        NC7SB3157_SMLF-IC,C99406-001
JTAG_MCP_MUX_TDO         J9B4             3        SCONN10_C12536004_SMLF-CONN,C1A
JTAG_MCP_MUX_TDO         R9B12            2        RES_0402-1.00K,1%,1/16W,CHIP,GA
JTAG_MCP_MUX_TDO         U1M2             4        NC7SB3157_SMLF-IC,C99406-001
JTAG_MCP_TCK             R9B9             1        RES_0402-1.00K,1%,1/16W,CHIP,GA
JTAG_MCP_TCK             R9B10            1        RES_0402-49.9,1%,1/16W,CHIP,G2A
JTAG_MCP_TCK             R9B11            1        RES_0402-0.0,5%,1/16W,CHIP,G21A
JTAG_MCP_TCK             U2D1             CB23     SKX_EXT_B_BGA1-IC,TBD
JTAG_MCP_TCK             U5D1             CB23     SKX_EXT_B_BGA1-IC,TBD
JTAG_MCP_TCK_R           J9B4             1        SCONN10_C12536004_SMLF-CONN,C1A
JTAG_MCP_TCK_R           R9B10            2        RES_0402-49.9,1%,1/16W,CHIP,G2A
JTAG_MCP_TCK_R           R9B11            2        RES_0402-0.0,5%,1/16W,CHIP,G21A
JTAG_MCP_TCK_R           U9A5             2        74CBTLV1G125_SMLF-IC,C88177-00A
JTAG_MCP_TMS             R1M19            2        RES_0402-1.00K,1%,1/16W,CHIP,GA
JTAG_MCP_TMS             R1M22            2        RES_0402-49.9,1%,1/16W,CHIP,G2A
JTAG_MCP_TMS             R9B13            1        RES_0402-0.0,5%,1/16W,CHIP,G21A
JTAG_MCP_TMS             U2D1             CE24     SKX_EXT_B_BGA1-IC,TBD
JTAG_MCP_TMS             U5D1             CE24     SKX_EXT_B_BGA1-IC,TBD
JTAG_MCP_TMS_R           J9B4             5        SCONN10_C12536004_SMLF-CONN,C1A
JTAG_MCP_TMS_R           R9B13            2        RES_0402-0.0,5%,1/16W,CHIP,G21A
JTAG_MCP_TMS_R1          C1M33            1        CAP_A_0402V-0.1UF,16V,10%,X7R,A
JTAG_MCP_TMS_R1          R1M22            1        RES_0402-49.9,1%,1/16W,CHIP,G2A
JTAG_MCP_TMS_R1          U1M5             4        74CBTLV1G125_SMLF-IC,C88177-00A
JTAG_MCP_TRST_N          J9B4             6        SCONN10_C12536004_SMLF-CONN,C1A
JTAG_MCP_TRST_N          R1M21            2        RES_0402-1.00K,1%,1/16W,CHIP,GA
JTAG_MCP_TRST_N          R1M23            1        RES_0402-1.00K,1%,1/16W,EMPTY,A
JTAG_MCP_TRST_N          U2D1             CD23     SKX_EXT_B_BGA1-IC,TBD
JTAG_MCP_TRST_N          U5D1             CD23     SKX_EXT_B_BGA1-IC,TBD
JTAG_PCH_GBE_CLK         R8G15            1        RES_0402-0.0,5%,1/16W,EMPTY,G2A
JTAG_PCH_GBE_CLK         U7C1             BV21     LBG_CORE_QAT_EXT_D_BGA1-IC,H91A
JTAG_PCH_GBE_TDI         R7G19            1        RES_0402-0.0,5%,1/16W,EMPTY,G2A
JTAG_PCH_GBE_TDI         U7C1             BY23     LBG_CORE_QAT_EXT_D_BGA1-IC,H91A
JTAG_PCH_GBE_TDO         R7G16            1        RES_0402-0.0,5%,1/16W,EMPTY,G2A
JTAG_PCH_GBE_TDO         U7C1             CA20     LBG_CORE_QAT_EXT_D_BGA1-IC,H91A
JTAG_PCH_GBE_TMS         R8G12            1        RES_0402-0.0,5%,1/16W,EMPTY,G2A
JTAG_PCH_GBE_TMS         U7C1             CA22     LBG_CORE_QAT_EXT_D_BGA1-IC,H91A
JTAG_PCH_GBE_TRST_N      R8G9             1        RES_0402-0.0,5%,1/16W,EMPTY,G2A
JTAG_PCH_GBE_TRST_N      U7C1             CA24     LBG_CORE_QAT_EXT_D_BGA1-IC,H91A
JTAG_PCH_PLD_TCK         R8G16            1        RES_0402-0.0,5%,1/16W,EMPTY,G2A
JTAG_PCH_PLD_TCK         U7C1             AL18     LBG_CORE_QAT_EXT_D_BGA1-IC,H91A
JTAG_PCH_PLD_TDI         R7G18            1        RES_0402-0.0,5%,1/16W,EMPTY,G2A
JTAG_PCH_PLD_TDI         U7C1             AK17     LBG_CORE_QAT_EXT_D_BGA1-IC,H91A
JTAG_PCH_PLD_TDO         R7G15            1        RES_0402-0.0,5%,1/16W,EMPTY,G2A
JTAG_PCH_PLD_TDO         U7C1             AR20     LBG_CORE_QAT_EXT_D_BGA1-IC,H91A
JTAG_PCH_PLD_TMS         R8G11            1        RES_0402-0.0,5%,1/16W,EMPTY,G2A
JTAG_PCH_PLD_TMS         U7C1             AH9      LBG_CORE_QAT_EXT_D_BGA1-IC,H91A
JTAG_PLD_TCK             R8G18            1        RES_0402-0.0,5%,1/16W,CHIP,G21A
JTAG_PLD_TCK             U8D7             A7       LCMXO2_A_256BGA-IC,H63395-001
JTAG_PLD_TDI             R8G7             1        RES_0402-0.0,5%,1/16W,CHIP,G21A
JTAG_PLD_TDI             U8D7             A6       LCMXO2_A_256BGA-IC,H63395-001
JTAG_PLD_TDO             R7G14            1        RES_0402-0.0,5%,1/16W,CHIP,G21A
JTAG_PLD_TDO             U8D7             C6       LCMXO2_A_256BGA-IC,H63395-001
JTAG_PLD_TMS             R8G13            1        RES_0402-0.0,5%,1/16W,CHIP,G21A
JTAG_PLD_TMS             U8D7             B8       LCMXO2_A_256BGA-IC,H63395-001
JTAG_TCK                 R8G15            2        RES_0402-0.0,5%,1/16W,EMPTY,G2A
JTAG_TCK                 R8G16            2        RES_0402-0.0,5%,1/16W,EMPTY,G2A
JTAG_TCK                 R8G17            2        RES_0402-0.0,5%,1/16W,CHIP,G21A
JTAG_TCK                 R8G18            2        RES_0402-0.0,5%,1/16W,CHIP,G21A
JTAG_TCK                 R8G22            1        RES_0402-0.0,5%,1/16W,CHIP,G21A
JTAG_TCK_R               J7G2             8        CONN8_C77962004_PIP-CONN,C7796A
JTAG_TCK_R               R8G22            2        RES_0402-0.0,5%,1/16W,CHIP,G21A
JTAG_TCK_R               R8G23            1        RES_0402-4.75K,1%,1/16W,CHIP,GA
JTAG_TDI                 R7G18            2        RES_0402-0.0,5%,1/16W,EMPTY,G2A
JTAG_TDI                 R7G19            2        RES_0402-0.0,5%,1/16W,EMPTY,G2A
JTAG_TDI                 R8G7             2        RES_0402-0.0,5%,1/16W,CHIP,G21A
JTAG_TDI                 R8G8             2        RES_0402-0.0,5%,1/16W,CHIP,G21A
JTAG_TDI                 R8G19            1        RES_0402-0.0,5%,1/16W,CHIP,G21A
JTAG_TDI_R               J7G2             3        CONN8_C77962004_PIP-CONN,C7796A
JTAG_TDI_R               R7G23            2        RES_0402-10.0K,1%,1/16W,CHIP,GA
JTAG_TDI_R               R8G19            2        RES_0402-0.0,5%,1/16W,CHIP,G21A
JTAG_TDO                 R7G14            2        RES_0402-0.0,5%,1/16W,CHIP,G21A
JTAG_TDO                 R7G15            2        RES_0402-0.0,5%,1/16W,EMPTY,G2A
JTAG_TDO                 R7G16            2        RES_0402-0.0,5%,1/16W,EMPTY,G2A
JTAG_TDO                 R7G17            2        RES_0402-0.0,5%,1/16W,CHIP,G21A
JTAG_TDO                 R7G21            1        RES_0402-0.0,5%,1/16W,CHIP,G21A
JTAG_TDO_R               J7G2             2        CONN8_C77962004_PIP-CONN,C7796A
JTAG_TDO_R               R7G21            2        RES_0402-0.0,5%,1/16W,CHIP,G21A
JTAG_TDO_R               R7G22            2        RES_0402-10.0K,1%,1/16W,CHIP,GA
JTAG_TMS                 R8G11            2        RES_0402-0.0,5%,1/16W,EMPTY,G2A
JTAG_TMS                 R8G12            2        RES_0402-0.0,5%,1/16W,EMPTY,G2A
JTAG_TMS                 R8G13            2        RES_0402-0.0,5%,1/16W,CHIP,G21A
JTAG_TMS                 R8G14            2        RES_0402-0.0,5%,1/16W,CHIP,G21A
JTAG_TMS                 R8G21            1        RES_0402-0.0,5%,1/16W,CHIP,G21A
JTAG_TMS_R               J7G2             6        CONN8_C77962004_PIP-CONN,C7796A
JTAG_TMS_R               R8G20            2        RES_0402-10.0K,1%,1/16W,CHIP,GA
JTAG_TMS_R               R8G21            2        RES_0402-0.0,5%,1/16W,CHIP,G21A
JTAG_TRST_N              J7G2             4        CONN8_C77962004_PIP-CONN,C7796A
JTAG_TRST_N              R8G9             2        RES_0402-0.0,5%,1/16W,EMPTY,G2A
JTAG_TRST_N              R8G10            2        RES_0402-0.0,5%,1/16W,CHIP,G21A
KR_P0_OCP_RX_C_DN        C8C14            2        CAP_A_0402V-0.1UF,16V,10%,X7R,A
KR_P0_OCP_RX_C_DN        U7C1             BH31     LBG_CORE_QAT_EXT_D_BGA1-IC,H91A
KR_P0_OCP_RX_C_DP        C8C15            2        CAP_A_0402V-0.1UF,16V,10%,X7R,A
KR_P0_OCP_RX_C_DP        U7C1             BF31     LBG_CORE_QAT_EXT_D_BGA1-IC,H91A
KR_P0_OCP_RX_DN          C8C14            1        CAP_A_0402V-0.1UF,16V,10%,X7R,A
KR_P0_OCP_RX_DN          J8E4             53       SCONN64_H87568002_A_SMT-CONN,HA
KR_P0_OCP_RX_DP          C8C15            1        CAP_A_0402V-0.1UF,16V,10%,X7R,A
KR_P0_OCP_RX_DP          J8E4             52       SCONN64_H87568002_A_SMT-CONN,HA
KR_P0_OCP_TX_DN          J8E4             41       SCONN64_H87568002_A_SMT-CONN,HA
KR_P0_OCP_TX_DN          U7C1             BM27     LBG_CORE_QAT_EXT_D_BGA1-IC,H91A
KR_P0_OCP_TX_DP          J8E4             40       SCONN64_H87568002_A_SMT-CONN,HA
KR_P0_OCP_TX_DP          U7C1             BR27     LBG_CORE_QAT_EXT_D_BGA1-IC,H91A
KR_P1_OCP_RX_C_DN        C8C13            2        CAP_A_0402V-0.1UF,16V,10%,X7R,A
KR_P1_OCP_RX_C_DN        U7C1             BG29     LBG_CORE_QAT_EXT_D_BGA1-IC,H91A
KR_P1_OCP_RX_C_DP        C8C12            2        CAP_A_0402V-0.1UF,16V,10%,X7R,A
KR_P1_OCP_RX_C_DP        U7C1             BJ29     LBG_CORE_QAT_EXT_D_BGA1-IC,H91A
KR_P1_OCP_RX_DN          C8C13            1        CAP_A_0402V-0.1UF,16V,10%,X7R,A
KR_P1_OCP_RX_DN          J8E4             59       SCONN64_H87568002_A_SMT-CONN,HA
KR_P1_OCP_RX_DP          C8C12            1        CAP_A_0402V-0.1UF,16V,10%,X7R,A
KR_P1_OCP_RX_DP          J8E4             58       SCONN64_H87568002_A_SMT-CONN,HA
KR_P1_OCP_TX_DN          J8E4             47       SCONN64_H87568002_A_SMT-CONN,HA
KR_P1_OCP_TX_DN          U7C1             BM24     LBG_CORE_QAT_EXT_D_BGA1-IC,H91A
KR_P1_OCP_TX_DP          J8E4             46       SCONN64_H87568002_A_SMT-CONN,HA
KR_P1_OCP_TX_DP          U7C1             BR24     LBG_CORE_QAT_EXT_D_BGA1-IC,H91A
KR_P2_OCP_RX_C_DN        C8C10            2        CAP_A_0402V-0.1UF,16V,10%,X7R,A
KR_P2_OCP_RX_C_DN        U7C1             BJ37     LBG_CORE_QAT_EXT_D_BGA1-IC,H91A
KR_P2_OCP_RX_C_DP        C8C11            2        CAP_A_0402V-0.1UF,16V,10%,X7R,A
KR_P2_OCP_RX_C_DP        U7C1             BG37     LBG_CORE_QAT_EXT_D_BGA1-IC,H91A
KR_P2_OCP_RX_DN          C8C10            1        CAP_A_0402V-0.1UF,16V,10%,X7R,A
KR_P2_OCP_RX_DN          J8E4             18       SCONN64_H87568002_A_SMT-CONN,HA
KR_P2_OCP_RX_DP          C8C11            1        CAP_A_0402V-0.1UF,16V,10%,X7R,A
KR_P2_OCP_RX_DP          J8E4             17       SCONN64_H87568002_A_SMT-CONN,HA
KR_P2_OCP_TX_DN          J8E4             6        SCONN64_H87568002_A_SMT-CONN,HA
KR_P2_OCP_TX_DN          U7C1             BM35     LBG_CORE_QAT_EXT_D_BGA1-IC,H91A
KR_P2_OCP_TX_DP          J8E4             5        SCONN64_H87568002_A_SMT-CONN,HA
KR_P2_OCP_TX_DP          U7C1             BR35     LBG_CORE_QAT_EXT_D_BGA1-IC,H91A
KR_P3_OCP_RX_C_DN        C8C9             2        CAP_A_0402V-0.1UF,16V,10%,X7R,A
KR_P3_OCP_RX_C_DN        U7C1             BF35     LBG_CORE_QAT_EXT_D_BGA1-IC,H91A
KR_P3_OCP_RX_C_DP        C8C8             2        CAP_A_0402V-0.1UF,16V,10%,X7R,A
KR_P3_OCP_RX_C_DP        U7C1             BH35     LBG_CORE_QAT_EXT_D_BGA1-IC,H91A
KR_P3_OCP_RX_DN          C8C9             1        CAP_A_0402V-0.1UF,16V,10%,X7R,A
KR_P3_OCP_RX_DN          J8E4             24       SCONN64_H87568002_A_SMT-CONN,HA
KR_P3_OCP_RX_DP          C8C8             1        CAP_A_0402V-0.1UF,16V,10%,X7R,A
KR_P3_OCP_RX_DP          J8E4             23       SCONN64_H87568002_A_SMT-CONN,HA
KR_P3_OCP_TX_DN          J8E4             12       SCONN64_H87568002_A_SMT-CONN,HA
KR_P3_OCP_TX_DN          U7C1             BR31     LBG_CORE_QAT_EXT_D_BGA1-IC,H91A
KR_P3_OCP_TX_DP          J8E4             11       SCONN64_H87568002_A_SMT-CONN,HA
KR_P3_OCP_TX_DP          U7C1             BM31     LBG_CORE_QAT_EXT_D_BGA1-IC,H91A
LED_GBE_P0_0             J8E4             43       SCONN64_H87568002_A_SMT-CONN,HA
LED_GBE_P0_0             U7C1             BL1      LBG_CORE_QAT_EXT_D_BGA1-IC,H91A
LED_GBE_P0_1             J8E4             44       SCONN64_H87568002_A_SMT-CONN,HA
LED_GBE_P0_1             U7C1             BK4      LBG_CORE_QAT_EXT_D_BGA1-IC,H91A
LED_GBE_P1_0             J8E4             8        SCONN64_H87568002_A_SMT-CONN,HA
LED_GBE_P1_0             U7C1             BP4      LBG_CORE_QAT_EXT_D_BGA1-IC,H91A
LED_GBE_P1_1             J8E4             9        SCONN64_H87568002_A_SMT-CONN,HA
LED_GBE_P1_1             U7C1             BK2      LBG_CORE_QAT_EXT_D_BGA1-IC,H91A
LED_GBE_P2_0             J8E4             14       SCONN64_H87568002_A_SMT-CONN,HA
LED_GBE_P2_0             U7C1             BL3      LBG_CORE_QAT_EXT_D_BGA1-IC,H91A
LED_GBE_P2_1             J8E4             15       SCONN64_H87568002_A_SMT-CONN,HA
LED_GBE_P2_1             U7C1             BU6      LBG_CORE_QAT_EXT_D_BGA1-IC,H91A
LED_GBE_P3_0             J8E4             55       SCONN64_H87568002_A_SMT-CONN,HA
LED_GBE_P3_0             U7C1             CA13     LBG_CORE_QAT_EXT_D_BGA1-IC,H91A
LED_GBE_P3_1             J8E4             56       SCONN64_H87568002_A_SMT-CONN,HA
LED_GBE_P3_1             U7C1             BM2      LBG_CORE_QAT_EXT_D_BGA1-IC,H91A
LED_HFI0_CPU0_N          J8B1             5        SCONN24_H46321001_SM-SCONN,H46A
LED_HFI0_CPU0_N          R8B5             2        RES_0402-4.75K,1%,1/16W,CHIP,GA
LED_HFI0_CPU0_N          U5D1             BK21     SKX_EXT_B_BGA1-IC,TBD
LED_HFI1_CPU0_N          J8B1             13       SCONN24_H46321001_SM-SCONN,H46A
LED_HFI1_CPU0_N          R8B18            2        RES_0402-4.75K,1%,1/16W,CHIP,GA
LED_HFI1_CPU0_N          U5D1             BM23     SKX_EXT_B_BGA1-IC,TBD
LED_LAN_0_N              C9G3             1        CAP_0402LF-470PF,50V,10%,X7R,AA
LED_LAN_0_N              EU9E1            31       SPRINGVILLE_SM1-IC,G47144-004
LED_LAN_0_N              R9G3             2        RES_0402-150.0,1%,1/16W,CHIP,GA
LED_LAN_0_R_N            JA9G1            L1       CONN17_H71061002_PIP1-CONN,H71A
LED_LAN_0_R_N            R9G3             1        RES_0402-150.0,1%,1/16W,CHIP,GA
LED_LAN_1_N              C9F22            1        CAP_0402LF-470PF,50V,10%,X7R,AA
LED_LAN_1_N              EU9E1            30       SPRINGVILLE_SM1-IC,G47144-004
LED_LAN_1_N              R9G1             1        RES_0402-150.0,1%,1/16W,CHIP,GA
LED_LAN_1_R_N            JA9G1            L5       CONN17_H71061002_PIP1-CONN,H71A
LED_LAN_1_R_N            R9G1             2        RES_0402-150.0,1%,1/16W,CHIP,GA
LED_LAN_2_N              C9G1             1        CAP_0402LF-470PF,50V,10%,X7R,AA
LED_LAN_2_N              EU9E1            33       SPRINGVILLE_SM1-IC,G47144-004
LED_LAN_2_N              R9G2             2        RES_0402-150.0,1%,1/16W,CHIP,GA
LED_LAN_2_R_N            JA9G1            L3       CONN17_H71061002_PIP1-CONN,H71A
LED_LAN_2_R_N            R9G2             1        RES_0402-150.0,1%,1/16W,CHIP,GA
LED_P5V_STBY             DS9A6            1        LED_A1LF-GREEN,IC,C97278-010
LED_P5V_STBY             R1L37            2        RES_0402-301.0,1%,1/16W,CHIP,GA
LED_PCH_SATA_HDD_N       R1M10            1        RES_0402-0.0,5%,1/16W,CHIP,G21A
LED_PCH_SATA_HDD_N       U7C1             AV56     LBG_CORE_QAT_EXT_D_BGA1-IC,H91A
LED_PCH_SSATA_HDD_N      R1M13            1        RES_0402-0.0,5%,1/16W,CHIP,G21A
LED_PCH_SSATA_HDD_N      U7C1             AL11     LBG_CORE_QAT_EXT_D_BGA1-IC,H91A
LED_POSTCODE_0           R1L32            1        RES_0402-10.0,1%,1/16W,CHIP,G2A
LED_POSTCODE_0           U7C1             AV3      LBG_CORE_QAT_EXT_D_BGA1-IC,H91A
LED_POSTCODE_0           U9F4             A8       AST1250_BGA-IC,G85138-002
LED_POSTCODE_0_R         J9A2             1        CONN14_H54902001_PIP-CONN,H549A
LED_POSTCODE_0_R         R1L32            2        RES_0402-10.0,1%,1/16W,CHIP,G2A
LED_POSTCODE_1           R1L30            1        RES_0402-10.0,1%,1/16W,CHIP,G2A
LED_POSTCODE_1           U7C1             AR1      LBG_CORE_QAT_EXT_D_BGA1-IC,H91A
LED_POSTCODE_1           U9F4             C7       AST1250_BGA-IC,G85138-002
LED_POSTCODE_1_R         J9A2             2        CONN14_H54902001_PIP-CONN,H549A
LED_POSTCODE_1_R         R1L30            2        RES_0402-10.0,1%,1/16W,CHIP,G2A
LED_POSTCODE_2           R1L25            1        RES_0402-10.0,1%,1/16W,CHIP,G2A
LED_POSTCODE_2           U7C1             AT2      LBG_CORE_QAT_EXT_D_BGA1-IC,H91A
LED_POSTCODE_2           U9F4             B7       AST1250_BGA-IC,G85138-002
LED_POSTCODE_2_R         J9A2             3        CONN14_H54902001_PIP-CONN,H549A
LED_POSTCODE_2_R         R1L25            2        RES_0402-10.0,1%,1/16W,CHIP,G2A
LED_POSTCODE_3           R1L24            1        RES_0402-10.0,1%,1/16W,CHIP,G2A
LED_POSTCODE_3           U7C1             AY3      LBG_CORE_QAT_EXT_D_BGA1-IC,H91A
LED_POSTCODE_3           U9F4             A7       AST1250_BGA-IC,G85138-002
LED_POSTCODE_3_R         J9A2             4        CONN14_H54902001_PIP-CONN,H549A
LED_POSTCODE_3_R         R1L24            2        RES_0402-10.0,1%,1/16W,CHIP,G2A
LED_POSTCODE_4           R1L20            1        RES_0402-10.0,1%,1/16W,CHIP,G2A
LED_POSTCODE_4           U7C1             AW2      LBG_CORE_QAT_EXT_D_BGA1-IC,H91A
LED_POSTCODE_4           U9F4             D7       AST1250_BGA-IC,G85138-002
LED_POSTCODE_4_R         J9A2             5        CONN14_H54902001_PIP-CONN,H549A
LED_POSTCODE_4_R         R1L20            2        RES_0402-10.0,1%,1/16W,CHIP,G2A
LED_POSTCODE_5           R1L18            1        RES_0402-10.0,1%,1/16W,CHIP,G2A
LED_POSTCODE_5           U7C1             AV1      LBG_CORE_QAT_EXT_D_BGA1-IC,H91A
LED_POSTCODE_5           U9F4             B6       AST1250_BGA-IC,G85138-002
LED_POSTCODE_5_R         J9A2             6        CONN14_H54902001_PIP-CONN,H549A
LED_POSTCODE_5_R         R1L18            2        RES_0402-10.0,1%,1/16W,CHIP,G2A
LED_POSTCODE_6           R1L14            1        RES_0402-10.0,1%,1/16W,CHIP,G2A
LED_POSTCODE_6           U7C1             AR3      LBG_CORE_QAT_EXT_D_BGA1-IC,H91A
LED_POSTCODE_6           U9F4             A6       AST1250_BGA-IC,G85138-002
LED_POSTCODE_6_R         J9A2             7        CONN14_H54902001_PIP-CONN,H549A
LED_POSTCODE_6_R         R1L14            2        RES_0402-10.0,1%,1/16W,CHIP,G2A
LED_POSTCODE_7           R1L11            1        RES_0402-10.0,1%,1/16W,CHIP,G2A
LED_POSTCODE_7           U7C1             BE2      LBG_CORE_QAT_EXT_D_BGA1-IC,H91A
LED_POSTCODE_7           U9F4             E7       AST1250_BGA-IC,G85138-002
LED_POSTCODE_7_R         J9A2             8        CONN14_H54902001_PIP-CONN,H549A
LED_POSTCODE_7_R         R1L11            2        RES_0402-10.0,1%,1/16W,CHIP,G2A
LED_SAS_ACT_R_N          R1M12            2        RES_0402-10.0K,1%,1/16W,CHIP,GA
LED_SAS_ACT_R_N          R1M13            2        RES_0402-0.0,5%,1/16W,CHIP,G21A
LED_SAS_ACT_R_N          U1M1             2        TTL1G08_SOTLF-NC7SZ08,IC,D1032C
LED_SATA_ACT_R_N         R1M10            2        RES_0402-0.0,5%,1/16W,CHIP,G21A
LED_SATA_ACT_R_N         R1M11            2        RES_0402-10.0K,1%,1/16W,CHIP,GA
LED_SATA_ACT_R_N         U1M1             1        TTL1G08_SOTLF-NC7SZ08,IC,D1032C
LPC_LAD0_IO0             R3N26            1        RES_0402-33.2,1%,1/16W,CHIP,G2A
LPC_LAD0_IO0             U7C1             Y3       LBG_CORE_QAT_EXT_D_BGA1-IC,H91A
LPC_LAD0_IO0_R           R3N26            2        RES_0402-33.2,1%,1/16W,CHIP,G2A
LPC_LAD0_IO0_R           U9F4             B21      AST1250_BGA-IC,G85138-002
LPC_LAD1_IO1             R3N28            1        RES_0402-33.2,1%,1/16W,CHIP,G2A
LPC_LAD1_IO1             U7C1             N1       LBG_CORE_QAT_EXT_D_BGA1-IC,H91A
LPC_LAD1_IO1_R           R3N28            2        RES_0402-33.2,1%,1/16W,CHIP,G2A
LPC_LAD1_IO1_R           U9F4             A22      AST1250_BGA-IC,G85138-002
LPC_LAD2_IO2             R3N24            1        RES_0402-33.2,1%,1/16W,CHIP,G2A
LPC_LAD2_IO2             U7C1             W2       LBG_CORE_QAT_EXT_D_BGA1-IC,H91A
LPC_LAD2_IO2_R           R3N24            2        RES_0402-33.2,1%,1/16W,CHIP,G2A
LPC_LAD2_IO2_R           U9F4             F19      AST1250_BGA-IC,G85138-002
LPC_LAD3_IO3             R3N25            1        RES_0402-33.2,1%,1/16W,CHIP,G2A
LPC_LAD3_IO3             U7C1             Y1       LBG_CORE_QAT_EXT_D_BGA1-IC,H91A
LPC_LAD3_IO3_R           R3N25            2        RES_0402-33.2,1%,1/16W,CHIP,G2A
LPC_LAD3_IO3_R           U9F4             C19      AST1250_BGA-IC,G85138-002
LPC_LFRAME_N_CS0_N       R3N27            1        RES_0402-33.2,1%,1/16W,CHIP,G2A
LPC_LFRAME_N_CS0_N       U7C1             P4       LBG_CORE_QAT_EXT_D_BGA1-IC,H91A
LPC_LFRAME_N_CS0_R_N     R3N27            2        RES_0402-33.2,1%,1/16W,CHIP,G2A
LPC_LFRAME_N_CS0_R_N     U9F4             A21      AST1250_BGA-IC,G85138-002
M_ABC_RST_N              J4G1             58       SCONN288_H44441004_PIP-SCONN,HA
M_ABC_RST_N              J4G2             58       SCONN288_H44441004_PIP-SCONN,HA
M_ABC_RST_N              J4G3             58       SCONN288_H44441004_PIP-SCONN,HA
M_ABC_RST_N              J6T1             58       SCONN288_H44441003_PIP-SCONN,HA
M_ABC_RST_N              J6U1             58       SCONN288_H44441003_PIP-SCONN,HA
M_ABC_RST_N              J6U2             58       SCONN288_H44441003_PIP-SCONN,HA
M_ABC_RST_N              U5D1             U64      SKX_EXT_B_BGA1-IC,TBD
M_A_ACT_N                J4G1             62       SCONN288_H44441004_PIP-SCONN,HA
M_A_ACT_N                J6T1             62       SCONN288_H44441003_PIP-SCONN,HA
M_A_ACT_N                U5D1             J60      SKX_EXT_B_BGA1-IC,TBD
M_A_ALERT_N              J4G1             208      SCONN288_H44441004_PIP-SCONN,HA
M_A_ALERT_N              J6T1             208      SCONN288_H44441003_PIP-SCONN,HA
M_A_ALERT_N              U5D1             B61      SKX_EXT_B_BGA1-IC,TBD
M_A_BA<0>                J4G1             81       SCONN288_H44441004_PIP-SCONN,HA
M_A_BA<0>                J6T1             81       SCONN288_H44441003_PIP-SCONN,HA
M_A_BA<0>                U5D1             C52      SKX_EXT_B_BGA1-IC,TBD
M_A_BA<1>                J4G1             224      SCONN288_H44441004_PIP-SCONN,HA
M_A_BA<1>                J6T1             224      SCONN288_H44441003_PIP-SCONN,HA
M_A_BA<1>                U5D1             G54      SKX_EXT_B_BGA1-IC,TBD
M_A_BG<0>                J4G1             63       SCONN288_H44441004_PIP-SCONN,HA
M_A_BG<0>                J6T1             63       SCONN288_H44441003_PIP-SCONN,HA
M_A_BG<0>                U5D1             D61      SKX_EXT_B_BGA1-IC,TBD
M_A_BG<1>                J4G1             207      SCONN288_H44441004_PIP-SCONN,HA
M_A_BG<1>                J6T1             207      SCONN288_H44441003_PIP-SCONN,HA
M_A_BG<1>                U5D1             F63      SKX_EXT_B_BGA1-IC,TBD
M_A_C<2>                 J4G1             235      SCONN288_H44441004_PIP-SCONN,HA
M_A_C<2>                 J6T1             235      SCONN288_H44441003_PIP-SCONN,HA
M_A_C<2>                 U5D1             G46      SKX_EXT_B_BGA1-IC,TBD
M_A_CKE<0>               J4G1             60       SCONN288_H44441004_PIP-SCONN,HA
M_A_CKE<0>               U5D1             C62      SKX_EXT_B_BGA1-IC,TBD
M_A_CKE<1>               J4G1             203      SCONN288_H44441004_PIP-SCONN,HA
M_A_CKE<1>               U5D1             C64      SKX_EXT_B_BGA1-IC,TBD
M_A_CKE<2>               J6T1             60       SCONN288_H44441003_PIP-SCONN,HA
M_A_CKE<2>               U5D1             B63      SKX_EXT_B_BGA1-IC,TBD
M_A_CKE<3>               J6T1             203      SCONN288_H44441003_PIP-SCONN,HA
M_A_CKE<3>               U5D1             D63      SKX_EXT_B_BGA1-IC,TBD
M_A_CLK_DN<0>            J4G1             75       SCONN288_H44441004_PIP-SCONN,HA
M_A_CLK_DN<0>            U5D1             F55      SKX_EXT_B_BGA1-IC,TBD
M_A_CLK_DN<1>            J4G1             219      SCONN288_H44441004_PIP-SCONN,HA
M_A_CLK_DN<1>            U5D1             C54      SKX_EXT_B_BGA1-IC,TBD
M_A_CLK_DN<2>            J6T1             75       SCONN288_H44441003_PIP-SCONN,HA
M_A_CLK_DN<2>            U5D1             J56      SKX_EXT_B_BGA1-IC,TBD
M_A_CLK_DN<3>            J6T1             219      SCONN288_H44441003_PIP-SCONN,HA
M_A_CLK_DN<3>            U5D1             C56      SKX_EXT_B_BGA1-IC,TBD
M_A_CLK_DP<0>            J4G1             74       SCONN288_H44441004_PIP-SCONN,HA
M_A_CLK_DP<0>            U5D1             D55      SKX_EXT_B_BGA1-IC,TBD
M_A_CLK_DP<1>            J4G1             218      SCONN288_H44441004_PIP-SCONN,HA
M_A_CLK_DP<1>            U5D1             B55      SKX_EXT_B_BGA1-IC,TBD
M_A_CLK_DP<2>            J6T1             74       SCONN288_H44441003_PIP-SCONN,HA
M_A_CLK_DP<2>            U5D1             G56      SKX_EXT_B_BGA1-IC,TBD
M_A_CLK_DP<3>            J6T1             218      SCONN288_H44441003_PIP-SCONN,HA
M_A_CLK_DP<3>            U5D1             B57      SKX_EXT_B_BGA1-IC,TBD
M_A_CPU_VREF             C4F9             1        CAP_A_0402V-0.01UF,25V,10%,X7RA
M_A_CPU_VREF             R4F3             1        RES_0402-2,1.0%,1/16W,CHIP,G21A
M_A_CPU_VREF             U5D1             AJ64     SKX_EXT_B_BGA1-IC,TBD
M_A_CS_N<0>              J4G1             84       SCONN288_H44441004_PIP-SCONN,HA
M_A_CS_N<0>              U5D1             G52      SKX_EXT_B_BGA1-IC,TBD
M_A_CS_N<1>              J4G1             89       SCONN288_H44441004_PIP-SCONN,HA
M_A_CS_N<1>              U5D1             F49      SKX_EXT_B_BGA1-IC,TBD
M_A_CS_N<2>              J4G1             93       SCONN288_H44441004_PIP-SCONN,HA
M_A_CS_N<2>              U5D1             D47      SKX_EXT_B_BGA1-IC,TBD
M_A_CS_N<3>              J4G1             237      SCONN288_H44441004_PIP-SCONN,HA
M_A_CS_N<3>              U5D1             F47      SKX_EXT_B_BGA1-IC,TBD
M_A_CS_N<4>              J6T1             84       SCONN288_H44441003_PIP-SCONN,HA
M_A_CS_N<4>              U5D1             B51      SKX_EXT_B_BGA1-IC,TBD
M_A_CS_N<5>              J6T1             89       SCONN288_H44441003_PIP-SCONN,HA
M_A_CS_N<5>              U5D1             D49      SKX_EXT_B_BGA1-IC,TBD
M_A_CS_N<6>              J6T1             93       SCONN288_H44441003_PIP-SCONN,HA
M_A_CS_N<6>              U5D1             F45      SKX_EXT_B_BGA1-IC,TBD
M_A_CS_N<7>              J6T1             237      SCONN288_H44441003_PIP-SCONN,HA
M_A_CS_N<7>              U5D1             K45      SKX_EXT_B_BGA1-IC,TBD
M_A_DQ<0>                J4G1             150      SCONN288_H44441004_PIP-SCONN,HA
M_A_DQ<0>                J6T1             5        SCONN288_H44441003_PIP-SCONN,HA
M_A_DQ<0>                U5D1             AN86     SKX_EXT_B_BGA1-IC,TBD
M_A_DQ<1>                J4G1             5        SCONN288_H44441004_PIP-SCONN,HA
M_A_DQ<1>                J6T1             150      SCONN288_H44441003_PIP-SCONN,HA
M_A_DQ<1>                U5D1             AN84     SKX_EXT_B_BGA1-IC,TBD
M_A_DQ<2>                J4G1             157      SCONN288_H44441004_PIP-SCONN,HA
M_A_DQ<2>                J6T1             12       SCONN288_H44441003_PIP-SCONN,HA
M_A_DQ<2>                U5D1             AE86     SKX_EXT_B_BGA1-IC,TBD
M_A_DQ<3>                J4G1             12       SCONN288_H44441004_PIP-SCONN,HA
M_A_DQ<3>                J6T1             157      SCONN288_H44441003_PIP-SCONN,HA
M_A_DQ<3>                U5D1             AE84     SKX_EXT_B_BGA1-IC,TBD
M_A_DQ<4>                J4G1             148      SCONN288_H44441004_PIP-SCONN,HA
M_A_DQ<4>                J6T1             3        SCONN288_H44441003_PIP-SCONN,HA
M_A_DQ<4>                U5D1             AR86     SKX_EXT_B_BGA1-IC,TBD
M_A_DQ<5>                J4G1             3        SCONN288_H44441004_PIP-SCONN,HA
M_A_DQ<5>                J6T1             148      SCONN288_H44441003_PIP-SCONN,HA
M_A_DQ<5>                U5D1             AR84     SKX_EXT_B_BGA1-IC,TBD
M_A_DQ<6>                J4G1             155      SCONN288_H44441004_PIP-SCONN,HA
M_A_DQ<6>                J6T1             10       SCONN288_H44441003_PIP-SCONN,HA
M_A_DQ<6>                U5D1             AG86     SKX_EXT_B_BGA1-IC,TBD
M_A_DQ<7>                J4G1             10       SCONN288_H44441004_PIP-SCONN,HA
M_A_DQ<7>                J6T1             155      SCONN288_H44441003_PIP-SCONN,HA
M_A_DQ<7>                U5D1             AG84     SKX_EXT_B_BGA1-IC,TBD
M_A_DQ<8>                J4G1             161      SCONN288_H44441004_PIP-SCONN,HA
M_A_DQ<8>                J6T1             16       SCONN288_H44441003_PIP-SCONN,HA
M_A_DQ<8>                U5D1             W86      SKX_EXT_B_BGA1-IC,TBD
M_A_DQ<9>                J4G1             16       SCONN288_H44441004_PIP-SCONN,HA
M_A_DQ<9>                J6T1             161      SCONN288_H44441003_PIP-SCONN,HA
M_A_DQ<9>                U5D1             W84      SKX_EXT_B_BGA1-IC,TBD
M_A_DQ<10>               J4G1             168      SCONN288_H44441004_PIP-SCONN,HA
M_A_DQ<10>               J6T1             23       SCONN288_H44441003_PIP-SCONN,HA
M_A_DQ<10>               U5D1             L86      SKX_EXT_B_BGA1-IC,TBD
M_A_DQ<11>               J4G1             23       SCONN288_H44441004_PIP-SCONN,HA
M_A_DQ<11>               J6T1             168      SCONN288_H44441003_PIP-SCONN,HA
M_A_DQ<11>               U5D1             L84      SKX_EXT_B_BGA1-IC,TBD
M_A_DQ<12>               J4G1             159      SCONN288_H44441004_PIP-SCONN,HA
M_A_DQ<12>               J6T1             14       SCONN288_H44441003_PIP-SCONN,HA
M_A_DQ<12>               U5D1             AA86     SKX_EXT_B_BGA1-IC,TBD
M_A_DQ<13>               J4G1             14       SCONN288_H44441004_PIP-SCONN,HA
M_A_DQ<13>               J6T1             159      SCONN288_H44441003_PIP-SCONN,HA
M_A_DQ<13>               U5D1             AA84     SKX_EXT_B_BGA1-IC,TBD
M_A_DQ<14>               J4G1             166      SCONN288_H44441004_PIP-SCONN,HA
M_A_DQ<14>               J6T1             21       SCONN288_H44441003_PIP-SCONN,HA
M_A_DQ<14>               U5D1             N86      SKX_EXT_B_BGA1-IC,TBD
M_A_DQ<15>               J4G1             21       SCONN288_H44441004_PIP-SCONN,HA
M_A_DQ<15>               J6T1             166      SCONN288_H44441003_PIP-SCONN,HA
M_A_DQ<15>               U5D1             N84      SKX_EXT_B_BGA1-IC,TBD
M_A_DQ<16>               J4G1             172      SCONN288_H44441004_PIP-SCONN,HA
M_A_DQ<16>               J6T1             27       SCONN288_H44441003_PIP-SCONN,HA
M_A_DQ<16>               U5D1             V81      SKX_EXT_B_BGA1-IC,TBD
M_A_DQ<17>               J4G1             27       SCONN288_H44441004_PIP-SCONN,HA
M_A_DQ<17>               J6T1             172      SCONN288_H44441003_PIP-SCONN,HA
M_A_DQ<17>               U5D1             T79      SKX_EXT_B_BGA1-IC,TBD
M_A_DQ<18>               J4G1             179      SCONN288_H44441004_PIP-SCONN,HA
M_A_DQ<18>               J6T1             34       SCONN288_H44441003_PIP-SCONN,HA
M_A_DQ<18>               U5D1             N82      SKX_EXT_B_BGA1-IC,TBD
M_A_DQ<19>               J4G1             34       SCONN288_H44441004_PIP-SCONN,HA
M_A_DQ<19>               J6T1             179      SCONN288_H44441003_PIP-SCONN,HA
M_A_DQ<19>               U5D1             M81      SKX_EXT_B_BGA1-IC,TBD
M_A_DQ<20>               J4G1             170      SCONN288_H44441004_PIP-SCONN,HA
M_A_DQ<20>               J6T1             25       SCONN288_H44441003_PIP-SCONN,HA
M_A_DQ<20>               U5D1             W80      SKX_EXT_B_BGA1-IC,TBD
M_A_DQ<21>               J4G1             25       SCONN288_H44441004_PIP-SCONN,HA
M_A_DQ<21>               J6T1             170      SCONN288_H44441003_PIP-SCONN,HA
M_A_DQ<21>               U5D1             V79      SKX_EXT_B_BGA1-IC,TBD
M_A_DQ<22>               J4G1             177      SCONN288_H44441004_PIP-SCONN,HA
M_A_DQ<22>               J6T1             32       SCONN288_H44441003_PIP-SCONN,HA
M_A_DQ<22>               U5D1             R82      SKX_EXT_B_BGA1-IC,TBD
M_A_DQ<23>               J4G1             32       SCONN288_H44441004_PIP-SCONN,HA
M_A_DQ<23>               J6T1             177      SCONN288_H44441003_PIP-SCONN,HA
M_A_DQ<23>               U5D1             N80      SKX_EXT_B_BGA1-IC,TBD
M_A_DQ<24>               J4G1             183      SCONN288_H44441004_PIP-SCONN,HA
M_A_DQ<24>               J6T1             38       SCONN288_H44441003_PIP-SCONN,HA
M_A_DQ<24>               U5D1             L76      SKX_EXT_B_BGA1-IC,TBD
M_A_DQ<25>               J4G1             38       SCONN288_H44441004_PIP-SCONN,HA
M_A_DQ<25>               J6T1             183      SCONN288_H44441003_PIP-SCONN,HA
M_A_DQ<25>               U5D1             R76      SKX_EXT_B_BGA1-IC,TBD
M_A_DQ<26>               J4G1             190      SCONN288_H44441004_PIP-SCONN,HA
M_A_DQ<26>               J6T1             45       SCONN288_H44441003_PIP-SCONN,HA
M_A_DQ<26>               U5D1             M73      SKX_EXT_B_BGA1-IC,TBD
M_A_DQ<27>               J4G1             45       SCONN288_H44441004_PIP-SCONN,HA
M_A_DQ<27>               J6T1             190      SCONN288_H44441003_PIP-SCONN,HA
M_A_DQ<27>               U5D1             P73      SKX_EXT_B_BGA1-IC,TBD
M_A_DQ<28>               J4G1             181      SCONN288_H44441004_PIP-SCONN,HA
M_A_DQ<28>               J6T1             36       SCONN288_H44441003_PIP-SCONN,HA
M_A_DQ<28>               U5D1             M77      SKX_EXT_B_BGA1-IC,TBD
M_A_DQ<29>               J4G1             36       SCONN288_H44441004_PIP-SCONN,HA
M_A_DQ<29>               J6T1             181      SCONN288_H44441003_PIP-SCONN,HA
M_A_DQ<29>               U5D1             P77      SKX_EXT_B_BGA1-IC,TBD
M_A_DQ<30>               J4G1             188      SCONN288_H44441004_PIP-SCONN,HA
M_A_DQ<30>               J6T1             43       SCONN288_H44441003_PIP-SCONN,HA
M_A_DQ<30>               U5D1             L74      SKX_EXT_B_BGA1-IC,TBD
M_A_DQ<31>               J4G1             43       SCONN288_H44441004_PIP-SCONN,HA
M_A_DQ<31>               J6T1             188      SCONN288_H44441003_PIP-SCONN,HA
M_A_DQ<31>               U5D1             R74      SKX_EXT_B_BGA1-IC,TBD
M_A_DQ<32>               J4G1             242      SCONN288_H44441004_PIP-SCONN,HA
M_A_DQ<32>               J6T1             97       SCONN288_H44441003_PIP-SCONN,HA
M_A_DQ<32>               U5D1             C42      SKX_EXT_B_BGA1-IC,TBD
M_A_DQ<33>               J4G1             97       SCONN288_H44441004_PIP-SCONN,HA
M_A_DQ<33>               J6T1             242      SCONN288_H44441003_PIP-SCONN,HA
M_A_DQ<33>               U5D1             B41      SKX_EXT_B_BGA1-IC,TBD
M_A_DQ<34>               J4G1             249      SCONN288_H44441004_PIP-SCONN,HA
M_A_DQ<34>               J6T1             104      SCONN288_H44441003_PIP-SCONN,HA
M_A_DQ<34>               U5D1             C38      SKX_EXT_B_BGA1-IC,TBD
M_A_DQ<35>               J4G1             104      SCONN288_H44441004_PIP-SCONN,HA
M_A_DQ<35>               J6T1             249      SCONN288_H44441003_PIP-SCONN,HA
M_A_DQ<35>               U5D1             E38      SKX_EXT_B_BGA1-IC,TBD
M_A_DQ<36>               J4G1             240      SCONN288_H44441004_PIP-SCONN,HA
M_A_DQ<36>               J6T1             95       SCONN288_H44441003_PIP-SCONN,HA
M_A_DQ<36>               U5D1             E42      SKX_EXT_B_BGA1-IC,TBD
M_A_DQ<37>               J4G1             95       SCONN288_H44441004_PIP-SCONN,HA
M_A_DQ<37>               J6T1             240      SCONN288_H44441003_PIP-SCONN,HA
M_A_DQ<37>               U5D1             F41      SKX_EXT_B_BGA1-IC,TBD
M_A_DQ<38>               J4G1             247      SCONN288_H44441004_PIP-SCONN,HA
M_A_DQ<38>               J6T1             102      SCONN288_H44441003_PIP-SCONN,HA
M_A_DQ<38>               U5D1             B39      SKX_EXT_B_BGA1-IC,TBD
M_A_DQ<39>               J4G1             102      SCONN288_H44441004_PIP-SCONN,HA
M_A_DQ<39>               J6T1             247      SCONN288_H44441003_PIP-SCONN,HA
M_A_DQ<39>               U5D1             F39      SKX_EXT_B_BGA1-IC,TBD
M_A_DQ<40>               J4G1             253      SCONN288_H44441004_PIP-SCONN,HA
M_A_DQ<40>               J6T1             108      SCONN288_H44441003_PIP-SCONN,HA
M_A_DQ<40>               U5D1             K37      SKX_EXT_B_BGA1-IC,TBD
M_A_DQ<41>               J4G1             108      SCONN288_H44441004_PIP-SCONN,HA
M_A_DQ<41>               J6T1             253      SCONN288_H44441003_PIP-SCONN,HA
M_A_DQ<41>               U5D1             P37      SKX_EXT_B_BGA1-IC,TBD
M_A_DQ<42>               J4G1             260      SCONN288_H44441004_PIP-SCONN,HA
M_A_DQ<42>               J6T1             115      SCONN288_H44441003_PIP-SCONN,HA
M_A_DQ<42>               U5D1             L34      SKX_EXT_B_BGA1-IC,TBD
M_A_DQ<43>               J4G1             115      SCONN288_H44441004_PIP-SCONN,HA
M_A_DQ<43>               J6T1             260      SCONN288_H44441003_PIP-SCONN,HA
M_A_DQ<43>               U5D1             N34      SKX_EXT_B_BGA1-IC,TBD
M_A_DQ<44>               J4G1             251      SCONN288_H44441004_PIP-SCONN,HA
M_A_DQ<44>               J6T1             106      SCONN288_H44441003_PIP-SCONN,HA
M_A_DQ<44>               U5D1             L38      SKX_EXT_B_BGA1-IC,TBD
M_A_DQ<45>               J4G1             106      SCONN288_H44441004_PIP-SCONN,HA
M_A_DQ<45>               J6T1             251      SCONN288_H44441003_PIP-SCONN,HA
M_A_DQ<45>               U5D1             N38      SKX_EXT_B_BGA1-IC,TBD
M_A_DQ<46>               J4G1             258      SCONN288_H44441004_PIP-SCONN,HA
M_A_DQ<46>               J6T1             113      SCONN288_H44441003_PIP-SCONN,HA
M_A_DQ<46>               U5D1             K35      SKX_EXT_B_BGA1-IC,TBD
M_A_DQ<47>               J4G1             113      SCONN288_H44441004_PIP-SCONN,HA
M_A_DQ<47>               J6T1             258      SCONN288_H44441003_PIP-SCONN,HA
M_A_DQ<47>               U5D1             P35      SKX_EXT_B_BGA1-IC,TBD
M_A_DQ<48>               J4G1             264      SCONN288_H44441004_PIP-SCONN,HA
M_A_DQ<48>               J6T1             119      SCONN288_H44441003_PIP-SCONN,HA
M_A_DQ<48>               U5D1             K31      SKX_EXT_B_BGA1-IC,TBD
M_A_DQ<49>               J4G1             119      SCONN288_H44441004_PIP-SCONN,HA
M_A_DQ<49>               J6T1             264      SCONN288_H44441003_PIP-SCONN,HA
M_A_DQ<49>               U5D1             P31      SKX_EXT_B_BGA1-IC,TBD
M_A_DQ<50>               J4G1             271      SCONN288_H44441004_PIP-SCONN,HA
M_A_DQ<50>               J6T1             126      SCONN288_H44441003_PIP-SCONN,HA
M_A_DQ<50>               U5D1             L28      SKX_EXT_B_BGA1-IC,TBD
M_A_DQ<51>               J4G1             126      SCONN288_H44441004_PIP-SCONN,HA
M_A_DQ<51>               J6T1             271      SCONN288_H44441003_PIP-SCONN,HA
M_A_DQ<51>               U5D1             N28      SKX_EXT_B_BGA1-IC,TBD
M_A_DQ<52>               J4G1             262      SCONN288_H44441004_PIP-SCONN,HA
M_A_DQ<52>               J6T1             117      SCONN288_H44441003_PIP-SCONN,HA
M_A_DQ<52>               U5D1             L32      SKX_EXT_B_BGA1-IC,TBD
M_A_DQ<53>               J4G1             117      SCONN288_H44441004_PIP-SCONN,HA
M_A_DQ<53>               J6T1             262      SCONN288_H44441003_PIP-SCONN,HA
M_A_DQ<53>               U5D1             N32      SKX_EXT_B_BGA1-IC,TBD
M_A_DQ<54>               J4G1             269      SCONN288_H44441004_PIP-SCONN,HA
M_A_DQ<54>               J6T1             124      SCONN288_H44441003_PIP-SCONN,HA
M_A_DQ<54>               U5D1             K29      SKX_EXT_B_BGA1-IC,TBD
M_A_DQ<55>               J4G1             124      SCONN288_H44441004_PIP-SCONN,HA
M_A_DQ<55>               J6T1             269      SCONN288_H44441003_PIP-SCONN,HA
M_A_DQ<55>               U5D1             P29      SKX_EXT_B_BGA1-IC,TBD
M_A_DQ<56>               J4G1             275      SCONN288_H44441004_PIP-SCONN,HA
M_A_DQ<56>               J6T1             130      SCONN288_H44441003_PIP-SCONN,HA
M_A_DQ<56>               U5D1             K25      SKX_EXT_B_BGA1-IC,TBD
M_A_DQ<57>               J4G1             130      SCONN288_H44441004_PIP-SCONN,HA
M_A_DQ<57>               J6T1             275      SCONN288_H44441003_PIP-SCONN,HA
M_A_DQ<57>               U5D1             P25      SKX_EXT_B_BGA1-IC,TBD
M_A_DQ<58>               J4G1             282      SCONN288_H44441004_PIP-SCONN,HA
M_A_DQ<58>               J6T1             137      SCONN288_H44441003_PIP-SCONN,HA
M_A_DQ<58>               U5D1             P23      SKX_EXT_B_BGA1-IC,TBD
M_A_DQ<59>               J4G1             137      SCONN288_H44441004_PIP-SCONN,HA
M_A_DQ<59>               J6T1             282      SCONN288_H44441003_PIP-SCONN,HA
M_A_DQ<59>               U5D1             T23      SKX_EXT_B_BGA1-IC,TBD
M_A_DQ<60>               J4G1             273      SCONN288_H44441004_PIP-SCONN,HA
M_A_DQ<60>               J6T1             128      SCONN288_H44441003_PIP-SCONN,HA
M_A_DQ<60>               U5D1             L26      SKX_EXT_B_BGA1-IC,TBD
M_A_DQ<61>               J4G1             128      SCONN288_H44441004_PIP-SCONN,HA
M_A_DQ<61>               J6T1             273      SCONN288_H44441003_PIP-SCONN,HA
M_A_DQ<61>               U5D1             N26      SKX_EXT_B_BGA1-IC,TBD
M_A_DQ<62>               J4G1             280      SCONN288_H44441004_PIP-SCONN,HA
M_A_DQ<62>               J6T1             135      SCONN288_H44441003_PIP-SCONN,HA
M_A_DQ<62>               U5D1             H23      SKX_EXT_B_BGA1-IC,TBD
M_A_DQ<63>               J4G1             135      SCONN288_H44441004_PIP-SCONN,HA
M_A_DQ<63>               J6T1             280      SCONN288_H44441003_PIP-SCONN,HA
M_A_DQ<63>               U5D1             K23      SKX_EXT_B_BGA1-IC,TBD
M_A_DQS_DN<0>            J4G1             152      SCONN288_H44441004_PIP-SCONN,HA
M_A_DQS_DN<0>            J6T1             152      SCONN288_H44441003_PIP-SCONN,HA
M_A_DQS_DN<0>            U5D1             AJ84     SKX_EXT_B_BGA1-IC,TBD
M_A_DQS_DN<1>            J4G1             163      SCONN288_H44441004_PIP-SCONN,HA
M_A_DQS_DN<1>            J6T1             163      SCONN288_H44441003_PIP-SCONN,HA
M_A_DQS_DN<1>            U5D1             R84      SKX_EXT_B_BGA1-IC,TBD
M_A_DQS_DN<2>            J4G1             174      SCONN288_H44441004_PIP-SCONN,HA
M_A_DQS_DN<2>            J6T1             174      SCONN288_H44441003_PIP-SCONN,HA
M_A_DQS_DN<2>            U5D1             P79      SKX_EXT_B_BGA1-IC,TBD
M_A_DQS_DN<3>            J4G1             185      SCONN288_H44441004_PIP-SCONN,HA
M_A_DQS_DN<3>            J6T1             185      SCONN288_H44441003_PIP-SCONN,HA
M_A_DQS_DN<3>            U5D1             T75      SKX_EXT_B_BGA1-IC,TBD
M_A_DQS_DN<4>            J4G1             244      SCONN288_H44441004_PIP-SCONN,HA
M_A_DQS_DN<4>            J6T1             244      SCONN288_H44441003_PIP-SCONN,HA
M_A_DQS_DN<4>            U5D1             G40      SKX_EXT_B_BGA1-IC,TBD
M_A_DQS_DN<5>            J4G1             255      SCONN288_H44441004_PIP-SCONN,HA
M_A_DQS_DN<5>            J6T1             255      SCONN288_H44441003_PIP-SCONN,HA
M_A_DQS_DN<5>            U5D1             R36      SKX_EXT_B_BGA1-IC,TBD
M_A_DQS_DN<6>            J4G1             266      SCONN288_H44441004_PIP-SCONN,HA
M_A_DQS_DN<6>            J6T1             266      SCONN288_H44441003_PIP-SCONN,HA
M_A_DQS_DN<6>            U5D1             R30      SKX_EXT_B_BGA1-IC,TBD
M_A_DQS_DN<7>            J4G1             277      SCONN288_H44441004_PIP-SCONN,HA
M_A_DQS_DN<7>            J6T1             277      SCONN288_H44441003_PIP-SCONN,HA
M_A_DQS_DN<7>            U5D1             N24      SKX_EXT_B_BGA1-IC,TBD
M_A_DQS_DN<8>            J4G1             196      SCONN288_H44441004_PIP-SCONN,HA
M_A_DQS_DN<8>            J6T1             196      SCONN288_H44441003_PIP-SCONN,HA
M_A_DQS_DN<8>            U5D1             AH67     SKX_EXT_B_BGA1-IC,TBD
M_A_DQS_DN<9>            J4G1             8        SCONN288_H44441004_PIP-SCONN,HA
M_A_DQS_DN<9>            J6T1             8        SCONN288_H44441003_PIP-SCONN,HA
M_A_DQS_DN<9>            U5D1             AL84     SKX_EXT_B_BGA1-IC,TBD
M_A_DQS_DN<10>           J4G1             19       SCONN288_H44441004_PIP-SCONN,HA
M_A_DQS_DN<10>           J6T1             19       SCONN288_H44441003_PIP-SCONN,HA
M_A_DQS_DN<10>           U5D1             U84      SKX_EXT_B_BGA1-IC,TBD
M_A_DQS_DN<11>           J4G1             30       SCONN288_H44441004_PIP-SCONN,HA
M_A_DQS_DN<11>           J6T1             30       SCONN288_H44441003_PIP-SCONN,HA
M_A_DQS_DN<11>           U5D1             U82      SKX_EXT_B_BGA1-IC,TBD
M_A_DQS_DN<12>           J4G1             41       SCONN288_H44441004_PIP-SCONN,HA
M_A_DQS_DN<12>           J6T1             41       SCONN288_H44441003_PIP-SCONN,HA
M_A_DQS_DN<12>           U5D1             K75      SKX_EXT_B_BGA1-IC,TBD
M_A_DQS_DN<13>           J4G1             100      SCONN288_H44441004_PIP-SCONN,HA
M_A_DQS_DN<13>           J6T1             100      SCONN288_H44441003_PIP-SCONN,HA
M_A_DQS_DN<13>           U5D1             A40      SKX_EXT_B_BGA1-IC,TBD
M_A_DQS_DN<14>           J4G1             111      SCONN288_H44441004_PIP-SCONN,HA
M_A_DQS_DN<14>           J6T1             111      SCONN288_H44441003_PIP-SCONN,HA
M_A_DQS_DN<14>           U5D1             J36      SKX_EXT_B_BGA1-IC,TBD
M_A_DQS_DN<15>           J4G1             122      SCONN288_H44441004_PIP-SCONN,HA
M_A_DQS_DN<15>           J6T1             122      SCONN288_H44441003_PIP-SCONN,HA
M_A_DQS_DN<15>           U5D1             J30      SKX_EXT_B_BGA1-IC,TBD
M_A_DQS_DN<16>           J4G1             133      SCONN288_H44441004_PIP-SCONN,HA
M_A_DQS_DN<16>           J6T1             133      SCONN288_H44441003_PIP-SCONN,HA
M_A_DQS_DN<16>           U5D1             J24      SKX_EXT_B_BGA1-IC,TBD
M_A_DQS_DN<17>           J4G1             52       SCONN288_H44441004_PIP-SCONN,HA
M_A_DQS_DN<17>           J6T1             52       SCONN288_H44441003_PIP-SCONN,HA
M_A_DQS_DN<17>           U5D1             AB67     SKX_EXT_B_BGA1-IC,TBD
M_A_DQS_DP<0>            J4G1             153      SCONN288_H44441004_PIP-SCONN,HA
M_A_DQS_DP<0>            J6T1             153      SCONN288_H44441003_PIP-SCONN,HA
M_A_DQS_DP<0>            U5D1             AH85     SKX_EXT_B_BGA1-IC,TBD
M_A_DQS_DP<1>            J4G1             164      SCONN288_H44441004_PIP-SCONN,HA
M_A_DQS_DP<1>            J6T1             164      SCONN288_H44441003_PIP-SCONN,HA
M_A_DQS_DP<1>            U5D1             P85      SKX_EXT_B_BGA1-IC,TBD
M_A_DQS_DP<2>            J4G1             175      SCONN288_H44441004_PIP-SCONN,HA
M_A_DQS_DP<2>            J6T1             175      SCONN288_H44441003_PIP-SCONN,HA
M_A_DQS_DP<2>            U5D1             R80      SKX_EXT_B_BGA1-IC,TBD
M_A_DQS_DP<3>            J4G1             186      SCONN288_H44441004_PIP-SCONN,HA
M_A_DQS_DP<3>            J6T1             186      SCONN288_H44441003_PIP-SCONN,HA
M_A_DQS_DP<3>            U5D1             P75      SKX_EXT_B_BGA1-IC,TBD
M_A_DQS_DP<4>            J4G1             245      SCONN288_H44441004_PIP-SCONN,HA
M_A_DQS_DP<4>            J6T1             245      SCONN288_H44441003_PIP-SCONN,HA
M_A_DQS_DP<4>            U5D1             E40      SKX_EXT_B_BGA1-IC,TBD
M_A_DQS_DP<5>            J4G1             256      SCONN288_H44441004_PIP-SCONN,HA
M_A_DQS_DP<5>            J6T1             256      SCONN288_H44441003_PIP-SCONN,HA
M_A_DQS_DP<5>            U5D1             N36      SKX_EXT_B_BGA1-IC,TBD
M_A_DQS_DP<6>            J4G1             267      SCONN288_H44441004_PIP-SCONN,HA
M_A_DQS_DP<6>            J6T1             267      SCONN288_H44441003_PIP-SCONN,HA
M_A_DQS_DP<6>            U5D1             N30      SKX_EXT_B_BGA1-IC,TBD
M_A_DQS_DP<7>            J4G1             278      SCONN288_H44441004_PIP-SCONN,HA
M_A_DQS_DP<7>            J6T1             278      SCONN288_H44441003_PIP-SCONN,HA
M_A_DQS_DP<7>            U5D1             R24      SKX_EXT_B_BGA1-IC,TBD
M_A_DQS_DP<8>            J4G1             197      SCONN288_H44441004_PIP-SCONN,HA
M_A_DQS_DP<8>            J6T1             197      SCONN288_H44441003_PIP-SCONN,HA
M_A_DQS_DP<8>            U5D1             AF67     SKX_EXT_B_BGA1-IC,TBD
M_A_DQS_DP<9>            J4G1             7        SCONN288_H44441004_PIP-SCONN,HA
M_A_DQS_DP<9>            J6T1             7        SCONN288_H44441003_PIP-SCONN,HA
M_A_DQS_DP<9>            U5D1             AM85     SKX_EXT_B_BGA1-IC,TBD
M_A_DQS_DP<10>           J4G1             18       SCONN288_H44441004_PIP-SCONN,HA
M_A_DQS_DP<10>           J6T1             18       SCONN288_H44441003_PIP-SCONN,HA
M_A_DQS_DP<10>           U5D1             V85      SKX_EXT_B_BGA1-IC,TBD
M_A_DQS_DP<11>           J4G1             29       SCONN288_H44441004_PIP-SCONN,HA
M_A_DQS_DP<11>           J6T1             29       SCONN288_H44441003_PIP-SCONN,HA
M_A_DQS_DP<11>           U5D1             T81      SKX_EXT_B_BGA1-IC,TBD
M_A_DQS_DP<12>           J4G1             40       SCONN288_H44441004_PIP-SCONN,HA
M_A_DQS_DP<12>           J6T1             40       SCONN288_H44441003_PIP-SCONN,HA
M_A_DQS_DP<12>           U5D1             M75      SKX_EXT_B_BGA1-IC,TBD
M_A_DQS_DP<13>           J4G1             99       SCONN288_H44441004_PIP-SCONN,HA
M_A_DQS_DP<13>           J6T1             99       SCONN288_H44441003_PIP-SCONN,HA
M_A_DQS_DP<13>           U5D1             C40      SKX_EXT_B_BGA1-IC,TBD
M_A_DQS_DP<14>           J4G1             110      SCONN288_H44441004_PIP-SCONN,HA
M_A_DQS_DP<14>           J6T1             110      SCONN288_H44441003_PIP-SCONN,HA
M_A_DQS_DP<14>           U5D1             L36      SKX_EXT_B_BGA1-IC,TBD
M_A_DQS_DP<15>           J4G1             121      SCONN288_H44441004_PIP-SCONN,HA
M_A_DQS_DP<15>           J6T1             121      SCONN288_H44441003_PIP-SCONN,HA
M_A_DQS_DP<15>           U5D1             L30      SKX_EXT_B_BGA1-IC,TBD
M_A_DQS_DP<16>           J4G1             132      SCONN288_H44441004_PIP-SCONN,HA
M_A_DQS_DP<16>           J6T1             132      SCONN288_H44441003_PIP-SCONN,HA
M_A_DQS_DP<16>           U5D1             L24      SKX_EXT_B_BGA1-IC,TBD
M_A_DQS_DP<17>           J4G1             51       SCONN288_H44441004_PIP-SCONN,HA
M_A_DQS_DP<17>           J6T1             51       SCONN288_H44441003_PIP-SCONN,HA
M_A_DQS_DP<17>           U5D1             AD67     SKX_EXT_B_BGA1-IC,TBD
M_A_ECC<0>               J4G1             194      SCONN288_H44441004_PIP-SCONN,HA
M_A_ECC<0>               J6T1             49       SCONN288_H44441003_PIP-SCONN,HA
M_A_ECC<0>               U5D1             AC68     SKX_EXT_B_BGA1-IC,TBD
M_A_ECC<1>               J4G1             49       SCONN288_H44441004_PIP-SCONN,HA
M_A_ECC<1>               J6T1             194      SCONN288_H44441003_PIP-SCONN,HA
M_A_ECC<1>               U5D1             AG68     SKX_EXT_B_BGA1-IC,TBD
M_A_ECC<2>               J4G1             201      SCONN288_H44441004_PIP-SCONN,HA
M_A_ECC<2>               J6T1             56       SCONN288_H44441003_PIP-SCONN,HA
M_A_ECC<2>               U5D1             AD65     SKX_EXT_B_BGA1-IC,TBD
M_A_ECC<3>               J4G1             56       SCONN288_H44441004_PIP-SCONN,HA
M_A_ECC<3>               J6T1             201      SCONN288_H44441003_PIP-SCONN,HA
M_A_ECC<3>               U5D1             AF65     SKX_EXT_B_BGA1-IC,TBD
M_A_ECC<4>               J4G1             192      SCONN288_H44441004_PIP-SCONN,HA
M_A_ECC<4>               J6T1             47       SCONN288_H44441003_PIP-SCONN,HA
M_A_ECC<4>               U5D1             AD69     SKX_EXT_B_BGA1-IC,TBD
M_A_ECC<5>               J4G1             47       SCONN288_H44441004_PIP-SCONN,HA
M_A_ECC<5>               J6T1             192      SCONN288_H44441003_PIP-SCONN,HA
M_A_ECC<5>               U5D1             AF69     SKX_EXT_B_BGA1-IC,TBD
M_A_ECC<6>               J4G1             199      SCONN288_H44441004_PIP-SCONN,HA
M_A_ECC<6>               J6T1             54       SCONN288_H44441003_PIP-SCONN,HA
M_A_ECC<6>               U5D1             AC66     SKX_EXT_B_BGA1-IC,TBD
M_A_ECC<7>               J4G1             54       SCONN288_H44441004_PIP-SCONN,HA
M_A_ECC<7>               J6T1             199      SCONN288_H44441003_PIP-SCONN,HA
M_A_ECC<7>               U5D1             AG66     SKX_EXT_B_BGA1-IC,TBD
M_A_MA<0>                J4G1             79       SCONN288_H44441004_PIP-SCONN,HA
M_A_MA<0>                J6T1             79       SCONN288_H44441003_PIP-SCONN,HA
M_A_MA<0>                U5D1             F53      SKX_EXT_B_BGA1-IC,TBD
M_A_MA<1>                J4G1             72       SCONN288_H44441004_PIP-SCONN,HA
M_A_MA<1>                J6T1             72       SCONN288_H44441003_PIP-SCONN,HA
M_A_MA<1>                U5D1             F57      SKX_EXT_B_BGA1-IC,TBD
M_A_MA<2>                J4G1             216      SCONN288_H44441004_PIP-SCONN,HA
M_A_MA<2>                J6T1             216      SCONN288_H44441003_PIP-SCONN,HA
M_A_MA<2>                U5D1             D57      SKX_EXT_B_BGA1-IC,TBD
M_A_MA<3>                J4G1             71       SCONN288_H44441004_PIP-SCONN,HA
M_A_MA<3>                J6T1             71       SCONN288_H44441003_PIP-SCONN,HA
M_A_MA<3>                U5D1             C58      SKX_EXT_B_BGA1-IC,TBD
M_A_MA<4>                J4G1             214      SCONN288_H44441004_PIP-SCONN,HA
M_A_MA<4>                J6T1             214      SCONN288_H44441003_PIP-SCONN,HA
M_A_MA<4>                U5D1             G58      SKX_EXT_B_BGA1-IC,TBD
M_A_MA<5>                J4G1             213      SCONN288_H44441004_PIP-SCONN,HA
M_A_MA<5>                J6T1             213      SCONN288_H44441003_PIP-SCONN,HA
M_A_MA<5>                U5D1             F59      SKX_EXT_B_BGA1-IC,TBD
M_A_MA<6>                J4G1             69       SCONN288_H44441004_PIP-SCONN,HA
M_A_MA<6>                J6T1             69       SCONN288_H44441003_PIP-SCONN,HA
M_A_MA<6>                U5D1             D59      SKX_EXT_B_BGA1-IC,TBD
M_A_MA<7>                J4G1             211      SCONN288_H44441004_PIP-SCONN,HA
M_A_MA<7>                J6T1             211      SCONN288_H44441003_PIP-SCONN,HA
M_A_MA<7>                U5D1             G60      SKX_EXT_B_BGA1-IC,TBD
M_A_MA<8>                J4G1             68       SCONN288_H44441004_PIP-SCONN,HA
M_A_MA<8>                J6T1             68       SCONN288_H44441003_PIP-SCONN,HA
M_A_MA<8>                U5D1             C60      SKX_EXT_B_BGA1-IC,TBD
M_A_MA<9>                J4G1             66       SCONN288_H44441004_PIP-SCONN,HA
M_A_MA<9>                J6T1             66       SCONN288_H44441003_PIP-SCONN,HA
M_A_MA<9>                U5D1             F61      SKX_EXT_B_BGA1-IC,TBD
M_A_MA<10>               J4G1             225      SCONN288_H44441004_PIP-SCONN,HA
M_A_MA<10>               J6T1             225      SCONN288_H44441003_PIP-SCONN,HA
M_A_MA<10>               U5D1             J54      SKX_EXT_B_BGA1-IC,TBD
M_A_MA<11>               J4G1             210      SCONN288_H44441004_PIP-SCONN,HA
M_A_MA<11>               J6T1             210      SCONN288_H44441003_PIP-SCONN,HA
M_A_MA<11>               U5D1             G62      SKX_EXT_B_BGA1-IC,TBD
M_A_MA<12>               J4G1             65       SCONN288_H44441004_PIP-SCONN,HA
M_A_MA<12>               J6T1             65       SCONN288_H44441003_PIP-SCONN,HA
M_A_MA<12>               U5D1             J64      SKX_EXT_B_BGA1-IC,TBD
M_A_MA<13>               J4G1             232      SCONN288_H44441004_PIP-SCONN,HA
M_A_MA<13>               J6T1             232      SCONN288_H44441003_PIP-SCONN,HA
M_A_MA<13>               U5D1             J48      SKX_EXT_B_BGA1-IC,TBD
M_A_MA<14>               J4G1             228      SCONN288_H44441004_PIP-SCONN,HA
M_A_MA<14>               J6T1             228      SCONN288_H44441003_PIP-SCONN,HA
M_A_MA<14>               U5D1             F51      SKX_EXT_B_BGA1-IC,TBD
M_A_MA<15>               J4G1             86       SCONN288_H44441004_PIP-SCONN,HA
M_A_MA<15>               J6T1             86       SCONN288_H44441003_PIP-SCONN,HA
M_A_MA<15>               U5D1             K49      SKX_EXT_B_BGA1-IC,TBD
M_A_MA<16>               J4G1             82       SCONN288_H44441004_PIP-SCONN,HA
M_A_MA<16>               J6T1             82       SCONN288_H44441003_PIP-SCONN,HA
M_A_MA<16>               U5D1             D51      SKX_EXT_B_BGA1-IC,TBD
M_A_MA<17>               J4G1             234      SCONN288_H44441004_PIP-SCONN,HA
M_A_MA<17>               J6T1             234      SCONN288_H44441003_PIP-SCONN,HA
M_A_MA<17>               U5D1             K47      SKX_EXT_B_BGA1-IC,TBD
M_A_ODT<0>               J4G1             87       SCONN288_H44441004_PIP-SCONN,HA
M_A_ODT<0>               U5D1             C50      SKX_EXT_B_BGA1-IC,TBD
M_A_ODT<1>               J4G1             91       SCONN288_H44441004_PIP-SCONN,HA
M_A_ODT<1>               U5D1             C48      SKX_EXT_B_BGA1-IC,TBD
M_A_ODT<2>               J6T1             87       SCONN288_H44441003_PIP-SCONN,HA
M_A_ODT<2>               U5D1             G50      SKX_EXT_B_BGA1-IC,TBD
M_A_ODT<3>               J6T1             91       SCONN288_H44441003_PIP-SCONN,HA
M_A_ODT<3>               U5D1             G48      SKX_EXT_B_BGA1-IC,TBD
M_A_PAR                  J4G1             222      SCONN288_H44441004_PIP-SCONN,HA
M_A_PAR                  J6T1             222      SCONN288_H44441003_PIP-SCONN,HA
M_A_PAR                  U5D1             D53      SKX_EXT_B_BGA1-IC,TBD
M_A_VREF                 C4F10            1        CAP_A_0402V-0.01UF,25V,10%,X7RA
M_A_VREF                 C6T1             1        CAP_A_0402V-0.01UF,25V,10%,X7RA
M_A_VREF                 J4G1             146      SCONN288_H44441004_PIP-SCONN,HA
M_A_VREF                 J6T1             146      SCONN288_H44441003_PIP-SCONN,HA
M_A_VREF                 R4F3             2        RES_0402-2,1.0%,1/16W,CHIP,G21A
M_A_VREF                 R4F4             2        RES_0402-1.00K,1%,1/16W,CHIP,GA
M_A_VREF                 R4F5             1        RES_0402-1.00K,1%,1/16W,CHIP,GA
M_BMC_DDR3_DQ<0>         U9F4             W12      AST1250_BGA-IC,G85138-002
M_BMC_DDR3_DQ<0>         U9F5             H7       K4B1G16_BGA1-IC,G38649-001
M_BMC_DDR3_DQ<1>         U9F4             V12      AST1250_BGA-IC,G85138-002
M_BMC_DDR3_DQ<1>         U9F5             H3       K4B1G16_BGA1-IC,G38649-001
M_BMC_DDR3_DQ<2>         U9F4             AB11     AST1250_BGA-IC,G85138-002
M_BMC_DDR3_DQ<2>         U9F5             F8       K4B1G16_BGA1-IC,G38649-001
M_BMC_DDR3_DQ<3>         U9F4             AA11     AST1250_BGA-IC,G85138-002
M_BMC_DDR3_DQ<3>         U9F5             F7       K4B1G16_BGA1-IC,G38649-001
M_BMC_DDR3_DQ<4>         U9F4             Y11      AST1250_BGA-IC,G85138-002
M_BMC_DDR3_DQ<4>         U9F5             F2       K4B1G16_BGA1-IC,G38649-001
M_BMC_DDR3_DQ<5>         U9F4             W11      AST1250_BGA-IC,G85138-002
M_BMC_DDR3_DQ<5>         U9F5             G2       K4B1G16_BGA1-IC,G38649-001
M_BMC_DDR3_DQ<6>         U9F4             V11      AST1250_BGA-IC,G85138-002
M_BMC_DDR3_DQ<6>         U9F5             H8       K4B1G16_BGA1-IC,G38649-001
M_BMC_DDR3_DQ<7>         U9F4             Y10      AST1250_BGA-IC,G85138-002
M_BMC_DDR3_DQ<7>         U9F5             E3       K4B1G16_BGA1-IC,G38649-001
M_BMC_DDR3_DQ<8>         U9F4             V10      AST1250_BGA-IC,G85138-002
M_BMC_DDR3_DQ<8>         U9F5             D7       K4B1G16_BGA1-IC,G38649-001
M_BMC_DDR3_DQ<9>         U9F4             AB9      AST1250_BGA-IC,G85138-002
M_BMC_DDR3_DQ<9>         U9F5             B8       K4B1G16_BGA1-IC,G38649-001
M_BMC_DDR3_DQ<10>        U9F4             AA9      AST1250_BGA-IC,G85138-002
M_BMC_DDR3_DQ<10>        U9F5             A7       K4B1G16_BGA1-IC,G38649-001
M_BMC_DDR3_DQ<11>        U9F4             Y9       AST1250_BGA-IC,G85138-002
M_BMC_DDR3_DQ<11>        U9F5             C3       K4B1G16_BGA1-IC,G38649-001
M_BMC_DDR3_DQ<12>        U9F4             W9       AST1250_BGA-IC,G85138-002
M_BMC_DDR3_DQ<12>        U9F5             C2       K4B1G16_BGA1-IC,G38649-001
M_BMC_DDR3_DQ<13>        U9F4             V9       AST1250_BGA-IC,G85138-002
M_BMC_DDR3_DQ<13>        U9F5             C8       K4B1G16_BGA1-IC,G38649-001
M_BMC_DDR3_DQ<14>        U9F4             Y8       AST1250_BGA-IC,G85138-002
M_BMC_DDR3_DQ<14>        U9F5             A3       K4B1G16_BGA1-IC,G38649-001
M_BMC_DDR3_DQ<15>        U9F4             W8       AST1250_BGA-IC,G85138-002
M_BMC_DDR3_DQ<15>        U9F5             A2       K4B1G16_BGA1-IC,G38649-001
M_BMC_DDR3_MA<0>         U9F4             AB14     AST1250_BGA-IC,G85138-002
M_BMC_DDR3_MA<0>         U9F5             N3       K4B1G16_BGA1-IC,G38649-001
M_BMC_DDR3_MA<1>         U9F4             W15      AST1250_BGA-IC,G85138-002
M_BMC_DDR3_MA<1>         U9F5             P7       K4B1G16_BGA1-IC,G38649-001
M_BMC_DDR3_MA<2>         U9F4             V15      AST1250_BGA-IC,G85138-002
M_BMC_DDR3_MA<2>         U9F5             P3       K4B1G16_BGA1-IC,G38649-001
M_BMC_DDR3_MA<3>         U9F4             Y16      AST1250_BGA-IC,G85138-002
M_BMC_DDR3_MA<3>         U9F5             N2       K4B1G16_BGA1-IC,G38649-001
M_BMC_DDR3_MA<4>         U9F4             AB15     AST1250_BGA-IC,G85138-002
M_BMC_DDR3_MA<4>         U9F5             P8       K4B1G16_BGA1-IC,G38649-001
M_BMC_DDR3_MA<5>         U9F4             W16      AST1250_BGA-IC,G85138-002
M_BMC_DDR3_MA<5>         U9F5             P2       K4B1G16_BGA1-IC,G38649-001
M_BMC_DDR3_MA<6>         U9F4             AA15     AST1250_BGA-IC,G85138-002
M_BMC_DDR3_MA<6>         U9F5             R8       K4B1G16_BGA1-IC,G38649-001
M_BMC_DDR3_MA<7>         U9F4             AB18     AST1250_BGA-IC,G85138-002
M_BMC_DDR3_MA<7>         U9F5             R2       K4B1G16_BGA1-IC,G38649-001
M_BMC_DDR3_MA<8>         U9F4             AB16     AST1250_BGA-IC,G85138-002
M_BMC_DDR3_MA<8>         U9F5             T8       K4B1G16_BGA1-IC,G38649-001
M_BMC_DDR3_MA<9>         U9F4             AA17     AST1250_BGA-IC,G85138-002
M_BMC_DDR3_MA<9>         U9F5             R3       K4B1G16_BGA1-IC,G38649-001
M_BMC_DDR3_MA<10>        U9F4             Y15      AST1250_BGA-IC,G85138-002
M_BMC_DDR3_MA<10>        U9F5             L7       K4B1G16_BGA1-IC,G38649-001
M_BMC_DDR3_MA<11>        U9F4             AA16     AST1250_BGA-IC,G85138-002
M_BMC_DDR3_MA<11>        U9F5             R7       K4B1G16_BGA1-IC,G38649-001
M_BMC_DDR3_MA<12>        U9F4             W17      AST1250_BGA-IC,G85138-002
M_BMC_DDR3_MA<12>        U9F5             N7       K4B1G16_BGA1-IC,G38649-001
M_BMC_DDR3_MA<13>        U9F4             Y17      AST1250_BGA-IC,G85138-002
M_BMC_DDR3_MA<13>        U9F5             T3       K4B1G16_BGA1-IC,G38649-001
M_BMC_DDR3_MA<14>        U9F4             AB17     AST1250_BGA-IC,G85138-002
M_BMC_DDR3_MA<14>        U9F5             T7       K4B1G16_BGA1-IC,G38649-001
M_BMC_DDR3_MBA_0         U9F4             W14      AST1250_BGA-IC,G85138-002
M_BMC_DDR3_MBA_0         U9F5             M2       K4B1G16_BGA1-IC,G38649-001
M_BMC_DDR3_MBA_1         U9F4             AA14     AST1250_BGA-IC,G85138-002
M_BMC_DDR3_MBA_1         U9F5             N8       K4B1G16_BGA1-IC,G38649-001
M_BMC_DDR3_MBA_2         U9F4             Y14      AST1250_BGA-IC,G85138-002
M_BMC_DDR3_MBA_2         U9F5             M3       K4B1G16_BGA1-IC,G38649-001
M_BMC_DDR3_MCAS_N        U9F4             AB13     AST1250_BGA-IC,G85138-002
M_BMC_DDR3_MCAS_N        U9F5             K3       K4B1G16_BGA1-IC,G38649-001
M_BMC_DDR3_MCKE          U9F4             Y12      AST1250_BGA-IC,G85138-002
M_BMC_DDR3_MCKE          U9F5             K9       K4B1G16_BGA1-IC,G38649-001
M_BMC_DDR3_MCK_N         U9F4             AA12     AST1250_BGA-IC,G85138-002
M_BMC_DDR3_MCK_N         U9F5             K7       K4B1G16_BGA1-IC,G38649-001
M_BMC_DDR3_MCK_P         U9F4             AB12     AST1250_BGA-IC,G85138-002
M_BMC_DDR3_MCK_P         U9F5             J7       K4B1G16_BGA1-IC,G38649-001
M_BMC_DDR3_MCS_N         U9F4             AA13     AST1250_BGA-IC,G85138-002
M_BMC_DDR3_MCS_N         U9F5             L2       K4B1G16_BGA1-IC,G38649-001
M_BMC_DDR3_MDM_0         U9F4             W10      AST1250_BGA-IC,G85138-002
M_BMC_DDR3_MDM_0         U9F5             E7       K4B1G16_BGA1-IC,G38649-001
M_BMC_DDR3_MDM_1         U9F4             V8       AST1250_BGA-IC,G85138-002
M_BMC_DDR3_MDM_1         U9F5             D3       K4B1G16_BGA1-IC,G38649-001
M_BMC_DDR3_MDQS_0_DN     U9F4             AA10     AST1250_BGA-IC,G85138-002
M_BMC_DDR3_MDQS_0_DN     U9F5             G3       K4B1G16_BGA1-IC,G38649-001
M_BMC_DDR3_MDQS_0_DP     U9F4             AB10     AST1250_BGA-IC,G85138-002
M_BMC_DDR3_MDQS_0_DP     U9F5             F3       K4B1G16_BGA1-IC,G38649-001
M_BMC_DDR3_MDQS_1_DN     U9F4             AB8      AST1250_BGA-IC,G85138-002
M_BMC_DDR3_MDQS_1_DN     U9F5             B7       K4B1G16_BGA1-IC,G38649-001
M_BMC_DDR3_MDQS_1_DP     U9F4             AA8      AST1250_BGA-IC,G85138-002
M_BMC_DDR3_MDQS_1_DP     U9F5             C7       K4B1G16_BGA1-IC,G38649-001
M_BMC_DDR3_MODT          U9F4             V14      AST1250_BGA-IC,G85138-002
M_BMC_DDR3_MODT          U9F5             K1       K4B1G16_BGA1-IC,G38649-001
M_BMC_DDR3_MRAS_N        U9F4             W13      AST1250_BGA-IC,G85138-002
M_BMC_DDR3_MRAS_N        U9F5             J3       K4B1G16_BGA1-IC,G38649-001
M_BMC_DDR3_MVREF         C1T37            1        CAP_A_0402V-0.1UF,16V,10%,X7R,A
M_BMC_DDR3_MVREF         C1T39            2        CAP_A_0402V-0.01UF,25V,10%,X7RA
M_BMC_DDR3_MVREF         C1T41            1        CAP_A_0402V-0.01UF,25V,10%,X7RA
M_BMC_DDR3_MVREF         C1T48            1        CAP_A_0402V-0.1UF,16V,10%,X7R,A
M_BMC_DDR3_MVREF         C1T51            1        CAP_A_0402V-1.0UF,6.3V,10%,X6SA
M_BMC_DDR3_MVREF         R1T29            1        RES_0402-1.00K,1%,1/16W,CHIP,GA
M_BMC_DDR3_MVREF         R1T30            2        RES_0402-1.00K,1%,1/16W,CHIP,GA
M_BMC_DDR3_MVREF         U9F4             V13      AST1250_BGA-IC,G85138-002
M_BMC_DDR3_MVREF         U9F5             H1       K4B1G16_BGA1-IC,G38649-001
M_BMC_DDR3_MVREF         U9F5             M8       K4B1G16_BGA1-IC,G38649-001
M_BMC_DDR3_MWE_N         U9F4             Y13      AST1250_BGA-IC,G85138-002
M_BMC_DDR3_MWE_N         U9F5             L3       K4B1G16_BGA1-IC,G38649-001
M_B_ACT_N                J4G2             62       SCONN288_H44441004_PIP-SCONN,HA
M_B_ACT_N                J6U1             62       SCONN288_H44441003_PIP-SCONN,HA
M_B_ACT_N                U5D1             T63      SKX_EXT_B_BGA1-IC,TBD
M_B_ALERT_N              J4G2             208      SCONN288_H44441004_PIP-SCONN,HA
M_B_ALERT_N              J6U1             208      SCONN288_H44441003_PIP-SCONN,HA
M_B_ALERT_N              U5D1             W62      SKX_EXT_B_BGA1-IC,TBD
M_B_BA<0>                J4G2             81       SCONN288_H44441004_PIP-SCONN,HA
M_B_BA<0>                J6U1             81       SCONN288_H44441003_PIP-SCONN,HA
M_B_BA<0>                U5D1             T53      SKX_EXT_B_BGA1-IC,TBD
M_B_BA<1>                J4G2             224      SCONN288_H44441004_PIP-SCONN,HA
M_B_BA<1>                J6U1             224      SCONN288_H44441003_PIP-SCONN,HA
M_B_BA<1>                U5D1             K55      SKX_EXT_B_BGA1-IC,TBD
M_B_BG<0>                J4G2             63       SCONN288_H44441004_PIP-SCONN,HA
M_B_BG<0>                J6U1             63       SCONN288_H44441003_PIP-SCONN,HA
M_B_BG<0>                U5D1             M61      SKX_EXT_B_BGA1-IC,TBD
M_B_BG<1>                J4G2             207      SCONN288_H44441004_PIP-SCONN,HA
M_B_BG<1>                J6U1             207      SCONN288_H44441003_PIP-SCONN,HA
M_B_BG<1>                U5D1             N60      SKX_EXT_B_BGA1-IC,TBD
M_B_C<2>                 J4G2             235      SCONN288_H44441004_PIP-SCONN,HA
M_B_C<2>                 J6U1             235      SCONN288_H44441003_PIP-SCONN,HA
M_B_C<2>                 U5D1             M47      SKX_EXT_B_BGA1-IC,TBD
M_B_CKE<0>               J4G2             60       SCONN288_H44441004_PIP-SCONN,HA
M_B_CKE<0>               U5D1             N62      SKX_EXT_B_BGA1-IC,TBD
M_B_CKE<1>               J4G2             203      SCONN288_H44441004_PIP-SCONN,HA
M_B_CKE<1>               U5D1             R64      SKX_EXT_B_BGA1-IC,TBD
M_B_CKE<2>               J6U1             60       SCONN288_H44441003_PIP-SCONN,HA
M_B_CKE<2>               U5D1             K63      SKX_EXT_B_BGA1-IC,TBD
M_B_CKE<3>               J6U1             203      SCONN288_H44441003_PIP-SCONN,HA
M_B_CKE<3>               U5D1             L64      SKX_EXT_B_BGA1-IC,TBD
M_B_CLK_DN<0>            J4G2             75       SCONN288_H44441004_PIP-SCONN,HA
M_B_CLK_DN<0>            U5D1             M53      SKX_EXT_B_BGA1-IC,TBD
M_B_CLK_DN<1>            J4G2             219      SCONN288_H44441004_PIP-SCONN,HA
M_B_CLK_DN<1>            U5D1             R54      SKX_EXT_B_BGA1-IC,TBD
M_B_CLK_DN<2>            J6U1             75       SCONN288_H44441003_PIP-SCONN,HA
M_B_CLK_DN<2>            U5D1             N56      SKX_EXT_B_BGA1-IC,TBD
M_B_CLK_DN<3>            J6U1             219      SCONN288_H44441003_PIP-SCONN,HA
M_B_CLK_DN<3>            U5D1             R56      SKX_EXT_B_BGA1-IC,TBD
M_B_CLK_DP<0>            J4G2             74       SCONN288_H44441004_PIP-SCONN,HA
M_B_CLK_DP<0>            U5D1             N54      SKX_EXT_B_BGA1-IC,TBD
M_B_CLK_DP<1>            J4G2             218      SCONN288_H44441004_PIP-SCONN,HA
M_B_CLK_DP<1>            U5D1             T55      SKX_EXT_B_BGA1-IC,TBD
M_B_CLK_DP<2>            J6U1             74       SCONN288_H44441003_PIP-SCONN,HA
M_B_CLK_DP<2>            U5D1             M57      SKX_EXT_B_BGA1-IC,TBD
M_B_CLK_DP<3>            J6U1             218      SCONN288_H44441003_PIP-SCONN,HA
M_B_CLK_DP<3>            U5D1             T57      SKX_EXT_B_BGA1-IC,TBD
M_B_CPU_VREF             C4G1             1        CAP_A_0402V-0.01UF,25V,10%,X7RA
M_B_CPU_VREF             R4G1             1        RES_0402-2,1.0%,1/16W,CHIP,G21A
M_B_CPU_VREF             U5D1             AK63     SKX_EXT_B_BGA1-IC,TBD
M_B_CS_N<0>              J4G2             84       SCONN288_H44441004_PIP-SCONN,HA
M_B_CS_N<0>              U5D1             K51      SKX_EXT_B_BGA1-IC,TBD
M_B_CS_N<1>              J4G2             89       SCONN288_H44441004_PIP-SCONN,HA
M_B_CS_N<1>              U5D1             R50      SKX_EXT_B_BGA1-IC,TBD
M_B_CS_N<2>              J4G2             93       SCONN288_H44441004_PIP-SCONN,HA
M_B_CS_N<2>              U5D1             N46      SKX_EXT_B_BGA1-IC,TBD
M_B_CS_N<3>              J4G2             237      SCONN288_H44441004_PIP-SCONN,HA
M_B_CS_N<3>              U5D1             V47      SKX_EXT_B_BGA1-IC,TBD
M_B_CS_N<4>              J6U1             84       SCONN288_H44441003_PIP-SCONN,HA
M_B_CS_N<4>              U5D1             J50      SKX_EXT_B_BGA1-IC,TBD
M_B_CS_N<5>              J6U1             89       SCONN288_H44441003_PIP-SCONN,HA
M_B_CS_N<5>              U5D1             T49      SKX_EXT_B_BGA1-IC,TBD
M_B_CS_N<6>              J6U1             93       SCONN288_H44441003_PIP-SCONN,HA
M_B_CS_N<6>              U5D1             M45      SKX_EXT_B_BGA1-IC,TBD
M_B_CS_N<7>              J6U1             237      SCONN288_H44441003_PIP-SCONN,HA
M_B_CS_N<7>              U5D1             R46      SKX_EXT_B_BGA1-IC,TBD
M_B_DQ<0>                J4G2             150      SCONN288_H44441004_PIP-SCONN,HA
M_B_DQ<0>                J6U1             5        SCONN288_H44441003_PIP-SCONN,HA
M_B_DQ<0>                U5D1             AV81     SKX_EXT_B_BGA1-IC,TBD
M_B_DQ<1>                J4G2             5        SCONN288_H44441004_PIP-SCONN,HA
M_B_DQ<1>                J6U1             150      SCONN288_H44441003_PIP-SCONN,HA
M_B_DQ<1>                U5D1             AT79     SKX_EXT_B_BGA1-IC,TBD
M_B_DQ<2>                J4G2             157      SCONN288_H44441004_PIP-SCONN,HA
M_B_DQ<2>                J6U1             12       SCONN288_H44441003_PIP-SCONN,HA
M_B_DQ<2>                U5D1             AN82     SKX_EXT_B_BGA1-IC,TBD
M_B_DQ<3>                J4G2             12       SCONN288_H44441004_PIP-SCONN,HA
M_B_DQ<3>                J6U1             157      SCONN288_H44441003_PIP-SCONN,HA
M_B_DQ<3>                U5D1             AM81     SKX_EXT_B_BGA1-IC,TBD
M_B_DQ<4>                J4G2             148      SCONN288_H44441004_PIP-SCONN,HA
M_B_DQ<4>                J6U1             3        SCONN288_H44441003_PIP-SCONN,HA
M_B_DQ<4>                U5D1             AW80     SKX_EXT_B_BGA1-IC,TBD
M_B_DQ<5>                J4G2             3        SCONN288_H44441004_PIP-SCONN,HA
M_B_DQ<5>                J6U1             148      SCONN288_H44441003_PIP-SCONN,HA
M_B_DQ<5>                U5D1             AV79     SKX_EXT_B_BGA1-IC,TBD
M_B_DQ<6>                J4G2             155      SCONN288_H44441004_PIP-SCONN,HA
M_B_DQ<6>                J6U1             10       SCONN288_H44441003_PIP-SCONN,HA
M_B_DQ<6>                U5D1             AR82     SKX_EXT_B_BGA1-IC,TBD
M_B_DQ<7>                J4G2             10       SCONN288_H44441004_PIP-SCONN,HA
M_B_DQ<7>                J6U1             155      SCONN288_H44441003_PIP-SCONN,HA
M_B_DQ<7>                U5D1             AN80     SKX_EXT_B_BGA1-IC,TBD
M_B_DQ<8>                J4G2             161      SCONN288_H44441004_PIP-SCONN,HA
M_B_DQ<8>                J6U1             16       SCONN288_H44441003_PIP-SCONN,HA
M_B_DQ<8>                U5D1             AH81     SKX_EXT_B_BGA1-IC,TBD
M_B_DQ<9>                J4G2             16       SCONN288_H44441004_PIP-SCONN,HA
M_B_DQ<9>                J6U1             161      SCONN288_H44441003_PIP-SCONN,HA
M_B_DQ<9>                U5D1             AF79     SKX_EXT_B_BGA1-IC,TBD
M_B_DQ<10>               J4G2             168      SCONN288_H44441004_PIP-SCONN,HA
M_B_DQ<10>               J6U1             23       SCONN288_H44441003_PIP-SCONN,HA
M_B_DQ<10>               U5D1             AC82     SKX_EXT_B_BGA1-IC,TBD
M_B_DQ<11>               J4G2             23       SCONN288_H44441004_PIP-SCONN,HA
M_B_DQ<11>               J6U1             168      SCONN288_H44441003_PIP-SCONN,HA
M_B_DQ<11>               U5D1             AB81     SKX_EXT_B_BGA1-IC,TBD
M_B_DQ<12>               J4G2             159      SCONN288_H44441004_PIP-SCONN,HA
M_B_DQ<12>               J6U1             14       SCONN288_H44441003_PIP-SCONN,HA
M_B_DQ<12>               U5D1             AJ80     SKX_EXT_B_BGA1-IC,TBD
M_B_DQ<13>               J4G2             14       SCONN288_H44441004_PIP-SCONN,HA
M_B_DQ<13>               J6U1             159      SCONN288_H44441003_PIP-SCONN,HA
M_B_DQ<13>               U5D1             AH79     SKX_EXT_B_BGA1-IC,TBD
M_B_DQ<14>               J4G2             166      SCONN288_H44441004_PIP-SCONN,HA
M_B_DQ<14>               J6U1             21       SCONN288_H44441003_PIP-SCONN,HA
M_B_DQ<14>               U5D1             AE82     SKX_EXT_B_BGA1-IC,TBD
M_B_DQ<15>               J4G2             21       SCONN288_H44441004_PIP-SCONN,HA
M_B_DQ<15>               J6U1             166      SCONN288_H44441003_PIP-SCONN,HA
M_B_DQ<15>               U5D1             AC80     SKX_EXT_B_BGA1-IC,TBD
M_B_DQ<16>               J4G2             172      SCONN288_H44441004_PIP-SCONN,HA
M_B_DQ<16>               J6U1             27       SCONN288_H44441003_PIP-SCONN,HA
M_B_DQ<16>               U5D1             E80      SKX_EXT_B_BGA1-IC,TBD
M_B_DQ<17>               J4G2             27       SCONN288_H44441004_PIP-SCONN,HA
M_B_DQ<17>               J6U1             172      SCONN288_H44441003_PIP-SCONN,HA
M_B_DQ<17>               U5D1             J80      SKX_EXT_B_BGA1-IC,TBD
M_B_DQ<18>               J4G2             179      SCONN288_H44441004_PIP-SCONN,HA
M_B_DQ<18>               J6U1             34       SCONN288_H44441003_PIP-SCONN,HA
M_B_DQ<18>               U5D1             F77      SKX_EXT_B_BGA1-IC,TBD
M_B_DQ<19>               J4G2             34       SCONN288_H44441004_PIP-SCONN,HA
M_B_DQ<19>               J6U1             179      SCONN288_H44441003_PIP-SCONN,HA
M_B_DQ<19>               U5D1             H77      SKX_EXT_B_BGA1-IC,TBD
M_B_DQ<20>               J4G2             170      SCONN288_H44441004_PIP-SCONN,HA
M_B_DQ<20>               J6U1             25       SCONN288_H44441003_PIP-SCONN,HA
M_B_DQ<20>               U5D1             F81      SKX_EXT_B_BGA1-IC,TBD
M_B_DQ<21>               J4G2             25       SCONN288_H44441004_PIP-SCONN,HA
M_B_DQ<21>               J6U1             170      SCONN288_H44441003_PIP-SCONN,HA
M_B_DQ<21>               U5D1             H81      SKX_EXT_B_BGA1-IC,TBD
M_B_DQ<22>               J4G2             177      SCONN288_H44441004_PIP-SCONN,HA
M_B_DQ<22>               J6U1             32       SCONN288_H44441003_PIP-SCONN,HA
M_B_DQ<22>               U5D1             E78      SKX_EXT_B_BGA1-IC,TBD
M_B_DQ<23>               J4G2             32       SCONN288_H44441004_PIP-SCONN,HA
M_B_DQ<23>               J6U1             177      SCONN288_H44441003_PIP-SCONN,HA
M_B_DQ<23>               U5D1             J78      SKX_EXT_B_BGA1-IC,TBD
M_B_DQ<24>               J4G2             183      SCONN288_H44441004_PIP-SCONN,HA
M_B_DQ<24>               J6U1             38       SCONN288_H44441003_PIP-SCONN,HA
M_B_DQ<24>               U5D1             D75      SKX_EXT_B_BGA1-IC,TBD
M_B_DQ<25>               J4G2             38       SCONN288_H44441004_PIP-SCONN,HA
M_B_DQ<25>               J6U1             183      SCONN288_H44441003_PIP-SCONN,HA
M_B_DQ<25>               U5D1             C74      SKX_EXT_B_BGA1-IC,TBD
M_B_DQ<26>               J4G2             190      SCONN288_H44441004_PIP-SCONN,HA
M_B_DQ<26>               J6U1             45       SCONN288_H44441003_PIP-SCONN,HA
M_B_DQ<26>               U5D1             D71      SKX_EXT_B_BGA1-IC,TBD
M_B_DQ<27>               J4G2             45       SCONN288_H44441004_PIP-SCONN,HA
M_B_DQ<27>               J6U1             190      SCONN288_H44441003_PIP-SCONN,HA
M_B_DQ<27>               U5D1             F71      SKX_EXT_B_BGA1-IC,TBD
M_B_DQ<28>               J4G2             181      SCONN288_H44441004_PIP-SCONN,HA
M_B_DQ<28>               J6U1             36       SCONN288_H44441003_PIP-SCONN,HA
M_B_DQ<28>               U5D1             F75      SKX_EXT_B_BGA1-IC,TBD
M_B_DQ<29>               J4G2             36       SCONN288_H44441004_PIP-SCONN,HA
M_B_DQ<29>               J6U1             181      SCONN288_H44441003_PIP-SCONN,HA
M_B_DQ<29>               U5D1             G74      SKX_EXT_B_BGA1-IC,TBD
M_B_DQ<30>               J4G2             188      SCONN288_H44441004_PIP-SCONN,HA
M_B_DQ<30>               J6U1             43       SCONN288_H44441003_PIP-SCONN,HA
M_B_DQ<30>               U5D1             C72      SKX_EXT_B_BGA1-IC,TBD
M_B_DQ<31>               J4G2             43       SCONN288_H44441004_PIP-SCONN,HA
M_B_DQ<31>               J6U1             188      SCONN288_H44441003_PIP-SCONN,HA
M_B_DQ<31>               U5D1             G72      SKX_EXT_B_BGA1-IC,TBD
M_B_DQ<32>               J4G2             242      SCONN288_H44441004_PIP-SCONN,HA
M_B_DQ<32>               J6U1             97       SCONN288_H44441003_PIP-SCONN,HA
M_B_DQ<32>               U5D1             K43      SKX_EXT_B_BGA1-IC,TBD
M_B_DQ<33>               J4G2             97       SCONN288_H44441004_PIP-SCONN,HA
M_B_DQ<33>               J6U1             242      SCONN288_H44441003_PIP-SCONN,HA
M_B_DQ<33>               U5D1             H43      SKX_EXT_B_BGA1-IC,TBD
M_B_DQ<34>               J4G2             249      SCONN288_H44441004_PIP-SCONN,HA
M_B_DQ<34>               J6U1             104      SCONN288_H44441003_PIP-SCONN,HA
M_B_DQ<34>               U5D1             L40      SKX_EXT_B_BGA1-IC,TBD
M_B_DQ<35>               J4G2             104      SCONN288_H44441004_PIP-SCONN,HA
M_B_DQ<35>               J6U1             249      SCONN288_H44441003_PIP-SCONN,HA
M_B_DQ<35>               U5D1             N40      SKX_EXT_B_BGA1-IC,TBD
M_B_DQ<36>               J4G2             240      SCONN288_H44441004_PIP-SCONN,HA
M_B_DQ<36>               J6U1             95       SCONN288_H44441003_PIP-SCONN,HA
M_B_DQ<36>               U5D1             P43      SKX_EXT_B_BGA1-IC,TBD
M_B_DQ<37>               J4G2             95       SCONN288_H44441004_PIP-SCONN,HA
M_B_DQ<37>               J6U1             240      SCONN288_H44441003_PIP-SCONN,HA
M_B_DQ<37>               U5D1             T43      SKX_EXT_B_BGA1-IC,TBD
M_B_DQ<38>               J4G2             247      SCONN288_H44441004_PIP-SCONN,HA
M_B_DQ<38>               J6U1             102      SCONN288_H44441003_PIP-SCONN,HA
M_B_DQ<38>               U5D1             K41      SKX_EXT_B_BGA1-IC,TBD
M_B_DQ<39>               J4G2             102      SCONN288_H44441004_PIP-SCONN,HA
M_B_DQ<39>               J6U1             247      SCONN288_H44441003_PIP-SCONN,HA
M_B_DQ<39>               U5D1             P41      SKX_EXT_B_BGA1-IC,TBD
M_B_DQ<40>               J4G2             253      SCONN288_H44441004_PIP-SCONN,HA
M_B_DQ<40>               J6U1             108      SCONN288_H44441003_PIP-SCONN,HA
M_B_DQ<40>               U5D1             C36      SKX_EXT_B_BGA1-IC,TBD
M_B_DQ<41>               J4G2             108      SCONN288_H44441004_PIP-SCONN,HA
M_B_DQ<41>               J6U1             253      SCONN288_H44441003_PIP-SCONN,HA
M_B_DQ<41>               U5D1             B35      SKX_EXT_B_BGA1-IC,TBD
M_B_DQ<42>               J4G2             260      SCONN288_H44441004_PIP-SCONN,HA
M_B_DQ<42>               J6U1             115      SCONN288_H44441003_PIP-SCONN,HA
M_B_DQ<42>               U5D1             C32      SKX_EXT_B_BGA1-IC,TBD
M_B_DQ<43>               J4G2             115      SCONN288_H44441004_PIP-SCONN,HA
M_B_DQ<43>               J6U1             260      SCONN288_H44441003_PIP-SCONN,HA
M_B_DQ<43>               U5D1             E32      SKX_EXT_B_BGA1-IC,TBD
M_B_DQ<44>               J4G2             251      SCONN288_H44441004_PIP-SCONN,HA
M_B_DQ<44>               J6U1             106      SCONN288_H44441003_PIP-SCONN,HA
M_B_DQ<44>               U5D1             E36      SKX_EXT_B_BGA1-IC,TBD
M_B_DQ<45>               J4G2             106      SCONN288_H44441004_PIP-SCONN,HA
M_B_DQ<45>               J6U1             251      SCONN288_H44441003_PIP-SCONN,HA
M_B_DQ<45>               U5D1             F35      SKX_EXT_B_BGA1-IC,TBD
M_B_DQ<46>               J4G2             258      SCONN288_H44441004_PIP-SCONN,HA
M_B_DQ<46>               J6U1             113      SCONN288_H44441003_PIP-SCONN,HA
M_B_DQ<46>               U5D1             B33      SKX_EXT_B_BGA1-IC,TBD
M_B_DQ<47>               J4G2             113      SCONN288_H44441004_PIP-SCONN,HA
M_B_DQ<47>               J6U1             258      SCONN288_H44441003_PIP-SCONN,HA
M_B_DQ<47>               U5D1             F33      SKX_EXT_B_BGA1-IC,TBD
M_B_DQ<48>               J4G2             264      SCONN288_H44441004_PIP-SCONN,HA
M_B_DQ<48>               J6U1             119      SCONN288_H44441003_PIP-SCONN,HA
M_B_DQ<48>               U5D1             C30      SKX_EXT_B_BGA1-IC,TBD
M_B_DQ<49>               J4G2             119      SCONN288_H44441004_PIP-SCONN,HA
M_B_DQ<49>               J6U1             264      SCONN288_H44441003_PIP-SCONN,HA
M_B_DQ<49>               U5D1             B29      SKX_EXT_B_BGA1-IC,TBD
M_B_DQ<50>               J4G2             271      SCONN288_H44441004_PIP-SCONN,HA
M_B_DQ<50>               J6U1             126      SCONN288_H44441003_PIP-SCONN,HA
M_B_DQ<50>               U5D1             C26      SKX_EXT_B_BGA1-IC,TBD
M_B_DQ<51>               J4G2             126      SCONN288_H44441004_PIP-SCONN,HA
M_B_DQ<51>               J6U1             271      SCONN288_H44441003_PIP-SCONN,HA
M_B_DQ<51>               U5D1             E26      SKX_EXT_B_BGA1-IC,TBD
M_B_DQ<52>               J4G2             262      SCONN288_H44441004_PIP-SCONN,HA
M_B_DQ<52>               J6U1             117      SCONN288_H44441003_PIP-SCONN,HA
M_B_DQ<52>               U5D1             E30      SKX_EXT_B_BGA1-IC,TBD
M_B_DQ<53>               J4G2             117      SCONN288_H44441004_PIP-SCONN,HA
M_B_DQ<53>               J6U1             262      SCONN288_H44441003_PIP-SCONN,HA
M_B_DQ<53>               U5D1             F29      SKX_EXT_B_BGA1-IC,TBD
M_B_DQ<54>               J4G2             269      SCONN288_H44441004_PIP-SCONN,HA
M_B_DQ<54>               J6U1             124      SCONN288_H44441003_PIP-SCONN,HA
M_B_DQ<54>               U5D1             B27      SKX_EXT_B_BGA1-IC,TBD
M_B_DQ<55>               J4G2             124      SCONN288_H44441004_PIP-SCONN,HA
M_B_DQ<55>               J6U1             269      SCONN288_H44441003_PIP-SCONN,HA
M_B_DQ<55>               U5D1             F27      SKX_EXT_B_BGA1-IC,TBD
M_B_DQ<56>               J4G2             275      SCONN288_H44441004_PIP-SCONN,HA
M_B_DQ<56>               J6U1             130      SCONN288_H44441003_PIP-SCONN,HA
M_B_DQ<56>               U5D1             U28      SKX_EXT_B_BGA1-IC,TBD
M_B_DQ<57>               J4G2             130      SCONN288_H44441004_PIP-SCONN,HA
M_B_DQ<57>               J6U1             275      SCONN288_H44441003_PIP-SCONN,HA
M_B_DQ<57>               U5D1             AA28     SKX_EXT_B_BGA1-IC,TBD
M_B_DQ<58>               J4G2             282      SCONN288_H44441004_PIP-SCONN,HA
M_B_DQ<58>               J6U1             137      SCONN288_H44441003_PIP-SCONN,HA
M_B_DQ<58>               U5D1             V25      SKX_EXT_B_BGA1-IC,TBD
M_B_DQ<59>               J4G2             137      SCONN288_H44441004_PIP-SCONN,HA
M_B_DQ<59>               J6U1             282      SCONN288_H44441003_PIP-SCONN,HA
M_B_DQ<59>               U5D1             Y25      SKX_EXT_B_BGA1-IC,TBD
M_B_DQ<60>               J4G2             273      SCONN288_H44441004_PIP-SCONN,HA
M_B_DQ<60>               J6U1             128      SCONN288_H44441003_PIP-SCONN,HA
M_B_DQ<60>               U5D1             V29      SKX_EXT_B_BGA1-IC,TBD
M_B_DQ<61>               J4G2             128      SCONN288_H44441004_PIP-SCONN,HA
M_B_DQ<61>               J6U1             273      SCONN288_H44441003_PIP-SCONN,HA
M_B_DQ<61>               U5D1             Y29      SKX_EXT_B_BGA1-IC,TBD
M_B_DQ<62>               J4G2             280      SCONN288_H44441004_PIP-SCONN,HA
M_B_DQ<62>               J6U1             135      SCONN288_H44441003_PIP-SCONN,HA
M_B_DQ<62>               U5D1             U26      SKX_EXT_B_BGA1-IC,TBD
M_B_DQ<63>               J4G2             135      SCONN288_H44441004_PIP-SCONN,HA
M_B_DQ<63>               J6U1             280      SCONN288_H44441003_PIP-SCONN,HA
M_B_DQ<63>               U5D1             AA26     SKX_EXT_B_BGA1-IC,TBD
M_B_DQS_DN<0>            J4G2             152      SCONN288_H44441004_PIP-SCONN,HA
M_B_DQS_DN<0>            J6U1             152      SCONN288_H44441003_PIP-SCONN,HA
M_B_DQS_DN<0>            U5D1             AP79     SKX_EXT_B_BGA1-IC,TBD
M_B_DQS_DN<1>            J4G2             163      SCONN288_H44441004_PIP-SCONN,HA
M_B_DQS_DN<1>            J6U1             163      SCONN288_H44441003_PIP-SCONN,HA
M_B_DQS_DN<1>            U5D1             AD79     SKX_EXT_B_BGA1-IC,TBD
M_B_DQS_DN<2>            J4G2             174      SCONN288_H44441004_PIP-SCONN,HA
M_B_DQS_DN<2>            J6U1             174      SCONN288_H44441003_PIP-SCONN,HA
M_B_DQS_DN<2>            U5D1             K79      SKX_EXT_B_BGA1-IC,TBD
M_B_DQS_DN<3>            J4G2             185      SCONN288_H44441004_PIP-SCONN,HA
M_B_DQS_DN<3>            J6U1             185      SCONN288_H44441003_PIP-SCONN,HA
M_B_DQS_DN<3>            U5D1             H73      SKX_EXT_B_BGA1-IC,TBD
M_B_DQS_DN<4>            J4G2             244      SCONN288_H44441004_PIP-SCONN,HA
M_B_DQS_DN<4>            J6U1             244      SCONN288_H44441003_PIP-SCONN,HA
M_B_DQS_DN<4>            U5D1             N42      SKX_EXT_B_BGA1-IC,TBD
M_B_DQS_DN<5>            J4G2             255      SCONN288_H44441004_PIP-SCONN,HA
M_B_DQS_DN<5>            J6U1             255      SCONN288_H44441003_PIP-SCONN,HA
M_B_DQS_DN<5>            U5D1             G34      SKX_EXT_B_BGA1-IC,TBD
M_B_DQS_DN<6>            J4G2             266      SCONN288_H44441004_PIP-SCONN,HA
M_B_DQS_DN<6>            J6U1             266      SCONN288_H44441003_PIP-SCONN,HA
M_B_DQS_DN<6>            U5D1             G28      SKX_EXT_B_BGA1-IC,TBD
M_B_DQS_DN<7>            J4G2             277      SCONN288_H44441004_PIP-SCONN,HA
M_B_DQS_DN<7>            J6U1             277      SCONN288_H44441003_PIP-SCONN,HA
M_B_DQS_DN<7>            U5D1             AB27     SKX_EXT_B_BGA1-IC,TBD
M_B_DQS_DN<8>            J4G2             196      SCONN288_H44441004_PIP-SCONN,HA
M_B_DQS_DN<8>            J6U1             196      SCONN288_H44441003_PIP-SCONN,HA
M_B_DQS_DN<8>            U5D1             N68      SKX_EXT_B_BGA1-IC,TBD
M_B_DQS_DN<9>            J4G2             8        SCONN288_H44441004_PIP-SCONN,HA
M_B_DQS_DN<9>            J6U1             8        SCONN288_H44441003_PIP-SCONN,HA
M_B_DQS_DN<9>            U5D1             AU82     SKX_EXT_B_BGA1-IC,TBD
M_B_DQS_DN<10>           J4G2             19       SCONN288_H44441004_PIP-SCONN,HA
M_B_DQS_DN<10>           J6U1             19       SCONN288_H44441003_PIP-SCONN,HA
M_B_DQS_DN<10>           U5D1             AG82     SKX_EXT_B_BGA1-IC,TBD
M_B_DQS_DN<11>           J4G2             30       SCONN288_H44441004_PIP-SCONN,HA
M_B_DQS_DN<11>           J6U1             30       SCONN288_H44441003_PIP-SCONN,HA
M_B_DQS_DN<11>           U5D1             D79      SKX_EXT_B_BGA1-IC,TBD
M_B_DQS_DN<12>           J4G2             41       SCONN288_H44441004_PIP-SCONN,HA
M_B_DQS_DN<12>           J6U1             41       SCONN288_H44441003_PIP-SCONN,HA
M_B_DQS_DN<12>           U5D1             B73      SKX_EXT_B_BGA1-IC,TBD
M_B_DQS_DN<13>           J4G2             100      SCONN288_H44441004_PIP-SCONN,HA
M_B_DQS_DN<13>           J6U1             100      SCONN288_H44441003_PIP-SCONN,HA
M_B_DQS_DN<13>           U5D1             J42      SKX_EXT_B_BGA1-IC,TBD
M_B_DQS_DN<14>           J4G2             111      SCONN288_H44441004_PIP-SCONN,HA
M_B_DQS_DN<14>           J6U1             111      SCONN288_H44441003_PIP-SCONN,HA
M_B_DQS_DN<14>           U5D1             A34      SKX_EXT_B_BGA1-IC,TBD
M_B_DQS_DN<15>           J4G2             122      SCONN288_H44441004_PIP-SCONN,HA
M_B_DQS_DN<15>           J6U1             122      SCONN288_H44441003_PIP-SCONN,HA
M_B_DQS_DN<15>           U5D1             A28      SKX_EXT_B_BGA1-IC,TBD
M_B_DQS_DN<16>           J4G2             133      SCONN288_H44441004_PIP-SCONN,HA
M_B_DQS_DN<16>           J6U1             133      SCONN288_H44441003_PIP-SCONN,HA
M_B_DQS_DN<16>           U5D1             T27      SKX_EXT_B_BGA1-IC,TBD
M_B_DQS_DN<17>           J4G2             52       SCONN288_H44441004_PIP-SCONN,HA
M_B_DQS_DN<17>           J6U1             52       SCONN288_H44441003_PIP-SCONN,HA
M_B_DQS_DN<17>           U5D1             G68      SKX_EXT_B_BGA1-IC,TBD
M_B_DQS_DP<0>            J4G2             153      SCONN288_H44441004_PIP-SCONN,HA
M_B_DQS_DP<0>            J6U1             153      SCONN288_H44441003_PIP-SCONN,HA
M_B_DQS_DP<0>            U5D1             AR80     SKX_EXT_B_BGA1-IC,TBD
M_B_DQS_DP<1>            J4G2             164      SCONN288_H44441004_PIP-SCONN,HA
M_B_DQS_DP<1>            J6U1             164      SCONN288_H44441003_PIP-SCONN,HA
M_B_DQS_DP<1>            U5D1             AE80     SKX_EXT_B_BGA1-IC,TBD
M_B_DQS_DP<2>            J4G2             175      SCONN288_H44441004_PIP-SCONN,HA
M_B_DQS_DP<2>            J6U1             175      SCONN288_H44441003_PIP-SCONN,HA
M_B_DQS_DP<2>            U5D1             H79      SKX_EXT_B_BGA1-IC,TBD
M_B_DQS_DP<3>            J4G2             186      SCONN288_H44441004_PIP-SCONN,HA
M_B_DQS_DP<3>            J6U1             186      SCONN288_H44441003_PIP-SCONN,HA
M_B_DQS_DP<3>            U5D1             F73      SKX_EXT_B_BGA1-IC,TBD
M_B_DQS_DP<4>            J4G2             245      SCONN288_H44441004_PIP-SCONN,HA
M_B_DQS_DP<4>            J6U1             245      SCONN288_H44441003_PIP-SCONN,HA
M_B_DQS_DP<4>            U5D1             R42      SKX_EXT_B_BGA1-IC,TBD
M_B_DQS_DP<5>            J4G2             256      SCONN288_H44441004_PIP-SCONN,HA
M_B_DQS_DP<5>            J6U1             256      SCONN288_H44441003_PIP-SCONN,HA
M_B_DQS_DP<5>            U5D1             E34      SKX_EXT_B_BGA1-IC,TBD
M_B_DQS_DP<6>            J4G2             267      SCONN288_H44441004_PIP-SCONN,HA
M_B_DQS_DP<6>            J6U1             267      SCONN288_H44441003_PIP-SCONN,HA
M_B_DQS_DP<6>            U5D1             E28      SKX_EXT_B_BGA1-IC,TBD
M_B_DQS_DP<7>            J4G2             278      SCONN288_H44441004_PIP-SCONN,HA
M_B_DQS_DP<7>            J6U1             278      SCONN288_H44441003_PIP-SCONN,HA
M_B_DQS_DP<7>            U5D1             Y27      SKX_EXT_B_BGA1-IC,TBD
M_B_DQS_DP<8>            J4G2             197      SCONN288_H44441004_PIP-SCONN,HA
M_B_DQS_DP<8>            J6U1             197      SCONN288_H44441003_PIP-SCONN,HA
M_B_DQS_DP<8>            U5D1             L68      SKX_EXT_B_BGA1-IC,TBD
M_B_DQS_DP<9>            J4G2             7        SCONN288_H44441004_PIP-SCONN,HA
M_B_DQS_DP<9>            J6U1             7        SCONN288_H44441003_PIP-SCONN,HA
M_B_DQS_DP<9>            U5D1             AT81     SKX_EXT_B_BGA1-IC,TBD
M_B_DQS_DP<10>           J4G2             18       SCONN288_H44441004_PIP-SCONN,HA
M_B_DQS_DP<10>           J6U1             18       SCONN288_H44441003_PIP-SCONN,HA
M_B_DQS_DP<10>           U5D1             AF81     SKX_EXT_B_BGA1-IC,TBD
M_B_DQS_DP<11>           J4G2             29       SCONN288_H44441004_PIP-SCONN,HA
M_B_DQS_DP<11>           J6U1             29       SCONN288_H44441003_PIP-SCONN,HA
M_B_DQS_DP<11>           U5D1             F79      SKX_EXT_B_BGA1-IC,TBD
M_B_DQS_DP<12>           J4G2             40       SCONN288_H44441004_PIP-SCONN,HA
M_B_DQS_DP<12>           J6U1             40       SCONN288_H44441003_PIP-SCONN,HA
M_B_DQS_DP<12>           U5D1             D73      SKX_EXT_B_BGA1-IC,TBD
M_B_DQS_DP<13>           J4G2             99       SCONN288_H44441004_PIP-SCONN,HA
M_B_DQS_DP<13>           J6U1             99       SCONN288_H44441003_PIP-SCONN,HA
M_B_DQS_DP<13>           U5D1             L42      SKX_EXT_B_BGA1-IC,TBD
M_B_DQS_DP<14>           J4G2             110      SCONN288_H44441004_PIP-SCONN,HA
M_B_DQS_DP<14>           J6U1             110      SCONN288_H44441003_PIP-SCONN,HA
M_B_DQS_DP<14>           U5D1             C34      SKX_EXT_B_BGA1-IC,TBD
M_B_DQS_DP<15>           J4G2             121      SCONN288_H44441004_PIP-SCONN,HA
M_B_DQS_DP<15>           J6U1             121      SCONN288_H44441003_PIP-SCONN,HA
M_B_DQS_DP<15>           U5D1             C28      SKX_EXT_B_BGA1-IC,TBD
M_B_DQS_DP<16>           J4G2             132      SCONN288_H44441004_PIP-SCONN,HA
M_B_DQS_DP<16>           J6U1             132      SCONN288_H44441003_PIP-SCONN,HA
M_B_DQS_DP<16>           U5D1             V27      SKX_EXT_B_BGA1-IC,TBD
M_B_DQS_DP<17>           J4G2             51       SCONN288_H44441004_PIP-SCONN,HA
M_B_DQS_DP<17>           J6U1             51       SCONN288_H44441003_PIP-SCONN,HA
M_B_DQS_DP<17>           U5D1             J68      SKX_EXT_B_BGA1-IC,TBD
M_B_ECC<0>               J4G2             194      SCONN288_H44441004_PIP-SCONN,HA
M_B_ECC<0>               J6U1             49       SCONN288_H44441003_PIP-SCONN,HA
M_B_ECC<0>               U5D1             J70      SKX_EXT_B_BGA1-IC,TBD
M_B_ECC<1>               J4G2             49       SCONN288_H44441004_PIP-SCONN,HA
M_B_ECC<1>               J6U1             194      SCONN288_H44441003_PIP-SCONN,HA
M_B_ECC<1>               U5D1             H69      SKX_EXT_B_BGA1-IC,TBD
M_B_ECC<2>               J4G2             201      SCONN288_H44441004_PIP-SCONN,HA
M_B_ECC<2>               J6U1             56       SCONN288_H44441003_PIP-SCONN,HA
M_B_ECC<2>               U5D1             J66      SKX_EXT_B_BGA1-IC,TBD
M_B_ECC<3>               J4G2             56       SCONN288_H44441004_PIP-SCONN,HA
M_B_ECC<3>               J6U1             201      SCONN288_H44441003_PIP-SCONN,HA
M_B_ECC<3>               U5D1             L66      SKX_EXT_B_BGA1-IC,TBD
M_B_ECC<4>               J4G2             192      SCONN288_H44441004_PIP-SCONN,HA
M_B_ECC<4>               J6U1             47       SCONN288_H44441003_PIP-SCONN,HA
M_B_ECC<4>               U5D1             L70      SKX_EXT_B_BGA1-IC,TBD
M_B_ECC<5>               J4G2             47       SCONN288_H44441004_PIP-SCONN,HA
M_B_ECC<5>               J6U1             192      SCONN288_H44441003_PIP-SCONN,HA
M_B_ECC<5>               U5D1             M69      SKX_EXT_B_BGA1-IC,TBD
M_B_ECC<6>               J4G2             199      SCONN288_H44441004_PIP-SCONN,HA
M_B_ECC<6>               J6U1             54       SCONN288_H44441003_PIP-SCONN,HA
M_B_ECC<6>               U5D1             H67      SKX_EXT_B_BGA1-IC,TBD
M_B_ECC<7>               J4G2             54       SCONN288_H44441004_PIP-SCONN,HA
M_B_ECC<7>               J6U1             199      SCONN288_H44441003_PIP-SCONN,HA
M_B_ECC<7>               U5D1             M67      SKX_EXT_B_BGA1-IC,TBD
M_B_MA<0>                J4G2             79       SCONN288_H44441004_PIP-SCONN,HA
M_B_MA<0>                J6U1             79       SCONN288_H44441003_PIP-SCONN,HA
M_B_MA<0>                U5D1             J52      SKX_EXT_B_BGA1-IC,TBD
M_B_MA<1>                J4G2             72       SCONN288_H44441004_PIP-SCONN,HA
M_B_MA<1>                J6U1             72       SCONN288_H44441003_PIP-SCONN,HA
M_B_MA<1>                U5D1             J58      SKX_EXT_B_BGA1-IC,TBD
M_B_MA<2>                J4G2             216      SCONN288_H44441004_PIP-SCONN,HA
M_B_MA<2>                J6U1             216      SCONN288_H44441003_PIP-SCONN,HA
M_B_MA<2>                U5D1             K57      SKX_EXT_B_BGA1-IC,TBD
M_B_MA<3>                J4G2             71       SCONN288_H44441004_PIP-SCONN,HA
M_B_MA<3>                J6U1             71       SCONN288_H44441003_PIP-SCONN,HA
M_B_MA<3>                U5D1             N58      SKX_EXT_B_BGA1-IC,TBD
M_B_MA<4>                J4G2             214      SCONN288_H44441004_PIP-SCONN,HA
M_B_MA<4>                J6U1             214      SCONN288_H44441003_PIP-SCONN,HA
M_B_MA<4>                U5D1             M59      SKX_EXT_B_BGA1-IC,TBD
M_B_MA<5>                J4G2             213      SCONN288_H44441004_PIP-SCONN,HA
M_B_MA<5>                J6U1             213      SCONN288_H44441003_PIP-SCONN,HA
M_B_MA<5>                U5D1             R58      SKX_EXT_B_BGA1-IC,TBD
M_B_MA<6>                J4G2             69       SCONN288_H44441004_PIP-SCONN,HA
M_B_MA<6>                J6U1             69       SCONN288_H44441003_PIP-SCONN,HA
M_B_MA<6>                U5D1             T59      SKX_EXT_B_BGA1-IC,TBD
M_B_MA<7>                J4G2             211      SCONN288_H44441004_PIP-SCONN,HA
M_B_MA<7>                J6U1             211      SCONN288_H44441003_PIP-SCONN,HA
M_B_MA<7>                U5D1             V61      SKX_EXT_B_BGA1-IC,TBD
M_B_MA<8>                J4G2             68       SCONN288_H44441004_PIP-SCONN,HA
M_B_MA<8>                J6U1             68       SCONN288_H44441003_PIP-SCONN,HA
M_B_MA<8>                U5D1             W60      SKX_EXT_B_BGA1-IC,TBD
M_B_MA<9>                J4G2             66       SCONN288_H44441004_PIP-SCONN,HA
M_B_MA<9>                J6U1             66       SCONN288_H44441003_PIP-SCONN,HA
M_B_MA<9>                U5D1             K59      SKX_EXT_B_BGA1-IC,TBD
M_B_MA<10>               J4G2             225      SCONN288_H44441004_PIP-SCONN,HA
M_B_MA<10>               J6U1             225      SCONN288_H44441003_PIP-SCONN,HA
M_B_MA<10>               U5D1             M55      SKX_EXT_B_BGA1-IC,TBD
M_B_MA<11>               J4G2             210      SCONN288_H44441004_PIP-SCONN,HA
M_B_MA<11>               J6U1             210      SCONN288_H44441003_PIP-SCONN,HA
M_B_MA<11>               U5D1             R60      SKX_EXT_B_BGA1-IC,TBD
M_B_MA<12>               J4G2             65       SCONN288_H44441004_PIP-SCONN,HA
M_B_MA<12>               J6U1             65       SCONN288_H44441003_PIP-SCONN,HA
M_B_MA<12>               U5D1             T61      SKX_EXT_B_BGA1-IC,TBD
M_B_MA<13>               J4G2             232      SCONN288_H44441004_PIP-SCONN,HA
M_B_MA<13>               J6U1             232      SCONN288_H44441003_PIP-SCONN,HA
M_B_MA<13>               U5D1             M51      SKX_EXT_B_BGA1-IC,TBD
M_B_MA<14>               J4G2             228      SCONN288_H44441004_PIP-SCONN,HA
M_B_MA<14>               J6U1             228      SCONN288_H44441003_PIP-SCONN,HA
M_B_MA<14>               U5D1             T51      SKX_EXT_B_BGA1-IC,TBD
M_B_MA<15>               J4G2             86       SCONN288_H44441004_PIP-SCONN,HA
M_B_MA<15>               J6U1             86       SCONN288_H44441003_PIP-SCONN,HA
M_B_MA<15>               U5D1             N52      SKX_EXT_B_BGA1-IC,TBD
M_B_MA<16>               J4G2             82       SCONN288_H44441004_PIP-SCONN,HA
M_B_MA<16>               J6U1             82       SCONN288_H44441003_PIP-SCONN,HA
M_B_MA<16>               U5D1             R52      SKX_EXT_B_BGA1-IC,TBD
M_B_MA<17>               J4G2             234      SCONN288_H44441004_PIP-SCONN,HA
M_B_MA<17>               J6U1             234      SCONN288_H44441003_PIP-SCONN,HA
M_B_MA<17>               U5D1             N48      SKX_EXT_B_BGA1-IC,TBD
M_B_ODT<0>               J4G2             87       SCONN288_H44441004_PIP-SCONN,HA
M_B_ODT<0>               U5D1             N50      SKX_EXT_B_BGA1-IC,TBD
M_B_ODT<1>               J4G2             91       SCONN288_H44441004_PIP-SCONN,HA
M_B_ODT<1>               U5D1             R48      SKX_EXT_B_BGA1-IC,TBD
M_B_ODT<2>               J6U1             87       SCONN288_H44441003_PIP-SCONN,HA
M_B_ODT<2>               U5D1             M49      SKX_EXT_B_BGA1-IC,TBD
M_B_ODT<3>               J6U1             91       SCONN288_H44441003_PIP-SCONN,HA
M_B_ODT<3>               U5D1             T47      SKX_EXT_B_BGA1-IC,TBD
M_B_PAR                  J4G2             222      SCONN288_H44441004_PIP-SCONN,HA
M_B_PAR                  J6U1             222      SCONN288_H44441003_PIP-SCONN,HA
M_B_PAR                  U5D1             K53      SKX_EXT_B_BGA1-IC,TBD
M_B_VREF                 C4G3             1        CAP_A_0402V-0.01UF,25V,10%,X7RA
M_B_VREF                 C6U9             1        CAP_A_0402V-0.01UF,25V,10%,X7RA
M_B_VREF                 J4G2             146      SCONN288_H44441004_PIP-SCONN,HA
M_B_VREF                 J6U1             146      SCONN288_H44441003_PIP-SCONN,HA
M_B_VREF                 R4G1             2        RES_0402-2,1.0%,1/16W,CHIP,G21A
M_B_VREF                 R4G2             2        RES_0402-1.00K,1%,1/16W,CHIP,GA
M_B_VREF                 R4G3             1        RES_0402-1.00K,1%,1/16W,CHIP,GA
M_C_ACT_N                J4G3             62       SCONN288_H44441004_PIP-SCONN,HA
M_C_ACT_N                J6U2             62       SCONN288_H44441003_PIP-SCONN,HA
M_C_ACT_N                U5D1             AB61     SKX_EXT_B_BGA1-IC,TBD
M_C_ALERT_N              J4G3             208      SCONN288_H44441004_PIP-SCONN,HA
M_C_ALERT_N              J6U2             208      SCONN288_H44441003_PIP-SCONN,HA
M_C_ALERT_N              U5D1             AD61     SKX_EXT_B_BGA1-IC,TBD
M_C_BA<0>                J4G3             81       SCONN288_H44441004_PIP-SCONN,HA
M_C_BA<0>                J6U2             81       SCONN288_H44441003_PIP-SCONN,HA
M_C_BA<0>                U5D1             W52      SKX_EXT_B_BGA1-IC,TBD
M_C_BA<1>                J4G3             224      SCONN288_H44441004_PIP-SCONN,HA
M_C_BA<1>                J6U2             224      SCONN288_H44441003_PIP-SCONN,HA
M_C_BA<1>                U5D1             AE56     SKX_EXT_B_BGA1-IC,TBD
M_C_BG<0>                J4G3             63       SCONN288_H44441004_PIP-SCONN,HA
M_C_BG<0>                J6U2             63       SCONN288_H44441003_PIP-SCONN,HA
M_C_BG<0>                U5D1             AA60     SKX_EXT_B_BGA1-IC,TBD
M_C_BG<1>                J4G3             207      SCONN288_H44441004_PIP-SCONN,HA
M_C_BG<1>                J6U2             207      SCONN288_H44441003_PIP-SCONN,HA
M_C_BG<1>                U5D1             AE62     SKX_EXT_B_BGA1-IC,TBD
M_C_C<2>                 J4G3             235      SCONN288_H44441004_PIP-SCONN,HA
M_C_C<2>                 J6U2             235      SCONN288_H44441003_PIP-SCONN,HA
M_C_C<2>                 U5D1             AB45     SKX_EXT_B_BGA1-IC,TBD
M_C_CKE<0>               J4G3             60       SCONN288_H44441004_PIP-SCONN,HA
M_C_CKE<0>               U5D1             AA62     SKX_EXT_B_BGA1-IC,TBD
M_C_CKE<1>               J4G3             203      SCONN288_H44441004_PIP-SCONN,HA
M_C_CKE<1>               U5D1             AD63     SKX_EXT_B_BGA1-IC,TBD
M_C_CKE<2>               J6U2             60       SCONN288_H44441003_PIP-SCONN,HA
M_C_CKE<2>               U5D1             V63      SKX_EXT_B_BGA1-IC,TBD
M_C_CKE<3>               J6U2             203      SCONN288_H44441003_PIP-SCONN,HA
M_C_CKE<3>               U5D1             AB63     SKX_EXT_B_BGA1-IC,TBD
M_C_CLK_DN<0>            J4G3             75       SCONN288_H44441004_PIP-SCONN,HA
M_C_CLK_DN<0>            U5D1             AA54     SKX_EXT_B_BGA1-IC,TBD
M_C_CLK_DN<1>            J4G3             219      SCONN288_H44441004_PIP-SCONN,HA
M_C_CLK_DN<1>            U5D1             W54      SKX_EXT_B_BGA1-IC,TBD
M_C_CLK_DN<2>            J6U2             75       SCONN288_H44441003_PIP-SCONN,HA
M_C_CLK_DN<2>            U5D1             AA56     SKX_EXT_B_BGA1-IC,TBD
M_C_CLK_DN<3>            J6U2             219      SCONN288_H44441003_PIP-SCONN,HA
M_C_CLK_DN<3>            U5D1             W56      SKX_EXT_B_BGA1-IC,TBD
M_C_CLK_DP<0>            J4G3             74       SCONN288_H44441004_PIP-SCONN,HA
M_C_CLK_DP<0>            U5D1             AB55     SKX_EXT_B_BGA1-IC,TBD
M_C_CLK_DP<1>            J4G3             218      SCONN288_H44441004_PIP-SCONN,HA
M_C_CLK_DP<1>            U5D1             V55      SKX_EXT_B_BGA1-IC,TBD
M_C_CLK_DP<2>            J6U2             74       SCONN288_H44441003_PIP-SCONN,HA
M_C_CLK_DP<2>            U5D1             AB57     SKX_EXT_B_BGA1-IC,TBD
M_C_CLK_DP<3>            J6U2             218      SCONN288_H44441003_PIP-SCONN,HA
M_C_CLK_DP<3>            U5D1             V57      SKX_EXT_B_BGA1-IC,TBD
M_C_CPU_VREF             C4G17            1        CAP_A_0402V-0.01UF,25V,10%,X7RA
M_C_CPU_VREF             R4G20            1        RES_0402-2,1.0%,1/16W,CHIP,G21A
M_C_CPU_VREF             U5D1             AH63     SKX_EXT_B_BGA1-IC,TBD
M_C_CS_N<0>              J4G3             84       SCONN288_H44441004_PIP-SCONN,HA
M_C_CS_N<0>              U5D1             V51      SKX_EXT_B_BGA1-IC,TBD
M_C_CS_N<1>              J4G3             89       SCONN288_H44441004_PIP-SCONN,HA
M_C_CS_N<1>              U5D1             AB49     SKX_EXT_B_BGA1-IC,TBD
M_C_CS_N<2>              J4G3             93       SCONN288_H44441004_PIP-SCONN,HA
M_C_CS_N<2>              U5D1             W46      SKX_EXT_B_BGA1-IC,TBD
M_C_CS_N<3>              J4G3             237      SCONN288_H44441004_PIP-SCONN,HA
M_C_CS_N<3>              U5D1             AA46     SKX_EXT_B_BGA1-IC,TBD
M_C_CS_N<4>              J6U2             84       SCONN288_H44441003_PIP-SCONN,HA
M_C_CS_N<4>              U5D1             AB51     SKX_EXT_B_BGA1-IC,TBD
M_C_CS_N<5>              J6U2             89       SCONN288_H44441003_PIP-SCONN,HA
M_C_CS_N<5>              U5D1             W48      SKX_EXT_B_BGA1-IC,TBD
M_C_CS_N<6>              J6U2             93       SCONN288_H44441003_PIP-SCONN,HA
M_C_CS_N<6>              U5D1             T45      SKX_EXT_B_BGA1-IC,TBD
M_C_CS_N<7>              J6U2             237      SCONN288_H44441003_PIP-SCONN,HA
M_C_CS_N<7>              U5D1             V45      SKX_EXT_B_BGA1-IC,TBD
M_C_DQ<0>                J4G3             150      SCONN288_H44441004_PIP-SCONN,HA
M_C_DQ<0>                J6U2             5        SCONN288_H44441003_PIP-SCONN,HA
M_C_DQ<0>                U5D1             AR76     SKX_EXT_B_BGA1-IC,TBD
M_C_DQ<1>                J4G3             5        SCONN288_H44441004_PIP-SCONN,HA
M_C_DQ<1>                J6U2             150      SCONN288_H44441003_PIP-SCONN,HA
M_C_DQ<1>                U5D1             AN74     SKX_EXT_B_BGA1-IC,TBD
M_C_DQ<2>                J4G3             157      SCONN288_H44441004_PIP-SCONN,HA
M_C_DQ<2>                J6U2             12       SCONN288_H44441003_PIP-SCONN,HA
M_C_DQ<2>                U5D1             AK77     SKX_EXT_B_BGA1-IC,TBD
M_C_DQ<3>                J4G3             12       SCONN288_H44441004_PIP-SCONN,HA
M_C_DQ<3>                J6U2             157      SCONN288_H44441003_PIP-SCONN,HA
M_C_DQ<3>                U5D1             AJ76     SKX_EXT_B_BGA1-IC,TBD
M_C_DQ<4>                J4G3             148      SCONN288_H44441004_PIP-SCONN,HA
M_C_DQ<4>                J6U2             3        SCONN288_H44441003_PIP-SCONN,HA
M_C_DQ<4>                U5D1             AT75     SKX_EXT_B_BGA1-IC,TBD
M_C_DQ<5>                J4G3             3        SCONN288_H44441004_PIP-SCONN,HA
M_C_DQ<5>                J6U2             148      SCONN288_H44441003_PIP-SCONN,HA
M_C_DQ<5>                U5D1             AR74     SKX_EXT_B_BGA1-IC,TBD
M_C_DQ<6>                J4G3             155      SCONN288_H44441004_PIP-SCONN,HA
M_C_DQ<6>                J6U2             10       SCONN288_H44441003_PIP-SCONN,HA
M_C_DQ<6>                U5D1             AM77     SKX_EXT_B_BGA1-IC,TBD
M_C_DQ<7>                J4G3             10       SCONN288_H44441004_PIP-SCONN,HA
M_C_DQ<7>                J6U2             155      SCONN288_H44441003_PIP-SCONN,HA
M_C_DQ<7>                U5D1             AK75     SKX_EXT_B_BGA1-IC,TBD
M_C_DQ<8>                J4G3             161      SCONN288_H44441004_PIP-SCONN,HA
M_C_DQ<8>                J6U2             16       SCONN288_H44441003_PIP-SCONN,HA
M_C_DQ<8>                U5D1             AE76     SKX_EXT_B_BGA1-IC,TBD
M_C_DQ<9>                J4G3             16       SCONN288_H44441004_PIP-SCONN,HA
M_C_DQ<9>                J6U2             161      SCONN288_H44441003_PIP-SCONN,HA
M_C_DQ<9>                U5D1             AC74     SKX_EXT_B_BGA1-IC,TBD
M_C_DQ<10>               J4G3             168      SCONN288_H44441004_PIP-SCONN,HA
M_C_DQ<10>               J6U2             23       SCONN288_H44441003_PIP-SCONN,HA
M_C_DQ<10>               U5D1             Y77      SKX_EXT_B_BGA1-IC,TBD
M_C_DQ<11>               J4G3             23       SCONN288_H44441004_PIP-SCONN,HA
M_C_DQ<11>               J6U2             168      SCONN288_H44441003_PIP-SCONN,HA
M_C_DQ<11>               U5D1             W76      SKX_EXT_B_BGA1-IC,TBD
M_C_DQ<12>               J4G3             159      SCONN288_H44441004_PIP-SCONN,HA
M_C_DQ<12>               J6U2             14       SCONN288_H44441003_PIP-SCONN,HA
M_C_DQ<12>               U5D1             AF75     SKX_EXT_B_BGA1-IC,TBD
M_C_DQ<13>               J4G3             14       SCONN288_H44441004_PIP-SCONN,HA
M_C_DQ<13>               J6U2             159      SCONN288_H44441003_PIP-SCONN,HA
M_C_DQ<13>               U5D1             AE74     SKX_EXT_B_BGA1-IC,TBD
M_C_DQ<14>               J4G3             166      SCONN288_H44441004_PIP-SCONN,HA
M_C_DQ<14>               J6U2             21       SCONN288_H44441003_PIP-SCONN,HA
M_C_DQ<14>               U5D1             AB77     SKX_EXT_B_BGA1-IC,TBD
M_C_DQ<15>               J4G3             21       SCONN288_H44441004_PIP-SCONN,HA
M_C_DQ<15>               J6U2             166      SCONN288_H44441003_PIP-SCONN,HA
M_C_DQ<15>               U5D1             Y75      SKX_EXT_B_BGA1-IC,TBD
M_C_DQ<16>               J4G3             172      SCONN288_H44441004_PIP-SCONN,HA
M_C_DQ<16>               J6U2             27       SCONN288_H44441003_PIP-SCONN,HA
M_C_DQ<16>               U5D1             W72      SKX_EXT_B_BGA1-IC,TBD
M_C_DQ<17>               J4G3             27       SCONN288_H44441004_PIP-SCONN,HA
M_C_DQ<17>               J6U2             172      SCONN288_H44441003_PIP-SCONN,HA
M_C_DQ<17>               U5D1             AA70     SKX_EXT_B_BGA1-IC,TBD
M_C_DQ<18>               J4G3             179      SCONN288_H44441004_PIP-SCONN,HA
M_C_DQ<18>               J6U2             34       SCONN288_H44441003_PIP-SCONN,HA
M_C_DQ<18>               U5D1             R70      SKX_EXT_B_BGA1-IC,TBD
M_C_DQ<19>               J4G3             34       SCONN288_H44441004_PIP-SCONN,HA
M_C_DQ<19>               J6U2             179      SCONN288_H44441003_PIP-SCONN,HA
M_C_DQ<19>               U5D1             T69      SKX_EXT_B_BGA1-IC,TBD
M_C_DQ<20>               J4G3             170      SCONN288_H44441004_PIP-SCONN,HA
M_C_DQ<20>               J6U2             25       SCONN288_H44441003_PIP-SCONN,HA
M_C_DQ<20>               U5D1             AA72     SKX_EXT_B_BGA1-IC,TBD
M_C_DQ<21>               J4G3             25       SCONN288_H44441004_PIP-SCONN,HA
M_C_DQ<21>               J6U2             170      SCONN288_H44441003_PIP-SCONN,HA
M_C_DQ<21>               U5D1             AB71     SKX_EXT_B_BGA1-IC,TBD
M_C_DQ<22>               J4G3             177      SCONN288_H44441004_PIP-SCONN,HA
M_C_DQ<22>               J6U2             32       SCONN288_H44441003_PIP-SCONN,HA
M_C_DQ<22>               U5D1             T71      SKX_EXT_B_BGA1-IC,TBD
M_C_DQ<23>               J4G3             32       SCONN288_H44441004_PIP-SCONN,HA
M_C_DQ<23>               J6U2             177      SCONN288_H44441003_PIP-SCONN,HA
M_C_DQ<23>               U5D1             V69      SKX_EXT_B_BGA1-IC,TBD
M_C_DQ<24>               J4G3             183      SCONN288_H44441004_PIP-SCONN,HA
M_C_DQ<24>               J6U2             38       SCONN288_H44441003_PIP-SCONN,HA
M_C_DQ<24>               U5D1             AM67     SKX_EXT_B_BGA1-IC,TBD
M_C_DQ<25>               J4G3             38       SCONN288_H44441004_PIP-SCONN,HA
M_C_DQ<25>               J6U2             183      SCONN288_H44441003_PIP-SCONN,HA
M_C_DQ<25>               U5D1             AT67     SKX_EXT_B_BGA1-IC,TBD
M_C_DQ<26>               J4G3             190      SCONN288_H44441004_PIP-SCONN,HA
M_C_DQ<26>               J6U2             45       SCONN288_H44441003_PIP-SCONN,HA
M_C_DQ<26>               U5D1             AN64     SKX_EXT_B_BGA1-IC,TBD
M_C_DQ<27>               J4G3             45       SCONN288_H44441004_PIP-SCONN,HA
M_C_DQ<27>               J6U2             190      SCONN288_H44441003_PIP-SCONN,HA
M_C_DQ<27>               U5D1             AR64     SKX_EXT_B_BGA1-IC,TBD
M_C_DQ<28>               J4G3             181      SCONN288_H44441004_PIP-SCONN,HA
M_C_DQ<28>               J6U2             36       SCONN288_H44441003_PIP-SCONN,HA
M_C_DQ<28>               U5D1             AN68     SKX_EXT_B_BGA1-IC,TBD
M_C_DQ<29>               J4G3             36       SCONN288_H44441004_PIP-SCONN,HA
M_C_DQ<29>               J6U2             181      SCONN288_H44441003_PIP-SCONN,HA
M_C_DQ<29>               U5D1             AR68     SKX_EXT_B_BGA1-IC,TBD
M_C_DQ<30>               J4G3             188      SCONN288_H44441004_PIP-SCONN,HA
M_C_DQ<30>               J6U2             43       SCONN288_H44441003_PIP-SCONN,HA
M_C_DQ<30>               U5D1             AM65     SKX_EXT_B_BGA1-IC,TBD
M_C_DQ<31>               J4G3             43       SCONN288_H44441004_PIP-SCONN,HA
M_C_DQ<31>               J6U2             188      SCONN288_H44441003_PIP-SCONN,HA
M_C_DQ<31>               U5D1             AT65     SKX_EXT_B_BGA1-IC,TBD
M_C_DQ<32>               J4G3             242      SCONN288_H44441004_PIP-SCONN,HA
M_C_DQ<32>               J6U2             97       SCONN288_H44441003_PIP-SCONN,HA
M_C_DQ<32>               U5D1             U40      SKX_EXT_B_BGA1-IC,TBD
M_C_DQ<33>               J4G3             97       SCONN288_H44441004_PIP-SCONN,HA
M_C_DQ<33>               J6U2             242      SCONN288_H44441003_PIP-SCONN,HA
M_C_DQ<33>               U5D1             AA40     SKX_EXT_B_BGA1-IC,TBD
M_C_DQ<34>               J4G3             249      SCONN288_H44441004_PIP-SCONN,HA
M_C_DQ<34>               J6U2             104      SCONN288_H44441003_PIP-SCONN,HA
M_C_DQ<34>               U5D1             V37      SKX_EXT_B_BGA1-IC,TBD
M_C_DQ<35>               J4G3             104      SCONN288_H44441004_PIP-SCONN,HA
M_C_DQ<35>               J6U2             249      SCONN288_H44441003_PIP-SCONN,HA
M_C_DQ<35>               U5D1             Y37      SKX_EXT_B_BGA1-IC,TBD
M_C_DQ<36>               J4G3             240      SCONN288_H44441004_PIP-SCONN,HA
M_C_DQ<36>               J6U2             95       SCONN288_H44441003_PIP-SCONN,HA
M_C_DQ<36>               U5D1             V41      SKX_EXT_B_BGA1-IC,TBD
M_C_DQ<37>               J4G3             95       SCONN288_H44441004_PIP-SCONN,HA
M_C_DQ<37>               J6U2             240      SCONN288_H44441003_PIP-SCONN,HA
M_C_DQ<37>               U5D1             Y41      SKX_EXT_B_BGA1-IC,TBD
M_C_DQ<38>               J4G3             247      SCONN288_H44441004_PIP-SCONN,HA
M_C_DQ<38>               J6U2             102      SCONN288_H44441003_PIP-SCONN,HA
M_C_DQ<38>               U5D1             U38      SKX_EXT_B_BGA1-IC,TBD
M_C_DQ<39>               J4G3             102      SCONN288_H44441004_PIP-SCONN,HA
M_C_DQ<39>               J6U2             247      SCONN288_H44441003_PIP-SCONN,HA
M_C_DQ<39>               U5D1             AA38     SKX_EXT_B_BGA1-IC,TBD
M_C_DQ<40>               J4G3             253      SCONN288_H44441004_PIP-SCONN,HA
M_C_DQ<40>               J6U2             108      SCONN288_H44441003_PIP-SCONN,HA
M_C_DQ<40>               U5D1             U34      SKX_EXT_B_BGA1-IC,TBD
M_C_DQ<41>               J4G3             108      SCONN288_H44441004_PIP-SCONN,HA
M_C_DQ<41>               J6U2             253      SCONN288_H44441003_PIP-SCONN,HA
M_C_DQ<41>               U5D1             AA34     SKX_EXT_B_BGA1-IC,TBD
M_C_DQ<42>               J4G3             260      SCONN288_H44441004_PIP-SCONN,HA
M_C_DQ<42>               J6U2             115      SCONN288_H44441003_PIP-SCONN,HA
M_C_DQ<42>               U5D1             V31      SKX_EXT_B_BGA1-IC,TBD
M_C_DQ<43>               J4G3             115      SCONN288_H44441004_PIP-SCONN,HA
M_C_DQ<43>               J6U2             260      SCONN288_H44441003_PIP-SCONN,HA
M_C_DQ<43>               U5D1             Y31      SKX_EXT_B_BGA1-IC,TBD
M_C_DQ<44>               J4G3             251      SCONN288_H44441004_PIP-SCONN,HA
M_C_DQ<44>               J6U2             106      SCONN288_H44441003_PIP-SCONN,HA
M_C_DQ<44>               U5D1             V35      SKX_EXT_B_BGA1-IC,TBD
M_C_DQ<45>               J4G3             106      SCONN288_H44441004_PIP-SCONN,HA
M_C_DQ<45>               J6U2             251      SCONN288_H44441003_PIP-SCONN,HA
M_C_DQ<45>               U5D1             Y35      SKX_EXT_B_BGA1-IC,TBD
M_C_DQ<46>               J4G3             258      SCONN288_H44441004_PIP-SCONN,HA
M_C_DQ<46>               J6U2             113      SCONN288_H44441003_PIP-SCONN,HA
M_C_DQ<46>               U5D1             U32      SKX_EXT_B_BGA1-IC,TBD
M_C_DQ<47>               J4G3             113      SCONN288_H44441004_PIP-SCONN,HA
M_C_DQ<47>               J6U2             258      SCONN288_H44441003_PIP-SCONN,HA
M_C_DQ<47>               U5D1             AA32     SKX_EXT_B_BGA1-IC,TBD
M_C_DQ<48>               J4G3             264      SCONN288_H44441004_PIP-SCONN,HA
M_C_DQ<48>               J6U2             119      SCONN288_H44441003_PIP-SCONN,HA
M_C_DQ<48>               U5D1             AD31     SKX_EXT_B_BGA1-IC,TBD
M_C_DQ<49>               J4G3             119      SCONN288_H44441004_PIP-SCONN,HA
M_C_DQ<49>               J6U2             264      SCONN288_H44441003_PIP-SCONN,HA
M_C_DQ<49>               U5D1             AH31     SKX_EXT_B_BGA1-IC,TBD
M_C_DQ<50>               J4G3             271      SCONN288_H44441004_PIP-SCONN,HA
M_C_DQ<50>               J6U2             126      SCONN288_H44441003_PIP-SCONN,HA
M_C_DQ<50>               U5D1             AE28     SKX_EXT_B_BGA1-IC,TBD
M_C_DQ<51>               J4G3             126      SCONN288_H44441004_PIP-SCONN,HA
M_C_DQ<51>               J6U2             271      SCONN288_H44441003_PIP-SCONN,HA
M_C_DQ<51>               U5D1             AG28     SKX_EXT_B_BGA1-IC,TBD
M_C_DQ<52>               J4G3             262      SCONN288_H44441004_PIP-SCONN,HA
M_C_DQ<52>               J6U2             117      SCONN288_H44441003_PIP-SCONN,HA
M_C_DQ<52>               U5D1             AE32     SKX_EXT_B_BGA1-IC,TBD
M_C_DQ<53>               J4G3             117      SCONN288_H44441004_PIP-SCONN,HA
M_C_DQ<53>               J6U2             262      SCONN288_H44441003_PIP-SCONN,HA
M_C_DQ<53>               U5D1             AG32     SKX_EXT_B_BGA1-IC,TBD
M_C_DQ<54>               J4G3             269      SCONN288_H44441004_PIP-SCONN,HA
M_C_DQ<54>               J6U2             124      SCONN288_H44441003_PIP-SCONN,HA
M_C_DQ<54>               U5D1             AD29     SKX_EXT_B_BGA1-IC,TBD
M_C_DQ<55>               J4G3             124      SCONN288_H44441004_PIP-SCONN,HA
M_C_DQ<55>               J6U2             269      SCONN288_H44441003_PIP-SCONN,HA
M_C_DQ<55>               U5D1             AH29     SKX_EXT_B_BGA1-IC,TBD
M_C_DQ<56>               J4G3             275      SCONN288_H44441004_PIP-SCONN,HA
M_C_DQ<56>               J6U2             130      SCONN288_H44441003_PIP-SCONN,HA
M_C_DQ<56>               U5D1             AD25     SKX_EXT_B_BGA1-IC,TBD
M_C_DQ<57>               J4G3             130      SCONN288_H44441004_PIP-SCONN,HA
M_C_DQ<57>               J6U2             275      SCONN288_H44441003_PIP-SCONN,HA
M_C_DQ<57>               U5D1             AH25     SKX_EXT_B_BGA1-IC,TBD
M_C_DQ<58>               J4G3             282      SCONN288_H44441004_PIP-SCONN,HA
M_C_DQ<58>               J6U2             137      SCONN288_H44441003_PIP-SCONN,HA
M_C_DQ<58>               U5D1             AE22     SKX_EXT_B_BGA1-IC,TBD
M_C_DQ<59>               J4G3             137      SCONN288_H44441004_PIP-SCONN,HA
M_C_DQ<59>               J6U2             282      SCONN288_H44441003_PIP-SCONN,HA
M_C_DQ<59>               U5D1             AG22     SKX_EXT_B_BGA1-IC,TBD
M_C_DQ<60>               J4G3             273      SCONN288_H44441004_PIP-SCONN,HA
M_C_DQ<60>               J6U2             128      SCONN288_H44441003_PIP-SCONN,HA
M_C_DQ<60>               U5D1             AE26     SKX_EXT_B_BGA1-IC,TBD
M_C_DQ<61>               J4G3             128      SCONN288_H44441004_PIP-SCONN,HA
M_C_DQ<61>               J6U2             273      SCONN288_H44441003_PIP-SCONN,HA
M_C_DQ<61>               U5D1             AG26     SKX_EXT_B_BGA1-IC,TBD
M_C_DQ<62>               J4G3             280      SCONN288_H44441004_PIP-SCONN,HA
M_C_DQ<62>               J6U2             135      SCONN288_H44441003_PIP-SCONN,HA
M_C_DQ<62>               U5D1             AD23     SKX_EXT_B_BGA1-IC,TBD
M_C_DQ<63>               J4G3             135      SCONN288_H44441004_PIP-SCONN,HA
M_C_DQ<63>               J6U2             280      SCONN288_H44441003_PIP-SCONN,HA
M_C_DQ<63>               U5D1             AH23     SKX_EXT_B_BGA1-IC,TBD
M_C_DQS_DN<0>            J4G3             152      SCONN288_H44441004_PIP-SCONN,HA
M_C_DQS_DN<0>            J6U2             152      SCONN288_H44441003_PIP-SCONN,HA
M_C_DQS_DN<0>            U5D1             AL74     SKX_EXT_B_BGA1-IC,TBD
M_C_DQS_DN<1>            J4G3             163      SCONN288_H44441004_PIP-SCONN,HA
M_C_DQS_DN<1>            J6U2             163      SCONN288_H44441003_PIP-SCONN,HA
M_C_DQS_DN<1>            U5D1             AA74     SKX_EXT_B_BGA1-IC,TBD
M_C_DQS_DN<2>            J4G3             174      SCONN288_H44441004_PIP-SCONN,HA
M_C_DQS_DN<2>            J6U2             174      SCONN288_H44441003_PIP-SCONN,HA
M_C_DQS_DN<2>            U5D1             Y69      SKX_EXT_B_BGA1-IC,TBD
M_C_DQS_DN<3>            J4G3             185      SCONN288_H44441004_PIP-SCONN,HA
M_C_DQS_DN<3>            J6U2             185      SCONN288_H44441003_PIP-SCONN,HA
M_C_DQS_DN<3>            U5D1             AU66     SKX_EXT_B_BGA1-IC,TBD
M_C_DQS_DN<4>            J4G3             244      SCONN288_H44441004_PIP-SCONN,HA
M_C_DQS_DN<4>            J6U2             244      SCONN288_H44441003_PIP-SCONN,HA
M_C_DQS_DN<4>            U5D1             AB39     SKX_EXT_B_BGA1-IC,TBD
M_C_DQS_DN<5>            J4G3             255      SCONN288_H44441004_PIP-SCONN,HA
M_C_DQS_DN<5>            J6U2             255      SCONN288_H44441003_PIP-SCONN,HA
M_C_DQS_DN<5>            U5D1             AB33     SKX_EXT_B_BGA1-IC,TBD
M_C_DQS_DN<6>            J4G3             266      SCONN288_H44441004_PIP-SCONN,HA
M_C_DQS_DN<6>            J6U2             266      SCONN288_H44441003_PIP-SCONN,HA
M_C_DQS_DN<6>            U5D1             AJ30     SKX_EXT_B_BGA1-IC,TBD
M_C_DQS_DN<7>            J4G3             277      SCONN288_H44441004_PIP-SCONN,HA
M_C_DQS_DN<7>            J6U2             277      SCONN288_H44441003_PIP-SCONN,HA
M_C_DQS_DN<7>            U5D1             AJ24     SKX_EXT_B_BGA1-IC,TBD
M_C_DQS_DN<8>            J4G3             196      SCONN288_H44441004_PIP-SCONN,HA
M_C_DQS_DN<8>            J6U2             196      SCONN288_H44441003_PIP-SCONN,HA
M_C_DQS_DN<8>            U5D1             BB71     SKX_EXT_B_BGA1-IC,TBD
M_C_DQS_DN<9>            J4G3             8        SCONN288_H44441004_PIP-SCONN,HA
M_C_DQS_DN<9>            J6U2             8        SCONN288_H44441003_PIP-SCONN,HA
M_C_DQS_DN<9>            U5D1             AP77     SKX_EXT_B_BGA1-IC,TBD
M_C_DQS_DN<10>           J4G3             19       SCONN288_H44441004_PIP-SCONN,HA
M_C_DQS_DN<10>           J6U2             19       SCONN288_H44441003_PIP-SCONN,HA
M_C_DQS_DN<10>           U5D1             AD77     SKX_EXT_B_BGA1-IC,TBD
M_C_DQS_DN<11>           J4G3             30       SCONN288_H44441004_PIP-SCONN,HA
M_C_DQS_DN<11>           J6U2             30       SCONN288_H44441003_PIP-SCONN,HA
M_C_DQS_DN<11>           U5D1             U72      SKX_EXT_B_BGA1-IC,TBD
M_C_DQS_DN<12>           J4G3             41       SCONN288_H44441004_PIP-SCONN,HA
M_C_DQS_DN<12>           J6U2             41       SCONN288_H44441003_PIP-SCONN,HA
M_C_DQS_DN<12>           U5D1             AL66     SKX_EXT_B_BGA1-IC,TBD
M_C_DQS_DN<13>           J4G3             100      SCONN288_H44441004_PIP-SCONN,HA
M_C_DQS_DN<13>           J6U2             100      SCONN288_H44441003_PIP-SCONN,HA
M_C_DQS_DN<13>           U5D1             T39      SKX_EXT_B_BGA1-IC,TBD
M_C_DQS_DN<14>           J4G3             111      SCONN288_H44441004_PIP-SCONN,HA
M_C_DQS_DN<14>           J6U2             111      SCONN288_H44441003_PIP-SCONN,HA
M_C_DQS_DN<14>           U5D1             T33      SKX_EXT_B_BGA1-IC,TBD
M_C_DQS_DN<15>           J4G3             122      SCONN288_H44441004_PIP-SCONN,HA
M_C_DQS_DN<15>           J6U2             122      SCONN288_H44441003_PIP-SCONN,HA
M_C_DQS_DN<15>           U5D1             AC30     SKX_EXT_B_BGA1-IC,TBD
M_C_DQS_DN<16>           J4G3             133      SCONN288_H44441004_PIP-SCONN,HA
M_C_DQS_DN<16>           J6U2             133      SCONN288_H44441003_PIP-SCONN,HA
M_C_DQS_DN<16>           U5D1             AC24     SKX_EXT_B_BGA1-IC,TBD
M_C_DQS_DN<17>           J4G3             52       SCONN288_H44441004_PIP-SCONN,HA
M_C_DQS_DN<17>           J6U2             52       SCONN288_H44441003_PIP-SCONN,HA
M_C_DQS_DN<17>           U5D1             AT71     SKX_EXT_B_BGA1-IC,TBD
M_C_DQS_DP<0>            J4G3             153      SCONN288_H44441004_PIP-SCONN,HA
M_C_DQS_DP<0>            J6U2             153      SCONN288_H44441003_PIP-SCONN,HA
M_C_DQS_DP<0>            U5D1             AM75     SKX_EXT_B_BGA1-IC,TBD
M_C_DQS_DP<1>            J4G3             164      SCONN288_H44441004_PIP-SCONN,HA
M_C_DQS_DP<1>            J6U2             164      SCONN288_H44441003_PIP-SCONN,HA
M_C_DQS_DP<1>            U5D1             AB75     SKX_EXT_B_BGA1-IC,TBD
M_C_DQS_DP<2>            J4G3             175      SCONN288_H44441004_PIP-SCONN,HA
M_C_DQS_DP<2>            J6U2             175      SCONN288_H44441003_PIP-SCONN,HA
M_C_DQS_DP<2>            U5D1             W70      SKX_EXT_B_BGA1-IC,TBD
M_C_DQS_DP<3>            J4G3             186      SCONN288_H44441004_PIP-SCONN,HA
M_C_DQS_DP<3>            J6U2             186      SCONN288_H44441003_PIP-SCONN,HA
M_C_DQS_DP<3>            U5D1             AR66     SKX_EXT_B_BGA1-IC,TBD
M_C_DQS_DP<4>            J4G3             245      SCONN288_H44441004_PIP-SCONN,HA
M_C_DQS_DP<4>            J6U2             245      SCONN288_H44441003_PIP-SCONN,HA
M_C_DQS_DP<4>            U5D1             Y39      SKX_EXT_B_BGA1-IC,TBD
M_C_DQS_DP<5>            J4G3             256      SCONN288_H44441004_PIP-SCONN,HA
M_C_DQS_DP<5>            J6U2             256      SCONN288_H44441003_PIP-SCONN,HA
M_C_DQS_DP<5>            U5D1             Y33      SKX_EXT_B_BGA1-IC,TBD
M_C_DQS_DP<6>            J4G3             267      SCONN288_H44441004_PIP-SCONN,HA
M_C_DQS_DP<6>            J6U2             267      SCONN288_H44441003_PIP-SCONN,HA
M_C_DQS_DP<6>            U5D1             AG30     SKX_EXT_B_BGA1-IC,TBD
M_C_DQS_DP<7>            J4G3             278      SCONN288_H44441004_PIP-SCONN,HA
M_C_DQS_DP<7>            J6U2             278      SCONN288_H44441003_PIP-SCONN,HA
M_C_DQS_DP<7>            U5D1             AG24     SKX_EXT_B_BGA1-IC,TBD
M_C_DQS_DP<8>            J4G3             197      SCONN288_H44441004_PIP-SCONN,HA
M_C_DQS_DP<8>            J6U2             197      SCONN288_H44441003_PIP-SCONN,HA
M_C_DQS_DP<8>            U5D1             AY71     SKX_EXT_B_BGA1-IC,TBD
M_C_DQS_DP<9>            J4G3             7        SCONN288_H44441004_PIP-SCONN,HA
M_C_DQS_DP<9>            J6U2             7        SCONN288_H44441003_PIP-SCONN,HA
M_C_DQS_DP<9>            U5D1             AN76     SKX_EXT_B_BGA1-IC,TBD
M_C_DQS_DP<10>           J4G3             18       SCONN288_H44441004_PIP-SCONN,HA
M_C_DQS_DP<10>           J6U2             18       SCONN288_H44441003_PIP-SCONN,HA
M_C_DQS_DP<10>           U5D1             AC76     SKX_EXT_B_BGA1-IC,TBD
M_C_DQS_DP<11>           J4G3             29       SCONN288_H44441004_PIP-SCONN,HA
M_C_DQS_DP<11>           J6U2             29       SCONN288_H44441003_PIP-SCONN,HA
M_C_DQS_DP<11>           U5D1             V71      SKX_EXT_B_BGA1-IC,TBD
M_C_DQS_DP<12>           J4G3             40       SCONN288_H44441004_PIP-SCONN,HA
M_C_DQS_DP<12>           J6U2             40       SCONN288_H44441003_PIP-SCONN,HA
M_C_DQS_DP<12>           U5D1             AN66     SKX_EXT_B_BGA1-IC,TBD
M_C_DQS_DP<13>           J4G3             99       SCONN288_H44441004_PIP-SCONN,HA
M_C_DQS_DP<13>           J6U2             99       SCONN288_H44441003_PIP-SCONN,HA
M_C_DQS_DP<13>           U5D1             V39      SKX_EXT_B_BGA1-IC,TBD
M_C_DQS_DP<14>           J4G3             110      SCONN288_H44441004_PIP-SCONN,HA
M_C_DQS_DP<14>           J6U2             110      SCONN288_H44441003_PIP-SCONN,HA
M_C_DQS_DP<14>           U5D1             V33      SKX_EXT_B_BGA1-IC,TBD
M_C_DQS_DP<15>           J4G3             121      SCONN288_H44441004_PIP-SCONN,HA
M_C_DQS_DP<15>           J6U2             121      SCONN288_H44441003_PIP-SCONN,HA
M_C_DQS_DP<15>           U5D1             AE30     SKX_EXT_B_BGA1-IC,TBD
M_C_DQS_DP<16>           J4G3             132      SCONN288_H44441004_PIP-SCONN,HA
M_C_DQS_DP<16>           J6U2             132      SCONN288_H44441003_PIP-SCONN,HA
M_C_DQS_DP<16>           U5D1             AE24     SKX_EXT_B_BGA1-IC,TBD
M_C_DQS_DP<17>           J4G3             51       SCONN288_H44441004_PIP-SCONN,HA
M_C_DQS_DP<17>           J6U2             51       SCONN288_H44441003_PIP-SCONN,HA
M_C_DQS_DP<17>           U5D1             AV71     SKX_EXT_B_BGA1-IC,TBD
M_C_ECC<0>               J4G3             194      SCONN288_H44441004_PIP-SCONN,HA
M_C_ECC<0>               J6U2             49       SCONN288_H44441003_PIP-SCONN,HA
M_C_ECC<0>               U5D1             AU72     SKX_EXT_B_BGA1-IC,TBD
M_C_ECC<1>               J4G3             49       SCONN288_H44441004_PIP-SCONN,HA
M_C_ECC<1>               J6U2             194      SCONN288_H44441003_PIP-SCONN,HA
M_C_ECC<1>               U5D1             BA72     SKX_EXT_B_BGA1-IC,TBD
M_C_ECC<2>               J4G3             201      SCONN288_H44441004_PIP-SCONN,HA
M_C_ECC<2>               J6U2             56       SCONN288_H44441003_PIP-SCONN,HA
M_C_ECC<2>               U5D1             AV69     SKX_EXT_B_BGA1-IC,TBD
M_C_ECC<3>               J4G3             56       SCONN288_H44441004_PIP-SCONN,HA
M_C_ECC<3>               J6U2             201      SCONN288_H44441003_PIP-SCONN,HA
M_C_ECC<3>               U5D1             AY69     SKX_EXT_B_BGA1-IC,TBD
M_C_ECC<4>               J4G3             192      SCONN288_H44441004_PIP-SCONN,HA
M_C_ECC<4>               J6U2             47       SCONN288_H44441003_PIP-SCONN,HA
M_C_ECC<4>               U5D1             AV73     SKX_EXT_B_BGA1-IC,TBD
M_C_ECC<5>               J4G3             47       SCONN288_H44441004_PIP-SCONN,HA
M_C_ECC<5>               J6U2             192      SCONN288_H44441003_PIP-SCONN,HA
M_C_ECC<5>               U5D1             AY73     SKX_EXT_B_BGA1-IC,TBD
M_C_ECC<6>               J4G3             199      SCONN288_H44441004_PIP-SCONN,HA
M_C_ECC<6>               J6U2             54       SCONN288_H44441003_PIP-SCONN,HA
M_C_ECC<6>               U5D1             AU70     SKX_EXT_B_BGA1-IC,TBD
M_C_ECC<7>               J4G3             54       SCONN288_H44441004_PIP-SCONN,HA
M_C_ECC<7>               J6U2             199      SCONN288_H44441003_PIP-SCONN,HA
M_C_ECC<7>               U5D1             BA70     SKX_EXT_B_BGA1-IC,TBD
M_C_MA<0>                J4G3             79       SCONN288_H44441004_PIP-SCONN,HA
M_C_MA<0>                J6U2             79       SCONN288_H44441003_PIP-SCONN,HA
M_C_MA<0>                U5D1             AB53     SKX_EXT_B_BGA1-IC,TBD
M_C_MA<1>                J4G3             72       SCONN288_H44441004_PIP-SCONN,HA
M_C_MA<1>                J6U2             72       SCONN288_H44441003_PIP-SCONN,HA
M_C_MA<1>                U5D1             AE58     SKX_EXT_B_BGA1-IC,TBD
M_C_MA<2>                J4G3             216      SCONN288_H44441004_PIP-SCONN,HA
M_C_MA<2>                J6U2             216      SCONN288_H44441003_PIP-SCONN,HA
M_C_MA<2>                U5D1             AD57     SKX_EXT_B_BGA1-IC,TBD
M_C_MA<3>                J4G3             71       SCONN288_H44441004_PIP-SCONN,HA
M_C_MA<3>                J6U2             71       SCONN288_H44441003_PIP-SCONN,HA
M_C_MA<3>                U5D1             W58      SKX_EXT_B_BGA1-IC,TBD
M_C_MA<4>                J4G3             214      SCONN288_H44441004_PIP-SCONN,HA
M_C_MA<4>                J6U2             214      SCONN288_H44441003_PIP-SCONN,HA
M_C_MA<4>                U5D1             AA58     SKX_EXT_B_BGA1-IC,TBD
M_C_MA<5>                J4G3             213      SCONN288_H44441004_PIP-SCONN,HA
M_C_MA<5>                J6U2             213      SCONN288_H44441003_PIP-SCONN,HA
M_C_MA<5>                U5D1             V59      SKX_EXT_B_BGA1-IC,TBD
M_C_MA<6>                J4G3             69       SCONN288_H44441004_PIP-SCONN,HA
M_C_MA<6>                J6U2             69       SCONN288_H44441003_PIP-SCONN,HA
M_C_MA<6>                U5D1             AB59     SKX_EXT_B_BGA1-IC,TBD
M_C_MA<7>                J4G3             211      SCONN288_H44441004_PIP-SCONN,HA
M_C_MA<7>                J6U2             211      SCONN288_H44441003_PIP-SCONN,HA
M_C_MA<7>                U5D1             AE60     SKX_EXT_B_BGA1-IC,TBD
M_C_MA<8>                J4G3             68       SCONN288_H44441004_PIP-SCONN,HA
M_C_MA<8>                J6U2             68       SCONN288_H44441003_PIP-SCONN,HA
M_C_MA<8>                U5D1             AD59     SKX_EXT_B_BGA1-IC,TBD
M_C_MA<9>                J4G3             66       SCONN288_H44441004_PIP-SCONN,HA
M_C_MA<9>                J6U2             66       SCONN288_H44441003_PIP-SCONN,HA
M_C_MA<9>                U5D1             AG58     SKX_EXT_B_BGA1-IC,TBD
M_C_MA<10>               J4G3             225      SCONN288_H44441004_PIP-SCONN,HA
M_C_MA<10>               J6U2             225      SCONN288_H44441003_PIP-SCONN,HA
M_C_MA<10>               U5D1             AD55     SKX_EXT_B_BGA1-IC,TBD
M_C_MA<11>               J4G3             210      SCONN288_H44441004_PIP-SCONN,HA
M_C_MA<11>               J6U2             210      SCONN288_H44441003_PIP-SCONN,HA
M_C_MA<11>               U5D1             AG60     SKX_EXT_B_BGA1-IC,TBD
M_C_MA<12>               J4G3             65       SCONN288_H44441004_PIP-SCONN,HA
M_C_MA<12>               J6U2             65       SCONN288_H44441003_PIP-SCONN,HA
M_C_MA<12>               U5D1             AG62     SKX_EXT_B_BGA1-IC,TBD
M_C_MA<13>               J4G3             232      SCONN288_H44441004_PIP-SCONN,HA
M_C_MA<13>               J6U2             232      SCONN288_H44441003_PIP-SCONN,HA
M_C_MA<13>               U5D1             AD53     SKX_EXT_B_BGA1-IC,TBD
M_C_MA<14>               J4G3             228      SCONN288_H44441004_PIP-SCONN,HA
M_C_MA<14>               J6U2             228      SCONN288_H44441003_PIP-SCONN,HA
M_C_MA<14>               U5D1             W50      SKX_EXT_B_BGA1-IC,TBD
M_C_MA<15>               J4G3             86       SCONN288_H44441004_PIP-SCONN,HA
M_C_MA<15>               J6U2             86       SCONN288_H44441003_PIP-SCONN,HA
M_C_MA<15>               U5D1             AE54     SKX_EXT_B_BGA1-IC,TBD
M_C_MA<16>               J4G3             82       SCONN288_H44441004_PIP-SCONN,HA
M_C_MA<16>               J6U2             82       SCONN288_H44441003_PIP-SCONN,HA
M_C_MA<16>               U5D1             AA52     SKX_EXT_B_BGA1-IC,TBD
M_C_MA<17>               J4G3             234      SCONN288_H44441004_PIP-SCONN,HA
M_C_MA<17>               J6U2             234      SCONN288_H44441003_PIP-SCONN,HA
M_C_MA<17>               U5D1             AC46     SKX_EXT_B_BGA1-IC,TBD
M_C_ODT<0>               J4G3             87       SCONN288_H44441004_PIP-SCONN,HA
M_C_ODT<0>               U5D1             AA50     SKX_EXT_B_BGA1-IC,TBD
M_C_ODT<1>               J4G3             91       SCONN288_H44441004_PIP-SCONN,HA
M_C_ODT<1>               U5D1             AA48     SKX_EXT_B_BGA1-IC,TBD
M_C_ODT<2>               J6U2             87       SCONN288_H44441003_PIP-SCONN,HA
M_C_ODT<2>               U5D1             V49      SKX_EXT_B_BGA1-IC,TBD
M_C_ODT<3>               J6U2             91       SCONN288_H44441003_PIP-SCONN,HA
M_C_ODT<3>               U5D1             AB47     SKX_EXT_B_BGA1-IC,TBD
M_C_PAR                  J4G3             222      SCONN288_H44441004_PIP-SCONN,HA
M_C_PAR                  J6U2             222      SCONN288_H44441003_PIP-SCONN,HA
M_C_PAR                  U5D1             V53      SKX_EXT_B_BGA1-IC,TBD
M_C_VREF                 C4G19            1        CAP_A_0402V-0.01UF,25V,10%,X7RA
M_C_VREF                 C6U17            1        CAP_A_0402V-0.01UF,25V,10%,X7RA
M_C_VREF                 J4G3             146      SCONN288_H44441004_PIP-SCONN,HA
M_C_VREF                 J6U2             146      SCONN288_H44441003_PIP-SCONN,HA
M_C_VREF                 R4G20            2        RES_0402-2,1.0%,1/16W,CHIP,G21A
M_C_VREF                 R4G21            2        RES_0402-1.00K,1%,1/16W,CHIP,GA
M_C_VREF                 R4G22            1        RES_0402-1.00K,1%,1/16W,CHIP,GA
M_DEF_RST_N              J4A1             58       SCONN288_H44441004_PIP-SCONN,HA
M_DEF_RST_N              J4A2             58       SCONN288_H44441004_PIP-SCONN,HA
M_DEF_RST_N              J4B1             58       SCONN288_H44441004_PIP-SCONN,HA
M_DEF_RST_N              J6L1             58       SCONN288_H44441003_PIP-SCONN,HA
M_DEF_RST_N              J6L2             58       SCONN288_H44441003_PIP-SCONN,HA
M_DEF_RST_N              J6M1             58       SCONN288_H44441003_PIP-SCONN,HA
M_DEF_RST_N              U5D1             DV63     SKX_EXT_B_BGA1-IC,TBD
M_D_ACT_N                J4B1             62       SCONN288_H44441004_PIP-SCONN,HA
M_D_ACT_N                J6M1             62       SCONN288_H44441003_PIP-SCONN,HA
M_D_ACT_N                U5D1             DW60     SKX_EXT_B_BGA1-IC,TBD
M_D_ALERT_N              J4B1             208      SCONN288_H44441004_PIP-SCONN,HA
M_D_ALERT_N              J6M1             208      SCONN288_H44441003_PIP-SCONN,HA
M_D_ALERT_N              U5D1             ED63     SKX_EXT_B_BGA1-IC,TBD
M_D_BA<0>                J4B1             81       SCONN288_H44441004_PIP-SCONN,HA
M_D_BA<0>                J6M1             81       SCONN288_H44441003_PIP-SCONN,HA
M_D_BA<0>                U5D1             EE52     SKX_EXT_B_BGA1-IC,TBD
M_D_BA<1>                J4B1             224      SCONN288_H44441004_PIP-SCONN,HA
M_D_BA<1>                J6M1             224      SCONN288_H44441003_PIP-SCONN,HA
M_D_BA<1>                U5D1             EA54     SKX_EXT_B_BGA1-IC,TBD
M_D_BG<0>                J4B1             63       SCONN288_H44441004_PIP-SCONN,HA
M_D_BG<0>                J6M1             63       SCONN288_H44441003_PIP-SCONN,HA
M_D_BG<0>                U5D1             ED61     SKX_EXT_B_BGA1-IC,TBD
M_D_BG<1>                J4B1             207      SCONN288_H44441004_PIP-SCONN,HA
M_D_BG<1>                J6M1             207      SCONN288_H44441003_PIP-SCONN,HA
M_D_BG<1>                U5D1             DW62     SKX_EXT_B_BGA1-IC,TBD
M_D_C<2>                 J4B1             235      SCONN288_H44441004_PIP-SCONN,HA
M_D_C<2>                 J6M1             235      SCONN288_H44441003_PIP-SCONN,HA
M_D_C<2>                 U5D1             DV47     SKX_EXT_B_BGA1-IC,TBD
M_D_CKE<0>               J4B1             60       SCONN288_H44441004_PIP-SCONN,HA
M_D_CKE<0>               U5D1             EE62     SKX_EXT_B_BGA1-IC,TBD
M_D_CKE<1>               J4B1             203      SCONN288_H44441004_PIP-SCONN,HA
M_D_CKE<1>               U5D1             EF63     SKX_EXT_B_BGA1-IC,TBD
M_D_CKE<2>               J6M1             60       SCONN288_H44441003_PIP-SCONN,HA
M_D_CKE<2>               U5D1             EA62     SKX_EXT_B_BGA1-IC,TBD
M_D_CKE<3>               J6M1             203      SCONN288_H44441003_PIP-SCONN,HA
M_D_CKE<3>               U5D1             EB63     SKX_EXT_B_BGA1-IC,TBD
M_D_CLK_DN<0>            J4B1             75       SCONN288_H44441004_PIP-SCONN,HA
M_D_CLK_DN<0>            U5D1             ED55     SKX_EXT_B_BGA1-IC,TBD
M_D_CLK_DN<1>            J4B1             219      SCONN288_H44441004_PIP-SCONN,HA
M_D_CLK_DN<1>            U5D1             EF55     SKX_EXT_B_BGA1-IC,TBD
M_D_CLK_DN<2>            J6M1             75       SCONN288_H44441003_PIP-SCONN,HA
M_D_CLK_DN<2>            U5D1             DW56     SKX_EXT_B_BGA1-IC,TBD
M_D_CLK_DN<3>            J6M1             219      SCONN288_H44441003_PIP-SCONN,HA
M_D_CLK_DN<3>            U5D1             EF57     SKX_EXT_B_BGA1-IC,TBD
M_D_CLK_DP<0>            J4B1             74       SCONN288_H44441004_PIP-SCONN,HA
M_D_CLK_DP<0>            U5D1             EB55     SKX_EXT_B_BGA1-IC,TBD
M_D_CLK_DP<1>            J4B1             218      SCONN288_H44441004_PIP-SCONN,HA
M_D_CLK_DP<1>            U5D1             EE54     SKX_EXT_B_BGA1-IC,TBD
M_D_CLK_DP<2>            J6M1             74       SCONN288_H44441003_PIP-SCONN,HA
M_D_CLK_DP<2>            U5D1             EA56     SKX_EXT_B_BGA1-IC,TBD
M_D_CLK_DP<3>            J6M1             218      SCONN288_H44441003_PIP-SCONN,HA
M_D_CLK_DP<3>            U5D1             EE56     SKX_EXT_B_BGA1-IC,TBD
M_D_CPU_VREF             C6M2             1        CAP_A_0402V-0.01UF,25V,10%,X7RA
M_D_CPU_VREF             R6M2             1        RES_0402-2,1.0%,1/16W,CHIP,G21A
M_D_CPU_VREF             U5D1             CP61     SKX_EXT_B_BGA1-IC,TBD
M_D_CS_N<0>              J4B1             84       SCONN288_H44441004_PIP-SCONN,HA
M_D_CS_N<0>              U5D1             EF51     SKX_EXT_B_BGA1-IC,TBD
M_D_CS_N<1>              J4B1             89       SCONN288_H44441004_PIP-SCONN,HA
M_D_CS_N<1>              U5D1             ED49     SKX_EXT_B_BGA1-IC,TBD
M_D_CS_N<2>              J4B1             93       SCONN288_H44441004_PIP-SCONN,HA
M_D_CS_N<2>              U5D1             ED47     SKX_EXT_B_BGA1-IC,TBD
M_D_CS_N<3>              J4B1             237      SCONN288_H44441004_PIP-SCONN,HA
M_D_CS_N<3>              U5D1             EB47     SKX_EXT_B_BGA1-IC,TBD
M_D_CS_N<4>              J6M1             84       SCONN288_H44441003_PIP-SCONN,HA
M_D_CS_N<4>              U5D1             EB51     SKX_EXT_B_BGA1-IC,TBD
M_D_CS_N<5>              J6M1             89       SCONN288_H44441003_PIP-SCONN,HA
M_D_CS_N<5>              U5D1             EB49     SKX_EXT_B_BGA1-IC,TBD
M_D_CS_N<6>              J6M1             93       SCONN288_H44441003_PIP-SCONN,HA
M_D_CS_N<6>              U5D1             DV45     SKX_EXT_B_BGA1-IC,TBD
M_D_CS_N<7>              J6M1             237      SCONN288_H44441003_PIP-SCONN,HA
M_D_CS_N<7>              U5D1             EB45     SKX_EXT_B_BGA1-IC,TBD
M_D_DQ<0>                J4B1             150      SCONN288_H44441004_PIP-SCONN,HA
M_D_DQ<0>                J6M1             5        SCONN288_H44441003_PIP-SCONN,HA
M_D_DQ<0>                U5D1             CN84     SKX_EXT_B_BGA1-IC,TBD
M_D_DQ<1>                J4B1             5        SCONN288_H44441004_PIP-SCONN,HA
M_D_DQ<1>                J6M1             150      SCONN288_H44441003_PIP-SCONN,HA
M_D_DQ<1>                U5D1             CN86     SKX_EXT_B_BGA1-IC,TBD
M_D_DQ<2>                J4B1             157      SCONN288_H44441004_PIP-SCONN,HA
M_D_DQ<2>                J6M1             12       SCONN288_H44441003_PIP-SCONN,HA
M_D_DQ<2>                U5D1             DA86     SKX_EXT_B_BGA1-IC,TBD
M_D_DQ<3>                J4B1             12       SCONN288_H44441004_PIP-SCONN,HA
M_D_DQ<3>                J6M1             157      SCONN288_H44441003_PIP-SCONN,HA
M_D_DQ<3>                U5D1             DA84     SKX_EXT_B_BGA1-IC,TBD
M_D_DQ<4>                J4B1             148      SCONN288_H44441004_PIP-SCONN,HA
M_D_DQ<4>                J6M1             3        SCONN288_H44441003_PIP-SCONN,HA
M_D_DQ<4>                U5D1             CL84     SKX_EXT_B_BGA1-IC,TBD
M_D_DQ<5>                J4B1             3        SCONN288_H44441004_PIP-SCONN,HA
M_D_DQ<5>                J6M1             148      SCONN288_H44441003_PIP-SCONN,HA
M_D_DQ<5>                U5D1             CL86     SKX_EXT_B_BGA1-IC,TBD
M_D_DQ<6>                J4B1             155      SCONN288_H44441004_PIP-SCONN,HA
M_D_DQ<6>                J6M1             10       SCONN288_H44441003_PIP-SCONN,HA
M_D_DQ<6>                U5D1             CW86     SKX_EXT_B_BGA1-IC,TBD
M_D_DQ<7>                J4B1             10       SCONN288_H44441004_PIP-SCONN,HA
M_D_DQ<7>                J6M1             155      SCONN288_H44441003_PIP-SCONN,HA
M_D_DQ<7>                U5D1             CW84     SKX_EXT_B_BGA1-IC,TBD
M_D_DQ<8>                J4B1             161      SCONN288_H44441004_PIP-SCONN,HA
M_D_DQ<8>                J6M1             16       SCONN288_H44441003_PIP-SCONN,HA
M_D_DQ<8>                U5D1             DG84     SKX_EXT_B_BGA1-IC,TBD
M_D_DQ<9>                J4B1             16       SCONN288_H44441004_PIP-SCONN,HA
M_D_DQ<9>                J6M1             161      SCONN288_H44441003_PIP-SCONN,HA
M_D_DQ<9>                U5D1             DH85     SKX_EXT_B_BGA1-IC,TBD
M_D_DQ<10>               J4B1             168      SCONN288_H44441004_PIP-SCONN,HA
M_D_DQ<10>               J6M1             23       SCONN288_H44441003_PIP-SCONN,HA
M_D_DQ<10>               U5D1             DV83     SKX_EXT_B_BGA1-IC,TBD
M_D_DQ<11>               J4B1             23       SCONN288_H44441004_PIP-SCONN,HA
M_D_DQ<11>               J6M1             168      SCONN288_H44441003_PIP-SCONN,HA
M_D_DQ<11>               U5D1             DY83     SKX_EXT_B_BGA1-IC,TBD
M_D_DQ<12>               J4B1             159      SCONN288_H44441004_PIP-SCONN,HA
M_D_DQ<12>               J6M1             14       SCONN288_H44441003_PIP-SCONN,HA
M_D_DQ<12>               U5D1             DD85     SKX_EXT_B_BGA1-IC,TBD
M_D_DQ<13>               J4B1             14       SCONN288_H44441004_PIP-SCONN,HA
M_D_DQ<13>               J6M1             159      SCONN288_H44441003_PIP-SCONN,HA
M_D_DQ<13>               U5D1             DE84     SKX_EXT_B_BGA1-IC,TBD
M_D_DQ<14>               J4B1             166      SCONN288_H44441004_PIP-SCONN,HA
M_D_DQ<14>               J6M1             21       SCONN288_H44441003_PIP-SCONN,HA
M_D_DQ<14>               U5D1             DR84     SKX_EXT_B_BGA1-IC,TBD
M_D_DQ<15>               J4B1             21       SCONN288_H44441004_PIP-SCONN,HA
M_D_DQ<15>               J6M1             166      SCONN288_H44441003_PIP-SCONN,HA
M_D_DQ<15>               U5D1             DV85     SKX_EXT_B_BGA1-IC,TBD
M_D_DQ<16>               J4B1             172      SCONN288_H44441004_PIP-SCONN,HA
M_D_DQ<16>               J6M1             27       SCONN288_H44441003_PIP-SCONN,HA
M_D_DQ<16>               U5D1             DM79     SKX_EXT_B_BGA1-IC,TBD
M_D_DQ<17>               J4B1             27       SCONN288_H44441004_PIP-SCONN,HA
M_D_DQ<17>               J6M1             172      SCONN288_H44441003_PIP-SCONN,HA
M_D_DQ<17>               U5D1             DK81     SKX_EXT_B_BGA1-IC,TBD
M_D_DQ<18>               J4B1             179      SCONN288_H44441004_PIP-SCONN,HA
M_D_DQ<18>               J6M1             34       SCONN288_H44441003_PIP-SCONN,HA
M_D_DQ<18>               U5D1             DT81     SKX_EXT_B_BGA1-IC,TBD
M_D_DQ<19>               J4B1             34       SCONN288_H44441004_PIP-SCONN,HA
M_D_DQ<19>               J6M1             179      SCONN288_H44441003_PIP-SCONN,HA
M_D_DQ<19>               U5D1             DR82     SKX_EXT_B_BGA1-IC,TBD
M_D_DQ<20>               J4B1             170      SCONN288_H44441004_PIP-SCONN,HA
M_D_DQ<20>               J6M1             25       SCONN288_H44441003_PIP-SCONN,HA
M_D_DQ<20>               U5D1             DK79     SKX_EXT_B_BGA1-IC,TBD
M_D_DQ<21>               J4B1             25       SCONN288_H44441004_PIP-SCONN,HA
M_D_DQ<21>               J6M1             170      SCONN288_H44441003_PIP-SCONN,HA
M_D_DQ<21>               U5D1             DJ80     SKX_EXT_B_BGA1-IC,TBD
M_D_DQ<22>               J4B1             177      SCONN288_H44441004_PIP-SCONN,HA
M_D_DQ<22>               J6M1             32       SCONN288_H44441003_PIP-SCONN,HA
M_D_DQ<22>               U5D1             DR80     SKX_EXT_B_BGA1-IC,TBD
M_D_DQ<23>               J4B1             32       SCONN288_H44441004_PIP-SCONN,HA
M_D_DQ<23>               J6M1             177      SCONN288_H44441003_PIP-SCONN,HA
M_D_DQ<23>               U5D1             DN82     SKX_EXT_B_BGA1-IC,TBD
M_D_DQ<24>               J4B1             183      SCONN288_H44441004_PIP-SCONN,HA
M_D_DQ<24>               J6M1             38       SCONN288_H44441003_PIP-SCONN,HA
M_D_DQ<24>               U5D1             DN76     SKX_EXT_B_BGA1-IC,TBD
M_D_DQ<25>               J4B1             38       SCONN288_H44441004_PIP-SCONN,HA
M_D_DQ<25>               J6M1             183      SCONN288_H44441003_PIP-SCONN,HA
M_D_DQ<25>               U5D1             DU76     SKX_EXT_B_BGA1-IC,TBD
M_D_DQ<26>               J4B1             190      SCONN288_H44441004_PIP-SCONN,HA
M_D_DQ<26>               J6M1             45       SCONN288_H44441003_PIP-SCONN,HA
M_D_DQ<26>               U5D1             DP73     SKX_EXT_B_BGA1-IC,TBD
M_D_DQ<27>               J4B1             45       SCONN288_H44441004_PIP-SCONN,HA
M_D_DQ<27>               J6M1             190      SCONN288_H44441003_PIP-SCONN,HA
M_D_DQ<27>               U5D1             DT73     SKX_EXT_B_BGA1-IC,TBD
M_D_DQ<28>               J4B1             181      SCONN288_H44441004_PIP-SCONN,HA
M_D_DQ<28>               J6M1             36       SCONN288_H44441003_PIP-SCONN,HA
M_D_DQ<28>               U5D1             DP77     SKX_EXT_B_BGA1-IC,TBD
M_D_DQ<29>               J4B1             36       SCONN288_H44441004_PIP-SCONN,HA
M_D_DQ<29>               J6M1             181      SCONN288_H44441003_PIP-SCONN,HA
M_D_DQ<29>               U5D1             DT77     SKX_EXT_B_BGA1-IC,TBD
M_D_DQ<30>               J4B1             188      SCONN288_H44441004_PIP-SCONN,HA
M_D_DQ<30>               J6M1             43       SCONN288_H44441003_PIP-SCONN,HA
M_D_DQ<30>               U5D1             DN74     SKX_EXT_B_BGA1-IC,TBD
M_D_DQ<31>               J4B1             43       SCONN288_H44441004_PIP-SCONN,HA
M_D_DQ<31>               J6M1             188      SCONN288_H44441003_PIP-SCONN,HA
M_D_DQ<31>               U5D1             DU74     SKX_EXT_B_BGA1-IC,TBD
M_D_DQ<32>               J4B1             242      SCONN288_H44441004_PIP-SCONN,HA
M_D_DQ<32>               J6M1             97       SCONN288_H44441003_PIP-SCONN,HA
M_D_DQ<32>               U5D1             EC40     SKX_EXT_B_BGA1-IC,TBD
M_D_DQ<33>               J4B1             97       SCONN288_H44441004_PIP-SCONN,HA
M_D_DQ<33>               J6M1             242      SCONN288_H44441003_PIP-SCONN,HA
M_D_DQ<33>               U5D1             ED39     SKX_EXT_B_BGA1-IC,TBD
M_D_DQ<34>               J4B1             249      SCONN288_H44441004_PIP-SCONN,HA
M_D_DQ<34>               J6M1             104      SCONN288_H44441003_PIP-SCONN,HA
M_D_DQ<34>               U5D1             EA36     SKX_EXT_B_BGA1-IC,TBD
M_D_DQ<35>               J4B1             104      SCONN288_H44441004_PIP-SCONN,HA
M_D_DQ<35>               J6M1             249      SCONN288_H44441003_PIP-SCONN,HA
M_D_DQ<35>               U5D1             EC36     SKX_EXT_B_BGA1-IC,TBD
M_D_DQ<36>               J4B1             240      SCONN288_H44441004_PIP-SCONN,HA
M_D_DQ<36>               J6M1             95       SCONN288_H44441003_PIP-SCONN,HA
M_D_DQ<36>               U5D1             DY39     SKX_EXT_B_BGA1-IC,TBD
M_D_DQ<37>               J4B1             95       SCONN288_H44441004_PIP-SCONN,HA
M_D_DQ<37>               J6M1             240      SCONN288_H44441003_PIP-SCONN,HA
M_D_DQ<37>               U5D1             EA40     SKX_EXT_B_BGA1-IC,TBD
M_D_DQ<38>               J4B1             247      SCONN288_H44441004_PIP-SCONN,HA
M_D_DQ<38>               J6M1             102      SCONN288_H44441003_PIP-SCONN,HA
M_D_DQ<38>               U5D1             DY37     SKX_EXT_B_BGA1-IC,TBD
M_D_DQ<39>               J4B1             102      SCONN288_H44441004_PIP-SCONN,HA
M_D_DQ<39>               J6M1             247      SCONN288_H44441003_PIP-SCONN,HA
M_D_DQ<39>               U5D1             ED37     SKX_EXT_B_BGA1-IC,TBD
M_D_DQ<40>               J4B1             253      SCONN288_H44441004_PIP-SCONN,HA
M_D_DQ<40>               J6M1             108      SCONN288_H44441003_PIP-SCONN,HA
M_D_DQ<40>               U5D1             DN36     SKX_EXT_B_BGA1-IC,TBD
M_D_DQ<41>               J4B1             108      SCONN288_H44441004_PIP-SCONN,HA
M_D_DQ<41>               J6M1             253      SCONN288_H44441003_PIP-SCONN,HA
M_D_DQ<41>               U5D1             DU36     SKX_EXT_B_BGA1-IC,TBD
M_D_DQ<42>               J4B1             260      SCONN288_H44441004_PIP-SCONN,HA
M_D_DQ<42>               J6M1             115      SCONN288_H44441003_PIP-SCONN,HA
M_D_DQ<42>               U5D1             DP33     SKX_EXT_B_BGA1-IC,TBD
M_D_DQ<43>               J4B1             115      SCONN288_H44441004_PIP-SCONN,HA
M_D_DQ<43>               J6M1             260      SCONN288_H44441003_PIP-SCONN,HA
M_D_DQ<43>               U5D1             DT33     SKX_EXT_B_BGA1-IC,TBD
M_D_DQ<44>               J4B1             251      SCONN288_H44441004_PIP-SCONN,HA
M_D_DQ<44>               J6M1             106      SCONN288_H44441003_PIP-SCONN,HA
M_D_DQ<44>               U5D1             DP37     SKX_EXT_B_BGA1-IC,TBD
M_D_DQ<45>               J4B1             106      SCONN288_H44441004_PIP-SCONN,HA
M_D_DQ<45>               J6M1             251      SCONN288_H44441003_PIP-SCONN,HA
M_D_DQ<45>               U5D1             DT37     SKX_EXT_B_BGA1-IC,TBD
M_D_DQ<46>               J4B1             258      SCONN288_H44441004_PIP-SCONN,HA
M_D_DQ<46>               J6M1             113      SCONN288_H44441003_PIP-SCONN,HA
M_D_DQ<46>               U5D1             DN34     SKX_EXT_B_BGA1-IC,TBD
M_D_DQ<47>               J4B1             113      SCONN288_H44441004_PIP-SCONN,HA
M_D_DQ<47>               J6M1             258      SCONN288_H44441003_PIP-SCONN,HA
M_D_DQ<47>               U5D1             DU34     SKX_EXT_B_BGA1-IC,TBD
M_D_DQ<48>               J4B1             264      SCONN288_H44441004_PIP-SCONN,HA
M_D_DQ<48>               J6M1             119      SCONN288_H44441003_PIP-SCONN,HA
M_D_DQ<48>               U5D1             DN30     SKX_EXT_B_BGA1-IC,TBD
M_D_DQ<49>               J4B1             119      SCONN288_H44441004_PIP-SCONN,HA
M_D_DQ<49>               J6M1             264      SCONN288_H44441003_PIP-SCONN,HA
M_D_DQ<49>               U5D1             DU30     SKX_EXT_B_BGA1-IC,TBD
M_D_DQ<50>               J4B1             271      SCONN288_H44441004_PIP-SCONN,HA
M_D_DQ<50>               J6M1             126      SCONN288_H44441003_PIP-SCONN,HA
M_D_DQ<50>               U5D1             DP27     SKX_EXT_B_BGA1-IC,TBD
M_D_DQ<51>               J4B1             126      SCONN288_H44441004_PIP-SCONN,HA
M_D_DQ<51>               J6M1             271      SCONN288_H44441003_PIP-SCONN,HA
M_D_DQ<51>               U5D1             DT27     SKX_EXT_B_BGA1-IC,TBD
M_D_DQ<52>               J4B1             262      SCONN288_H44441004_PIP-SCONN,HA
M_D_DQ<52>               J6M1             117      SCONN288_H44441003_PIP-SCONN,HA
M_D_DQ<52>               U5D1             DP31     SKX_EXT_B_BGA1-IC,TBD
M_D_DQ<53>               J4B1             117      SCONN288_H44441004_PIP-SCONN,HA
M_D_DQ<53>               J6M1             262      SCONN288_H44441003_PIP-SCONN,HA
M_D_DQ<53>               U5D1             DT31     SKX_EXT_B_BGA1-IC,TBD
M_D_DQ<54>               J4B1             269      SCONN288_H44441004_PIP-SCONN,HA
M_D_DQ<54>               J6M1             124      SCONN288_H44441003_PIP-SCONN,HA
M_D_DQ<54>               U5D1             DN28     SKX_EXT_B_BGA1-IC,TBD
M_D_DQ<55>               J4B1             124      SCONN288_H44441004_PIP-SCONN,HA
M_D_DQ<55>               J6M1             269      SCONN288_H44441003_PIP-SCONN,HA
M_D_DQ<55>               U5D1             DU28     SKX_EXT_B_BGA1-IC,TBD
M_D_DQ<56>               J4B1             275      SCONN288_H44441004_PIP-SCONN,HA
M_D_DQ<56>               J6M1             130      SCONN288_H44441003_PIP-SCONN,HA
M_D_DQ<56>               U5D1             DN24     SKX_EXT_B_BGA1-IC,TBD
M_D_DQ<57>               J4B1             130      SCONN288_H44441004_PIP-SCONN,HA
M_D_DQ<57>               J6M1             275      SCONN288_H44441003_PIP-SCONN,HA
M_D_DQ<57>               U5D1             DU24     SKX_EXT_B_BGA1-IC,TBD
M_D_DQ<58>               J4B1             282      SCONN288_H44441004_PIP-SCONN,HA
M_D_DQ<58>               J6M1             137      SCONN288_H44441003_PIP-SCONN,HA
M_D_DQ<58>               U5D1             DY21     SKX_EXT_B_BGA1-IC,TBD
M_D_DQ<59>               J4B1             137      SCONN288_H44441004_PIP-SCONN,HA
M_D_DQ<59>               J6M1             282      SCONN288_H44441003_PIP-SCONN,HA
M_D_DQ<59>               U5D1             EB21     SKX_EXT_B_BGA1-IC,TBD
M_D_DQ<60>               J4B1             273      SCONN288_H44441004_PIP-SCONN,HA
M_D_DQ<60>               J6M1             128      SCONN288_H44441003_PIP-SCONN,HA
M_D_DQ<60>               U5D1             DP25     SKX_EXT_B_BGA1-IC,TBD
M_D_DQ<61>               J4B1             128      SCONN288_H44441004_PIP-SCONN,HA
M_D_DQ<61>               J6M1             273      SCONN288_H44441003_PIP-SCONN,HA
M_D_DQ<61>               U5D1             DT25     SKX_EXT_B_BGA1-IC,TBD
M_D_DQ<62>               J4B1             280      SCONN288_H44441004_PIP-SCONN,HA
M_D_DQ<62>               J6M1             135      SCONN288_H44441003_PIP-SCONN,HA
M_D_DQ<62>               U5D1             EC22     SKX_EXT_B_BGA1-IC,TBD
M_D_DQ<63>               J4B1             135      SCONN288_H44441004_PIP-SCONN,HA
M_D_DQ<63>               J6M1             280      SCONN288_H44441003_PIP-SCONN,HA
M_D_DQ<63>               U5D1             DW22     SKX_EXT_B_BGA1-IC,TBD
M_D_DQS_DN<0>            J4B1             152      SCONN288_H44441004_PIP-SCONN,HA
M_D_DQS_DN<0>            J6M1             152      SCONN288_H44441003_PIP-SCONN,HA
M_D_DQS_DN<0>            U5D1             CU84     SKX_EXT_B_BGA1-IC,TBD
M_D_DQS_DN<1>            J4B1             163      SCONN288_H44441004_PIP-SCONN,HA
M_D_DQS_DN<1>            J6M1             163      SCONN288_H44441003_PIP-SCONN,HA
M_D_DQS_DN<1>            U5D1             DN84     SKX_EXT_B_BGA1-IC,TBD
M_D_DQS_DN<2>            J4B1             174      SCONN288_H44441004_PIP-SCONN,HA
M_D_DQS_DN<2>            J6M1             174      SCONN288_H44441003_PIP-SCONN,HA
M_D_DQS_DN<2>            U5D1             DL82     SKX_EXT_B_BGA1-IC,TBD
M_D_DQS_DN<3>            J4B1             185      SCONN288_H44441004_PIP-SCONN,HA
M_D_DQS_DN<3>            J6M1             185      SCONN288_H44441003_PIP-SCONN,HA
M_D_DQS_DN<3>            U5D1             DV75     SKX_EXT_B_BGA1-IC,TBD
M_D_DQS_DN<4>            J4B1             244      SCONN288_H44441004_PIP-SCONN,HA
M_D_DQS_DN<4>            J6M1             244      SCONN288_H44441003_PIP-SCONN,HA
M_D_DQS_DN<4>            U5D1             EE38     SKX_EXT_B_BGA1-IC,TBD
M_D_DQS_DN<5>            J4B1             255      SCONN288_H44441004_PIP-SCONN,HA
M_D_DQS_DN<5>            J6M1             255      SCONN288_H44441003_PIP-SCONN,HA
M_D_DQS_DN<5>            U5D1             DV35     SKX_EXT_B_BGA1-IC,TBD
M_D_DQS_DN<6>            J4B1             266      SCONN288_H44441004_PIP-SCONN,HA
M_D_DQS_DN<6>            J6M1             266      SCONN288_H44441003_PIP-SCONN,HA
M_D_DQS_DN<6>            U5D1             DV29     SKX_EXT_B_BGA1-IC,TBD
M_D_DQS_DN<7>            J4B1             277      SCONN288_H44441004_PIP-SCONN,HA
M_D_DQS_DN<7>            J6M1             277      SCONN288_H44441003_PIP-SCONN,HA
M_D_DQS_DN<7>            U5D1             DV23     SKX_EXT_B_BGA1-IC,TBD
M_D_DQS_DN<8>            J4B1             196      SCONN288_H44441004_PIP-SCONN,HA
M_D_DQS_DN<8>            J6M1             196      SCONN288_H44441003_PIP-SCONN,HA
M_D_DQS_DN<8>            U5D1             DF67     SKX_EXT_B_BGA1-IC,TBD
M_D_DQS_DN<9>            J4B1             8        SCONN288_H44441004_PIP-SCONN,HA
M_D_DQS_DN<9>            J6M1             8        SCONN288_H44441003_PIP-SCONN,HA
M_D_DQS_DN<9>            U5D1             CR84     SKX_EXT_B_BGA1-IC,TBD
M_D_DQS_DN<10>           J4B1             19       SCONN288_H44441004_PIP-SCONN,HA
M_D_DQS_DN<10>           J6M1             19       SCONN288_H44441003_PIP-SCONN,HA
M_D_DQS_DN<10>           U5D1             DM85     SKX_EXT_B_BGA1-IC,TBD
M_D_DQS_DN<11>           J4B1             30       SCONN288_H44441004_PIP-SCONN,HA
M_D_DQS_DN<11>           J6M1             30       SCONN288_H44441003_PIP-SCONN,HA
M_D_DQS_DN<11>           U5D1             DN80     SKX_EXT_B_BGA1-IC,TBD
M_D_DQS_DN<12>           J4B1             41       SCONN288_H44441004_PIP-SCONN,HA
M_D_DQS_DN<12>           J6M1             41       SCONN288_H44441003_PIP-SCONN,HA
M_D_DQS_DN<12>           U5D1             DP75     SKX_EXT_B_BGA1-IC,TBD
M_D_DQS_DN<13>           J4B1             100      SCONN288_H44441004_PIP-SCONN,HA
M_D_DQS_DN<13>           J6M1             100      SCONN288_H44441003_PIP-SCONN,HA
M_D_DQS_DN<13>           U5D1             EA38     SKX_EXT_B_BGA1-IC,TBD
M_D_DQS_DN<14>           J4B1             111      SCONN288_H44441004_PIP-SCONN,HA
M_D_DQS_DN<14>           J6M1             111      SCONN288_H44441003_PIP-SCONN,HA
M_D_DQS_DN<14>           U5D1             DP35     SKX_EXT_B_BGA1-IC,TBD
M_D_DQS_DN<15>           J4B1             122      SCONN288_H44441004_PIP-SCONN,HA
M_D_DQS_DN<15>           J6M1             122      SCONN288_H44441003_PIP-SCONN,HA
M_D_DQS_DN<15>           U5D1             DM29     SKX_EXT_B_BGA1-IC,TBD
M_D_DQS_DN<16>           J4B1             133      SCONN288_H44441004_PIP-SCONN,HA
M_D_DQS_DN<16>           J6M1             133      SCONN288_H44441003_PIP-SCONN,HA
M_D_DQS_DN<16>           U5D1             DM23     SKX_EXT_B_BGA1-IC,TBD
M_D_DQS_DN<17>           J4B1             52       SCONN288_H44441004_PIP-SCONN,HA
M_D_DQS_DN<17>           J6M1             52       SCONN288_H44441003_PIP-SCONN,HA
M_D_DQS_DN<17>           U5D1             DB67     SKX_EXT_B_BGA1-IC,TBD
M_D_DQS_DP<0>            J4B1             153      SCONN288_H44441004_PIP-SCONN,HA
M_D_DQS_DP<0>            J6M1             153      SCONN288_H44441003_PIP-SCONN,HA
M_D_DQS_DP<0>            U5D1             CV85     SKX_EXT_B_BGA1-IC,TBD
M_D_DQS_DP<1>            J4B1             164      SCONN288_H44441004_PIP-SCONN,HA
M_D_DQS_DP<1>            J6M1             164      SCONN288_H44441003_PIP-SCONN,HA
M_D_DQS_DP<1>            U5D1             DP85     SKX_EXT_B_BGA1-IC,TBD
M_D_DQS_DP<2>            J4B1             175      SCONN288_H44441004_PIP-SCONN,HA
M_D_DQS_DP<2>            J6M1             175      SCONN288_H44441003_PIP-SCONN,HA
M_D_DQS_DP<2>            U5D1             DM81     SKX_EXT_B_BGA1-IC,TBD
M_D_DQS_DP<3>            J4B1             186      SCONN288_H44441004_PIP-SCONN,HA
M_D_DQS_DP<3>            J6M1             186      SCONN288_H44441003_PIP-SCONN,HA
M_D_DQS_DP<3>            U5D1             DT75     SKX_EXT_B_BGA1-IC,TBD
M_D_DQS_DP<4>            J4B1             245      SCONN288_H44441004_PIP-SCONN,HA
M_D_DQS_DP<4>            J6M1             245      SCONN288_H44441003_PIP-SCONN,HA
M_D_DQS_DP<4>            U5D1             EC38     SKX_EXT_B_BGA1-IC,TBD
M_D_DQS_DP<5>            J4B1             256      SCONN288_H44441004_PIP-SCONN,HA
M_D_DQS_DP<5>            J6M1             256      SCONN288_H44441003_PIP-SCONN,HA
M_D_DQS_DP<5>            U5D1             DT35     SKX_EXT_B_BGA1-IC,TBD
M_D_DQS_DP<6>            J4B1             267      SCONN288_H44441004_PIP-SCONN,HA
M_D_DQS_DP<6>            J6M1             267      SCONN288_H44441003_PIP-SCONN,HA
M_D_DQS_DP<6>            U5D1             DT29     SKX_EXT_B_BGA1-IC,TBD
M_D_DQS_DP<7>            J4B1             278      SCONN288_H44441004_PIP-SCONN,HA
M_D_DQS_DP<7>            J6M1             278      SCONN288_H44441003_PIP-SCONN,HA
M_D_DQS_DP<7>            U5D1             DT23     SKX_EXT_B_BGA1-IC,TBD
M_D_DQS_DP<8>            J4B1             197      SCONN288_H44441004_PIP-SCONN,HA
M_D_DQS_DP<8>            J6M1             197      SCONN288_H44441003_PIP-SCONN,HA
M_D_DQS_DP<8>            U5D1             DD67     SKX_EXT_B_BGA1-IC,TBD
M_D_DQS_DP<9>            J4B1             7        SCONN288_H44441004_PIP-SCONN,HA
M_D_DQS_DP<9>            J6M1             7        SCONN288_H44441003_PIP-SCONN,HA
M_D_DQS_DP<9>            U5D1             CP85     SKX_EXT_B_BGA1-IC,TBD
M_D_DQS_DP<10>           J4B1             18       SCONN288_H44441004_PIP-SCONN,HA
M_D_DQS_DP<10>           J6M1             18       SCONN288_H44441003_PIP-SCONN,HA
M_D_DQS_DP<10>           U5D1             DL84     SKX_EXT_B_BGA1-IC,TBD
M_D_DQS_DP<11>           J4B1             29       SCONN288_H44441004_PIP-SCONN,HA
M_D_DQS_DP<11>           J6M1             29       SCONN288_H44441003_PIP-SCONN,HA
M_D_DQS_DP<11>           U5D1             DP79     SKX_EXT_B_BGA1-IC,TBD
M_D_DQS_DP<12>           J4B1             40       SCONN288_H44441004_PIP-SCONN,HA
M_D_DQS_DP<12>           J6M1             40       SCONN288_H44441003_PIP-SCONN,HA
M_D_DQS_DP<12>           U5D1             DM75     SKX_EXT_B_BGA1-IC,TBD
M_D_DQS_DP<13>           J4B1             99       SCONN288_H44441004_PIP-SCONN,HA
M_D_DQS_DP<13>           J6M1             99       SCONN288_H44441003_PIP-SCONN,HA
M_D_DQS_DP<13>           U5D1             DW38     SKX_EXT_B_BGA1-IC,TBD
M_D_DQS_DP<14>           J4B1             110      SCONN288_H44441004_PIP-SCONN,HA
M_D_DQS_DP<14>           J6M1             110      SCONN288_H44441003_PIP-SCONN,HA
M_D_DQS_DP<14>           U5D1             DM35     SKX_EXT_B_BGA1-IC,TBD
M_D_DQS_DP<15>           J4B1             121      SCONN288_H44441004_PIP-SCONN,HA
M_D_DQS_DP<15>           J6M1             121      SCONN288_H44441003_PIP-SCONN,HA
M_D_DQS_DP<15>           U5D1             DP29     SKX_EXT_B_BGA1-IC,TBD
M_D_DQS_DP<16>           J4B1             132      SCONN288_H44441004_PIP-SCONN,HA
M_D_DQS_DP<16>           J6M1             132      SCONN288_H44441003_PIP-SCONN,HA
M_D_DQS_DP<16>           U5D1             DP23     SKX_EXT_B_BGA1-IC,TBD
M_D_DQS_DP<17>           J4B1             51       SCONN288_H44441004_PIP-SCONN,HA
M_D_DQS_DP<17>           J6M1             51       SCONN288_H44441003_PIP-SCONN,HA
M_D_DQS_DP<17>           U5D1             CY67     SKX_EXT_B_BGA1-IC,TBD
M_D_ECC<0>               J4B1             194      SCONN288_H44441004_PIP-SCONN,HA
M_D_ECC<0>               J6M1             49       SCONN288_H44441003_PIP-SCONN,HA
M_D_ECC<0>               U5D1             DA68     SKX_EXT_B_BGA1-IC,TBD
M_D_ECC<1>               J4B1             49       SCONN288_H44441004_PIP-SCONN,HA
M_D_ECC<1>               J6M1             194      SCONN288_H44441003_PIP-SCONN,HA
M_D_ECC<1>               U5D1             DE68     SKX_EXT_B_BGA1-IC,TBD
M_D_ECC<2>               J4B1             201      SCONN288_H44441004_PIP-SCONN,HA
M_D_ECC<2>               J6M1             56       SCONN288_H44441003_PIP-SCONN,HA
M_D_ECC<2>               U5D1             DB65     SKX_EXT_B_BGA1-IC,TBD
M_D_ECC<3>               J4B1             56       SCONN288_H44441004_PIP-SCONN,HA
M_D_ECC<3>               J6M1             201      SCONN288_H44441003_PIP-SCONN,HA
M_D_ECC<3>               U5D1             DD65     SKX_EXT_B_BGA1-IC,TBD
M_D_ECC<4>               J4B1             192      SCONN288_H44441004_PIP-SCONN,HA
M_D_ECC<4>               J6M1             47       SCONN288_H44441003_PIP-SCONN,HA
M_D_ECC<4>               U5D1             DB69     SKX_EXT_B_BGA1-IC,TBD
M_D_ECC<5>               J4B1             47       SCONN288_H44441004_PIP-SCONN,HA
M_D_ECC<5>               J6M1             192      SCONN288_H44441003_PIP-SCONN,HA
M_D_ECC<5>               U5D1             DD69     SKX_EXT_B_BGA1-IC,TBD
M_D_ECC<6>               J4B1             199      SCONN288_H44441004_PIP-SCONN,HA
M_D_ECC<6>               J6M1             54       SCONN288_H44441003_PIP-SCONN,HA
M_D_ECC<6>               U5D1             DA66     SKX_EXT_B_BGA1-IC,TBD
M_D_ECC<7>               J4B1             54       SCONN288_H44441004_PIP-SCONN,HA
M_D_ECC<7>               J6M1             199      SCONN288_H44441003_PIP-SCONN,HA
M_D_ECC<7>               U5D1             DE66     SKX_EXT_B_BGA1-IC,TBD
M_D_MA<0>                J4B1             79       SCONN288_H44441004_PIP-SCONN,HA
M_D_MA<0>                J6M1             79       SCONN288_H44441003_PIP-SCONN,HA
M_D_MA<0>                U5D1             EB53     SKX_EXT_B_BGA1-IC,TBD
M_D_MA<1>                J4B1             72       SCONN288_H44441004_PIP-SCONN,HA
M_D_MA<1>                J6M1             72       SCONN288_H44441003_PIP-SCONN,HA
M_D_MA<1>                U5D1             ED57     SKX_EXT_B_BGA1-IC,TBD
M_D_MA<2>                J4B1             216      SCONN288_H44441004_PIP-SCONN,HA
M_D_MA<2>                J6M1             216      SCONN288_H44441003_PIP-SCONN,HA
M_D_MA<2>                U5D1             EE58     SKX_EXT_B_BGA1-IC,TBD
M_D_MA<3>                J4B1             71       SCONN288_H44441004_PIP-SCONN,HA
M_D_MA<3>                J6M1             71       SCONN288_H44441003_PIP-SCONN,HA
M_D_MA<3>                U5D1             EB57     SKX_EXT_B_BGA1-IC,TBD
M_D_MA<4>                J4B1             214      SCONN288_H44441004_PIP-SCONN,HA
M_D_MA<4>                J6M1             214      SCONN288_H44441003_PIP-SCONN,HA
M_D_MA<4>                U5D1             ED59     SKX_EXT_B_BGA1-IC,TBD
M_D_MA<5>                J4B1             213      SCONN288_H44441004_PIP-SCONN,HA
M_D_MA<5>                J6M1             213      SCONN288_H44441003_PIP-SCONN,HA
M_D_MA<5>                U5D1             EA58     SKX_EXT_B_BGA1-IC,TBD
M_D_MA<6>                J4B1             69       SCONN288_H44441004_PIP-SCONN,HA
M_D_MA<6>                J6M1             69       SCONN288_H44441003_PIP-SCONN,HA
M_D_MA<6>                U5D1             EE60     SKX_EXT_B_BGA1-IC,TBD
M_D_MA<7>                J4B1             211      SCONN288_H44441004_PIP-SCONN,HA
M_D_MA<7>                J6M1             211      SCONN288_H44441003_PIP-SCONN,HA
M_D_MA<7>                U5D1             EA60     SKX_EXT_B_BGA1-IC,TBD
M_D_MA<8>                J4B1             68       SCONN288_H44441004_PIP-SCONN,HA
M_D_MA<8>                J6M1             68       SCONN288_H44441003_PIP-SCONN,HA
M_D_MA<8>                U5D1             EB59     SKX_EXT_B_BGA1-IC,TBD
M_D_MA<9>                J4B1             66       SCONN288_H44441004_PIP-SCONN,HA
M_D_MA<9>                J6M1             66       SCONN288_H44441003_PIP-SCONN,HA
M_D_MA<9>                U5D1             EF61     SKX_EXT_B_BGA1-IC,TBD
M_D_MA<10>               J4B1             225      SCONN288_H44441004_PIP-SCONN,HA
M_D_MA<10>               J6M1             225      SCONN288_H44441003_PIP-SCONN,HA
M_D_MA<10>               U5D1             DW54     SKX_EXT_B_BGA1-IC,TBD
M_D_MA<11>               J4B1             210      SCONN288_H44441004_PIP-SCONN,HA
M_D_MA<11>               J6M1             210      SCONN288_H44441003_PIP-SCONN,HA
M_D_MA<11>               U5D1             EB61     SKX_EXT_B_BGA1-IC,TBD
M_D_MA<12>               J4B1             65       SCONN288_H44441004_PIP-SCONN,HA
M_D_MA<12>               J6M1             65       SCONN288_H44441003_PIP-SCONN,HA
M_D_MA<12>               U5D1             DT63     SKX_EXT_B_BGA1-IC,TBD
M_D_MA<13>               J4B1             232      SCONN288_H44441004_PIP-SCONN,HA
M_D_MA<13>               J6M1             232      SCONN288_H44441003_PIP-SCONN,HA
M_D_MA<13>               U5D1             DW48     SKX_EXT_B_BGA1-IC,TBD
M_D_MA<14>               J4B1             228      SCONN288_H44441004_PIP-SCONN,HA
M_D_MA<14>               J6M1             228      SCONN288_H44441003_PIP-SCONN,HA
M_D_MA<14>               U5D1             ED51     SKX_EXT_B_BGA1-IC,TBD
M_D_MA<15>               J4B1             86       SCONN288_H44441004_PIP-SCONN,HA
M_D_MA<15>               J6M1             86       SCONN288_H44441003_PIP-SCONN,HA
M_D_MA<15>               U5D1             DV49     SKX_EXT_B_BGA1-IC,TBD
M_D_MA<16>               J4B1             82       SCONN288_H44441004_PIP-SCONN,HA
M_D_MA<16>               J6M1             82       SCONN288_H44441003_PIP-SCONN,HA
M_D_MA<16>               U5D1             EA52     SKX_EXT_B_BGA1-IC,TBD
M_D_MA<17>               J4B1             234      SCONN288_H44441004_PIP-SCONN,HA
M_D_MA<17>               J6M1             234      SCONN288_H44441003_PIP-SCONN,HA
M_D_MA<17>               U5D1             EA46     SKX_EXT_B_BGA1-IC,TBD
M_D_ODT<0>               J4B1             87       SCONN288_H44441004_PIP-SCONN,HA
M_D_ODT<0>               U5D1             EE50     SKX_EXT_B_BGA1-IC,TBD
M_D_ODT<1>               J4B1             91       SCONN288_H44441004_PIP-SCONN,HA
M_D_ODT<1>               U5D1             EE48     SKX_EXT_B_BGA1-IC,TBD
M_D_ODT<2>               J6M1             87       SCONN288_H44441003_PIP-SCONN,HA
M_D_ODT<2>               U5D1             EA50     SKX_EXT_B_BGA1-IC,TBD
M_D_ODT<3>               J6M1             91       SCONN288_H44441003_PIP-SCONN,HA
M_D_ODT<3>               U5D1             EA48     SKX_EXT_B_BGA1-IC,TBD
M_D_PAR                  J4B1             222      SCONN288_H44441004_PIP-SCONN,HA
M_D_PAR                  J6M1             222      SCONN288_H44441003_PIP-SCONN,HA
M_D_PAR                  U5D1             ED53     SKX_EXT_B_BGA1-IC,TBD
M_D_VREF                 C4B12            1        CAP_A_0402V-0.01UF,25V,10%,X7RA
M_D_VREF                 C6M1             1        CAP_A_0402V-0.01UF,25V,10%,X7RA
M_D_VREF                 J4B1             146      SCONN288_H44441004_PIP-SCONN,HA
M_D_VREF                 J6M1             146      SCONN288_H44441003_PIP-SCONN,HA
M_D_VREF                 R6L16            1        RES_0402-1.00K,1%,1/16W,CHIP,GA
M_D_VREF                 R6M1             2        RES_0402-1.00K,1%,1/16W,CHIP,GA
M_D_VREF                 R6M2             2        RES_0402-2,1.0%,1/16W,CHIP,G21A
M_E_ACT_N                J4A2             62       SCONN288_H44441004_PIP-SCONN,HA
M_E_ACT_N                J6L2             62       SCONN288_H44441003_PIP-SCONN,HA
M_E_ACT_N                U5D1             DR62     SKX_EXT_B_BGA1-IC,TBD
M_E_ALERT_N              J4A2             208      SCONN288_H44441004_PIP-SCONN,HA
M_E_ALERT_N              J6L2             208      SCONN288_H44441003_PIP-SCONN,HA
M_E_ALERT_N              U5D1             DT61     SKX_EXT_B_BGA1-IC,TBD
M_E_BA<0>                J4A2             81       SCONN288_H44441004_PIP-SCONN,HA
M_E_BA<0>                J6L2             81       SCONN288_H44441003_PIP-SCONN,HA
M_E_BA<0>                U5D1             DM53     SKX_EXT_B_BGA1-IC,TBD
M_E_BA<1>                J4A2             224      SCONN288_H44441004_PIP-SCONN,HA
M_E_BA<1>                J6L2             224      SCONN288_H44441003_PIP-SCONN,HA
M_E_BA<1>                U5D1             DV55     SKX_EXT_B_BGA1-IC,TBD
M_E_BG<0>                J4A2             63       SCONN288_H44441004_PIP-SCONN,HA
M_E_BG<0>                J6L2             63       SCONN288_H44441003_PIP-SCONN,HA
M_E_BG<0>                U5D1             DJ62     SKX_EXT_B_BGA1-IC,TBD
M_E_BG<1>                J4A2             207      SCONN288_H44441004_PIP-SCONN,HA
M_E_BG<1>                J6L2             207      SCONN288_H44441003_PIP-SCONN,HA
M_E_BG<1>                U5D1             DM61     SKX_EXT_B_BGA1-IC,TBD
M_E_C<2>                 J4A2             235      SCONN288_H44441004_PIP-SCONN,HA
M_E_C<2>                 J6L2             235      SCONN288_H44441003_PIP-SCONN,HA
M_E_C<2>                 U5D1             DT47     SKX_EXT_B_BGA1-IC,TBD
M_E_CKE<0>               J4A2             60       SCONN288_H44441004_PIP-SCONN,HA
M_E_CKE<0>               U5D1             DM63     SKX_EXT_B_BGA1-IC,TBD
M_E_CKE<1>               J4A2             203      SCONN288_H44441004_PIP-SCONN,HA
M_E_CKE<1>               U5D1             DN64     SKX_EXT_B_BGA1-IC,TBD
M_E_CKE<2>               J6L2             60       SCONN288_H44441003_PIP-SCONN,HA
M_E_CKE<2>               U5D1             DL64     SKX_EXT_B_BGA1-IC,TBD
M_E_CKE<3>               J6L2             203      SCONN288_H44441003_PIP-SCONN,HA
M_E_CKE<3>               U5D1             DR64     SKX_EXT_B_BGA1-IC,TBD
M_E_CLK_DN<0>            J4A2             75       SCONN288_H44441004_PIP-SCONN,HA
M_E_CLK_DN<0>            U5D1             DM55     SKX_EXT_B_BGA1-IC,TBD
M_E_CLK_DN<1>            J4A2             219      SCONN288_H44441004_PIP-SCONN,HA
M_E_CLK_DN<1>            U5D1             DR54     SKX_EXT_B_BGA1-IC,TBD
M_E_CLK_DN<2>            J6L2             75       SCONN288_H44441003_PIP-SCONN,HA
M_E_CLK_DN<2>            U5D1             DM57     SKX_EXT_B_BGA1-IC,TBD
M_E_CLK_DN<3>            J6L2             219      SCONN288_H44441003_PIP-SCONN,HA
M_E_CLK_DN<3>            U5D1             DT57     SKX_EXT_B_BGA1-IC,TBD
M_E_CLK_DP<0>            J4A2             74       SCONN288_H44441004_PIP-SCONN,HA
M_E_CLK_DP<0>            U5D1             DN54     SKX_EXT_B_BGA1-IC,TBD
M_E_CLK_DP<1>            J4A2             218      SCONN288_H44441004_PIP-SCONN,HA
M_E_CLK_DP<1>            U5D1             DT53     SKX_EXT_B_BGA1-IC,TBD
M_E_CLK_DP<2>            J6L2             74       SCONN288_H44441003_PIP-SCONN,HA
M_E_CLK_DP<2>            U5D1             DN56     SKX_EXT_B_BGA1-IC,TBD
M_E_CLK_DP<3>            J6L2             218      SCONN288_H44441003_PIP-SCONN,HA
M_E_CLK_DP<3>            U5D1             DR56     SKX_EXT_B_BGA1-IC,TBD
M_E_CPU_VREF             C6L7             1        CAP_A_0402V-0.01UF,25V,10%,X7RA
M_E_CPU_VREF             R6L14            1        RES_0402-2,1.0%,1/16W,CHIP,G21A
M_E_CPU_VREF             U5D1             CT61     SKX_EXT_B_BGA1-IC,TBD
M_E_CS_N<0>              J4A2             84       SCONN288_H44441004_PIP-SCONN,HA
M_E_CS_N<0>              U5D1             DV51     SKX_EXT_B_BGA1-IC,TBD
M_E_CS_N<1>              J4A2             89       SCONN288_H44441004_PIP-SCONN,HA
M_E_CS_N<1>              U5D1             DN50     SKX_EXT_B_BGA1-IC,TBD
M_E_CS_N<2>              J4A2             93       SCONN288_H44441004_PIP-SCONN,HA
M_E_CS_N<2>              U5D1             DR46     SKX_EXT_B_BGA1-IC,TBD
M_E_CS_N<3>              J4A2             237      SCONN288_H44441004_PIP-SCONN,HA
M_E_CS_N<3>              U5D1             DK47     SKX_EXT_B_BGA1-IC,TBD
M_E_CS_N<4>              J6L2             84       SCONN288_H44441003_PIP-SCONN,HA
M_E_CS_N<4>              U5D1             DW50     SKX_EXT_B_BGA1-IC,TBD
M_E_CS_N<5>              J6L2             89       SCONN288_H44441003_PIP-SCONN,HA
M_E_CS_N<5>              U5D1             DM49     SKX_EXT_B_BGA1-IC,TBD
M_E_CS_N<6>              J6L2             93       SCONN288_H44441003_PIP-SCONN,HA
M_E_CS_N<6>              U5D1             DT45     SKX_EXT_B_BGA1-IC,TBD
M_E_CS_N<7>              J6L2             237      SCONN288_H44441003_PIP-SCONN,HA
M_E_CS_N<7>              U5D1             DN46     SKX_EXT_B_BGA1-IC,TBD
M_E_DQ<0>                J4A2             150      SCONN288_H44441004_PIP-SCONN,HA
M_E_DQ<0>                J6L2             5        SCONN288_H44441003_PIP-SCONN,HA
M_E_DQ<0>                U5D1             CM79     SKX_EXT_B_BGA1-IC,TBD
M_E_DQ<1>                J4A2             5        SCONN288_H44441004_PIP-SCONN,HA
M_E_DQ<1>                J6L2             150      SCONN288_H44441003_PIP-SCONN,HA
M_E_DQ<1>                U5D1             CK81     SKX_EXT_B_BGA1-IC,TBD
M_E_DQ<2>                J4A2             157      SCONN288_H44441004_PIP-SCONN,HA
M_E_DQ<2>                J6L2             12       SCONN288_H44441003_PIP-SCONN,HA
M_E_DQ<2>                U5D1             CT81     SKX_EXT_B_BGA1-IC,TBD
M_E_DQ<3>                J4A2             12       SCONN288_H44441004_PIP-SCONN,HA
M_E_DQ<3>                J6L2             157      SCONN288_H44441003_PIP-SCONN,HA
M_E_DQ<3>                U5D1             CR82     SKX_EXT_B_BGA1-IC,TBD
M_E_DQ<4>                J4A2             148      SCONN288_H44441004_PIP-SCONN,HA
M_E_DQ<4>                J6L2             3        SCONN288_H44441003_PIP-SCONN,HA
M_E_DQ<4>                U5D1             CK79     SKX_EXT_B_BGA1-IC,TBD
M_E_DQ<5>                J4A2             3        SCONN288_H44441004_PIP-SCONN,HA
M_E_DQ<5>                J6L2             148      SCONN288_H44441003_PIP-SCONN,HA
M_E_DQ<5>                U5D1             CJ80     SKX_EXT_B_BGA1-IC,TBD
M_E_DQ<6>                J4A2             155      SCONN288_H44441004_PIP-SCONN,HA
M_E_DQ<6>                J6L2             10       SCONN288_H44441003_PIP-SCONN,HA
M_E_DQ<6>                U5D1             CR80     SKX_EXT_B_BGA1-IC,TBD
M_E_DQ<7>                J4A2             10       SCONN288_H44441004_PIP-SCONN,HA
M_E_DQ<7>                J6L2             155      SCONN288_H44441003_PIP-SCONN,HA
M_E_DQ<7>                U5D1             CN82     SKX_EXT_B_BGA1-IC,TBD
M_E_DQ<8>                J4A2             161      SCONN288_H44441004_PIP-SCONN,HA
M_E_DQ<8>                J6L2             16       SCONN288_H44441003_PIP-SCONN,HA
M_E_DQ<8>                U5D1             DB79     SKX_EXT_B_BGA1-IC,TBD
M_E_DQ<9>                J4A2             16       SCONN288_H44441004_PIP-SCONN,HA
M_E_DQ<9>                J6L2             161      SCONN288_H44441003_PIP-SCONN,HA
M_E_DQ<9>                U5D1             CY81     SKX_EXT_B_BGA1-IC,TBD
M_E_DQ<10>               J4A2             168      SCONN288_H44441004_PIP-SCONN,HA
M_E_DQ<10>               J6L2             23       SCONN288_H44441003_PIP-SCONN,HA
M_E_DQ<10>               U5D1             DE80     SKX_EXT_B_BGA1-IC,TBD
M_E_DQ<11>               J4A2             23       SCONN288_H44441004_PIP-SCONN,HA
M_E_DQ<11>               J6L2             168      SCONN288_H44441003_PIP-SCONN,HA
M_E_DQ<11>               U5D1             DF81     SKX_EXT_B_BGA1-IC,TBD
M_E_DQ<12>               J4A2             159      SCONN288_H44441004_PIP-SCONN,HA
M_E_DQ<12>               J6L2             14       SCONN288_H44441003_PIP-SCONN,HA
M_E_DQ<12>               U5D1             CY79     SKX_EXT_B_BGA1-IC,TBD
M_E_DQ<13>               J4A2             14       SCONN288_H44441004_PIP-SCONN,HA
M_E_DQ<13>               J6L2             159      SCONN288_H44441003_PIP-SCONN,HA
M_E_DQ<13>               U5D1             CW80     SKX_EXT_B_BGA1-IC,TBD
M_E_DQ<14>               J4A2             166      SCONN288_H44441004_PIP-SCONN,HA
M_E_DQ<14>               J6L2             21       SCONN288_H44441003_PIP-SCONN,HA
M_E_DQ<14>               U5D1             DC82     SKX_EXT_B_BGA1-IC,TBD
M_E_DQ<15>               J4A2             21       SCONN288_H44441004_PIP-SCONN,HA
M_E_DQ<15>               J6L2             166      SCONN288_H44441003_PIP-SCONN,HA
M_E_DQ<15>               U5D1             DE82     SKX_EXT_B_BGA1-IC,TBD
M_E_DQ<16>               J4A2             172      SCONN288_H44441004_PIP-SCONN,HA
M_E_DQ<16>               J6L2             27       SCONN288_H44441003_PIP-SCONN,HA
M_E_DQ<16>               U5D1             DW80     SKX_EXT_B_BGA1-IC,TBD
M_E_DQ<17>               J4A2             27       SCONN288_H44441004_PIP-SCONN,HA
M_E_DQ<17>               J6L2             172      SCONN288_H44441003_PIP-SCONN,HA
M_E_DQ<17>               U5D1             EC80     SKX_EXT_B_BGA1-IC,TBD
M_E_DQ<18>               J4A2             179      SCONN288_H44441004_PIP-SCONN,HA
M_E_DQ<18>               J6L2             34       SCONN288_H44441003_PIP-SCONN,HA
M_E_DQ<18>               U5D1             DY77     SKX_EXT_B_BGA1-IC,TBD
M_E_DQ<19>               J4A2             34       SCONN288_H44441004_PIP-SCONN,HA
M_E_DQ<19>               J6L2             179      SCONN288_H44441003_PIP-SCONN,HA
M_E_DQ<19>               U5D1             EB77     SKX_EXT_B_BGA1-IC,TBD
M_E_DQ<20>               J4A2             170      SCONN288_H44441004_PIP-SCONN,HA
M_E_DQ<20>               J6L2             25       SCONN288_H44441003_PIP-SCONN,HA
M_E_DQ<20>               U5D1             DY81     SKX_EXT_B_BGA1-IC,TBD
M_E_DQ<21>               J4A2             25       SCONN288_H44441004_PIP-SCONN,HA
M_E_DQ<21>               J6L2             170      SCONN288_H44441003_PIP-SCONN,HA
M_E_DQ<21>               U5D1             EB81     SKX_EXT_B_BGA1-IC,TBD
M_E_DQ<22>               J4A2             177      SCONN288_H44441004_PIP-SCONN,HA
M_E_DQ<22>               J6L2             32       SCONN288_H44441003_PIP-SCONN,HA
M_E_DQ<22>               U5D1             DW78     SKX_EXT_B_BGA1-IC,TBD
M_E_DQ<23>               J4A2             32       SCONN288_H44441004_PIP-SCONN,HA
M_E_DQ<23>               J6L2             177      SCONN288_H44441003_PIP-SCONN,HA
M_E_DQ<23>               U5D1             EC78     SKX_EXT_B_BGA1-IC,TBD
M_E_DQ<24>               J4A2             183      SCONN288_H44441004_PIP-SCONN,HA
M_E_DQ<24>               J6L2             38       SCONN288_H44441003_PIP-SCONN,HA
M_E_DQ<24>               U5D1             ED75     SKX_EXT_B_BGA1-IC,TBD
M_E_DQ<25>               J4A2             38       SCONN288_H44441004_PIP-SCONN,HA
M_E_DQ<25>               J6L2             183      SCONN288_H44441003_PIP-SCONN,HA
M_E_DQ<25>               U5D1             EE74     SKX_EXT_B_BGA1-IC,TBD
M_E_DQ<26>               J4A2             190      SCONN288_H44441004_PIP-SCONN,HA
M_E_DQ<26>               J6L2             45       SCONN288_H44441003_PIP-SCONN,HA
M_E_DQ<26>               U5D1             EB71     SKX_EXT_B_BGA1-IC,TBD
M_E_DQ<27>               J4A2             45       SCONN288_H44441004_PIP-SCONN,HA
M_E_DQ<27>               J6L2             190      SCONN288_H44441003_PIP-SCONN,HA
M_E_DQ<27>               U5D1             ED71     SKX_EXT_B_BGA1-IC,TBD
M_E_DQ<28>               J4A2             181      SCONN288_H44441004_PIP-SCONN,HA
M_E_DQ<28>               J6L2             36       SCONN288_H44441003_PIP-SCONN,HA
M_E_DQ<28>               U5D1             EA74     SKX_EXT_B_BGA1-IC,TBD
M_E_DQ<29>               J4A2             36       SCONN288_H44441004_PIP-SCONN,HA
M_E_DQ<29>               J6L2             181      SCONN288_H44441003_PIP-SCONN,HA
M_E_DQ<29>               U5D1             EB75     SKX_EXT_B_BGA1-IC,TBD
M_E_DQ<30>               J4A2             188      SCONN288_H44441004_PIP-SCONN,HA
M_E_DQ<30>               J6L2             43       SCONN288_H44441003_PIP-SCONN,HA
M_E_DQ<30>               U5D1             EA72     SKX_EXT_B_BGA1-IC,TBD
M_E_DQ<31>               J4A2             43       SCONN288_H44441004_PIP-SCONN,HA
M_E_DQ<31>               J6L2             188      SCONN288_H44441003_PIP-SCONN,HA
M_E_DQ<31>               U5D1             EE72     SKX_EXT_B_BGA1-IC,TBD
M_E_DQ<32>               J4A2             242      SCONN288_H44441004_PIP-SCONN,HA
M_E_DQ<32>               J6L2             97       SCONN288_H44441003_PIP-SCONN,HA
M_E_DQ<32>               U5D1             DU42     SKX_EXT_B_BGA1-IC,TBD
M_E_DQ<33>               J4A2             97       SCONN288_H44441004_PIP-SCONN,HA
M_E_DQ<33>               J6L2             242      SCONN288_H44441003_PIP-SCONN,HA
M_E_DQ<33>               U5D1             DW42     SKX_EXT_B_BGA1-IC,TBD
M_E_DQ<34>               J4A2             249      SCONN288_H44441004_PIP-SCONN,HA
M_E_DQ<34>               J6L2             104      SCONN288_H44441003_PIP-SCONN,HA
M_E_DQ<34>               U5D1             DP39     SKX_EXT_B_BGA1-IC,TBD
M_E_DQ<35>               J4A2             104      SCONN288_H44441004_PIP-SCONN,HA
M_E_DQ<35>               J6L2             249      SCONN288_H44441003_PIP-SCONN,HA
M_E_DQ<35>               U5D1             DT39     SKX_EXT_B_BGA1-IC,TBD
M_E_DQ<36>               J4A2             240      SCONN288_H44441004_PIP-SCONN,HA
M_E_DQ<36>               J6L2             95       SCONN288_H44441003_PIP-SCONN,HA
M_E_DQ<36>               U5D1             DL42     SKX_EXT_B_BGA1-IC,TBD
M_E_DQ<37>               J4A2             95       SCONN288_H44441004_PIP-SCONN,HA
M_E_DQ<37>               J6L2             240      SCONN288_H44441003_PIP-SCONN,HA
M_E_DQ<37>               U5D1             DN42     SKX_EXT_B_BGA1-IC,TBD
M_E_DQ<38>               J4A2             247      SCONN288_H44441004_PIP-SCONN,HA
M_E_DQ<38>               J6L2             102      SCONN288_H44441003_PIP-SCONN,HA
M_E_DQ<38>               U5D1             DN40     SKX_EXT_B_BGA1-IC,TBD
M_E_DQ<39>               J4A2             102      SCONN288_H44441004_PIP-SCONN,HA
M_E_DQ<39>               J6L2             247      SCONN288_H44441003_PIP-SCONN,HA
M_E_DQ<39>               U5D1             DU40     SKX_EXT_B_BGA1-IC,TBD
M_E_DQ<40>               J4A2             253      SCONN288_H44441004_PIP-SCONN,HA
M_E_DQ<40>               J6L2             108      SCONN288_H44441003_PIP-SCONN,HA
M_E_DQ<40>               U5D1             EC34     SKX_EXT_B_BGA1-IC,TBD
M_E_DQ<41>               J4A2             108      SCONN288_H44441004_PIP-SCONN,HA
M_E_DQ<41>               J6L2             253      SCONN288_H44441003_PIP-SCONN,HA
M_E_DQ<41>               U5D1             ED33     SKX_EXT_B_BGA1-IC,TBD
M_E_DQ<42>               J4A2             260      SCONN288_H44441004_PIP-SCONN,HA
M_E_DQ<42>               J6L2             115      SCONN288_H44441003_PIP-SCONN,HA
M_E_DQ<42>               U5D1             EA30     SKX_EXT_B_BGA1-IC,TBD
M_E_DQ<43>               J4A2             115      SCONN288_H44441004_PIP-SCONN,HA
M_E_DQ<43>               J6L2             260      SCONN288_H44441003_PIP-SCONN,HA
M_E_DQ<43>               U5D1             EC30     SKX_EXT_B_BGA1-IC,TBD
M_E_DQ<44>               J4A2             251      SCONN288_H44441004_PIP-SCONN,HA
M_E_DQ<44>               J6L2             106      SCONN288_H44441003_PIP-SCONN,HA
M_E_DQ<44>               U5D1             DY33     SKX_EXT_B_BGA1-IC,TBD
M_E_DQ<45>               J4A2             106      SCONN288_H44441004_PIP-SCONN,HA
M_E_DQ<45>               J6L2             251      SCONN288_H44441003_PIP-SCONN,HA
M_E_DQ<45>               U5D1             EA34     SKX_EXT_B_BGA1-IC,TBD
M_E_DQ<46>               J4A2             258      SCONN288_H44441004_PIP-SCONN,HA
M_E_DQ<46>               J6L2             113      SCONN288_H44441003_PIP-SCONN,HA
M_E_DQ<46>               U5D1             DY31     SKX_EXT_B_BGA1-IC,TBD
M_E_DQ<47>               J4A2             113      SCONN288_H44441004_PIP-SCONN,HA
M_E_DQ<47>               J6L2             258      SCONN288_H44441003_PIP-SCONN,HA
M_E_DQ<47>               U5D1             ED31     SKX_EXT_B_BGA1-IC,TBD
M_E_DQ<48>               J4A2             264      SCONN288_H44441004_PIP-SCONN,HA
M_E_DQ<48>               J6L2             119      SCONN288_H44441003_PIP-SCONN,HA
M_E_DQ<48>               U5D1             EC28     SKX_EXT_B_BGA1-IC,TBD
M_E_DQ<49>               J4A2             119      SCONN288_H44441004_PIP-SCONN,HA
M_E_DQ<49>               J6L2             264      SCONN288_H44441003_PIP-SCONN,HA
M_E_DQ<49>               U5D1             ED27     SKX_EXT_B_BGA1-IC,TBD
M_E_DQ<50>               J4A2             271      SCONN288_H44441004_PIP-SCONN,HA
M_E_DQ<50>               J6L2             126      SCONN288_H44441003_PIP-SCONN,HA
M_E_DQ<50>               U5D1             EA24     SKX_EXT_B_BGA1-IC,TBD
M_E_DQ<51>               J4A2             126      SCONN288_H44441004_PIP-SCONN,HA
M_E_DQ<51>               J6L2             271      SCONN288_H44441003_PIP-SCONN,HA
M_E_DQ<51>               U5D1             EC24     SKX_EXT_B_BGA1-IC,TBD
M_E_DQ<52>               J4A2             262      SCONN288_H44441004_PIP-SCONN,HA
M_E_DQ<52>               J6L2             117      SCONN288_H44441003_PIP-SCONN,HA
M_E_DQ<52>               U5D1             DY27     SKX_EXT_B_BGA1-IC,TBD
M_E_DQ<53>               J4A2             117      SCONN288_H44441004_PIP-SCONN,HA
M_E_DQ<53>               J6L2             262      SCONN288_H44441003_PIP-SCONN,HA
M_E_DQ<53>               U5D1             EA28     SKX_EXT_B_BGA1-IC,TBD
M_E_DQ<54>               J4A2             269      SCONN288_H44441004_PIP-SCONN,HA
M_E_DQ<54>               J6L2             124      SCONN288_H44441003_PIP-SCONN,HA
M_E_DQ<54>               U5D1             DY25     SKX_EXT_B_BGA1-IC,TBD
M_E_DQ<55>               J4A2             124      SCONN288_H44441004_PIP-SCONN,HA
M_E_DQ<55>               J6L2             269      SCONN288_H44441003_PIP-SCONN,HA
M_E_DQ<55>               U5D1             ED25     SKX_EXT_B_BGA1-IC,TBD
M_E_DQ<56>               J4A2             275      SCONN288_H44441004_PIP-SCONN,HA
M_E_DQ<56>               J6L2             130      SCONN288_H44441003_PIP-SCONN,HA
M_E_DQ<56>               U5D1             DF27     SKX_EXT_B_BGA1-IC,TBD
M_E_DQ<57>               J4A2             130      SCONN288_H44441004_PIP-SCONN,HA
M_E_DQ<57>               J6L2             275      SCONN288_H44441003_PIP-SCONN,HA
M_E_DQ<57>               U5D1             DK27     SKX_EXT_B_BGA1-IC,TBD
M_E_DQ<58>               J4A2             282      SCONN288_H44441004_PIP-SCONN,HA
M_E_DQ<58>               J6L2             137      SCONN288_H44441003_PIP-SCONN,HA
M_E_DQ<58>               U5D1             DD25     SKX_EXT_B_BGA1-IC,TBD
M_E_DQ<59>               J4A2             137      SCONN288_H44441004_PIP-SCONN,HA
M_E_DQ<59>               J6L2             282      SCONN288_H44441003_PIP-SCONN,HA
M_E_DQ<59>               U5D1             DJ24     SKX_EXT_B_BGA1-IC,TBD
M_E_DQ<60>               J4A2             273      SCONN288_H44441004_PIP-SCONN,HA
M_E_DQ<60>               J6L2             128      SCONN288_H44441003_PIP-SCONN,HA
M_E_DQ<60>               U5D1             DG28     SKX_EXT_B_BGA1-IC,TBD
M_E_DQ<61>               J4A2             128      SCONN288_H44441004_PIP-SCONN,HA
M_E_DQ<61>               J6L2             273      SCONN288_H44441003_PIP-SCONN,HA
M_E_DQ<61>               U5D1             DJ28     SKX_EXT_B_BGA1-IC,TBD
M_E_DQ<62>               J4A2             280      SCONN288_H44441004_PIP-SCONN,HA
M_E_DQ<62>               J6L2             135      SCONN288_H44441003_PIP-SCONN,HA
M_E_DQ<62>               U5D1             DF25     SKX_EXT_B_BGA1-IC,TBD
M_E_DQ<63>               J4A2             135      SCONN288_H44441004_PIP-SCONN,HA
M_E_DQ<63>               J6L2             280      SCONN288_H44441003_PIP-SCONN,HA
M_E_DQ<63>               U5D1             DK25     SKX_EXT_B_BGA1-IC,TBD
M_E_DQS_DN<0>            J4A2             152      SCONN288_H44441004_PIP-SCONN,HA
M_E_DQS_DN<0>            J6L2             152      SCONN288_H44441003_PIP-SCONN,HA
M_E_DQS_DN<0>            U5D1             CL82     SKX_EXT_B_BGA1-IC,TBD
M_E_DQS_DN<1>            J4A2             163      SCONN288_H44441004_PIP-SCONN,HA
M_E_DQS_DN<1>            J6L2             163      SCONN288_H44441003_PIP-SCONN,HA
M_E_DQS_DN<1>            U5D1             DA82     SKX_EXT_B_BGA1-IC,TBD
M_E_DQS_DN<2>            J4A2             174      SCONN288_H44441004_PIP-SCONN,HA
M_E_DQS_DN<2>            J6L2             174      SCONN288_H44441003_PIP-SCONN,HA
M_E_DQS_DN<2>            U5D1             ED79     SKX_EXT_B_BGA1-IC,TBD
M_E_DQS_DN<3>            J4A2             185      SCONN288_H44441004_PIP-SCONN,HA
M_E_DQS_DN<3>            J6L2             185      SCONN288_H44441003_PIP-SCONN,HA
M_E_DQS_DN<3>            U5D1             EF73     SKX_EXT_B_BGA1-IC,TBD
M_E_DQS_DN<4>            J4A2             244      SCONN288_H44441004_PIP-SCONN,HA
M_E_DQS_DN<4>            J6L2             244      SCONN288_H44441003_PIP-SCONN,HA
M_E_DQS_DN<4>            U5D1             DV41     SKX_EXT_B_BGA1-IC,TBD
M_E_DQS_DN<5>            J4A2             255      SCONN288_H44441004_PIP-SCONN,HA
M_E_DQS_DN<5>            J6L2             255      SCONN288_H44441003_PIP-SCONN,HA
M_E_DQS_DN<5>            U5D1             EE32     SKX_EXT_B_BGA1-IC,TBD
M_E_DQS_DN<6>            J4A2             266      SCONN288_H44441004_PIP-SCONN,HA
M_E_DQS_DN<6>            J6L2             266      SCONN288_H44441003_PIP-SCONN,HA
M_E_DQS_DN<6>            U5D1             EE26     SKX_EXT_B_BGA1-IC,TBD
M_E_DQS_DN<7>            J4A2             277      SCONN288_H44441004_PIP-SCONN,HA
M_E_DQS_DN<7>            J6L2             277      SCONN288_H44441003_PIP-SCONN,HA
M_E_DQS_DN<7>            U5D1             DL26     SKX_EXT_B_BGA1-IC,TBD
M_E_DQS_DN<8>            J4A2             196      SCONN288_H44441004_PIP-SCONN,HA
M_E_DQS_DN<8>            J6L2             196      SCONN288_H44441003_PIP-SCONN,HA
M_E_DQS_DN<8>            U5D1             EB67     SKX_EXT_B_BGA1-IC,TBD
M_E_DQS_DN<9>            J4A2             8        SCONN288_H44441004_PIP-SCONN,HA
M_E_DQS_DN<9>            J6L2             8        SCONN288_H44441003_PIP-SCONN,HA
M_E_DQS_DN<9>            U5D1             CN80     SKX_EXT_B_BGA1-IC,TBD
M_E_DQS_DN<10>           J4A2             19       SCONN288_H44441004_PIP-SCONN,HA
M_E_DQS_DN<10>           J6L2             19       SCONN288_H44441003_PIP-SCONN,HA
M_E_DQS_DN<10>           U5D1             DC80     SKX_EXT_B_BGA1-IC,TBD
M_E_DQS_DN<11>           J4A2             30       SCONN288_H44441004_PIP-SCONN,HA
M_E_DQS_DN<11>           J6L2             30       SCONN288_H44441003_PIP-SCONN,HA
M_E_DQS_DN<11>           U5D1             DY79     SKX_EXT_B_BGA1-IC,TBD
M_E_DQS_DN<12>           J4A2             41       SCONN288_H44441004_PIP-SCONN,HA
M_E_DQS_DN<12>           J6L2             41       SCONN288_H44441003_PIP-SCONN,HA
M_E_DQS_DN<12>           U5D1             EB73     SKX_EXT_B_BGA1-IC,TBD
M_E_DQS_DN<13>           J4A2             100      SCONN288_H44441004_PIP-SCONN,HA
M_E_DQS_DN<13>           J6L2             100      SCONN288_H44441003_PIP-SCONN,HA
M_E_DQS_DN<13>           U5D1             DP41     SKX_EXT_B_BGA1-IC,TBD
M_E_DQS_DN<14>           J4A2             111      SCONN288_H44441004_PIP-SCONN,HA
M_E_DQS_DN<14>           J6L2             111      SCONN288_H44441003_PIP-SCONN,HA
M_E_DQS_DN<14>           U5D1             EA32     SKX_EXT_B_BGA1-IC,TBD
M_E_DQS_DN<15>           J4A2             122      SCONN288_H44441004_PIP-SCONN,HA
M_E_DQS_DN<15>           J6L2             122      SCONN288_H44441003_PIP-SCONN,HA
M_E_DQS_DN<15>           U5D1             EA26     SKX_EXT_B_BGA1-IC,TBD
M_E_DQS_DN<16>           J4A2             133      SCONN288_H44441004_PIP-SCONN,HA
M_E_DQS_DN<16>           J6L2             133      SCONN288_H44441003_PIP-SCONN,HA
M_E_DQS_DN<16>           U5D1             DG26     SKX_EXT_B_BGA1-IC,TBD
M_E_DQS_DN<17>           J4A2             52       SCONN288_H44441004_PIP-SCONN,HA
M_E_DQS_DN<17>           J6L2             52       SCONN288_H44441003_PIP-SCONN,HA
M_E_DQS_DN<17>           U5D1             DV67     SKX_EXT_B_BGA1-IC,TBD
M_E_DQS_DP<0>            J4A2             153      SCONN288_H44441004_PIP-SCONN,HA
M_E_DQS_DP<0>            J6L2             153      SCONN288_H44441003_PIP-SCONN,HA
M_E_DQS_DP<0>            U5D1             CM81     SKX_EXT_B_BGA1-IC,TBD
M_E_DQS_DP<1>            J4A2             164      SCONN288_H44441004_PIP-SCONN,HA
M_E_DQS_DP<1>            J6L2             164      SCONN288_H44441003_PIP-SCONN,HA
M_E_DQS_DP<1>            U5D1             DB81     SKX_EXT_B_BGA1-IC,TBD
M_E_DQS_DP<2>            J4A2             175      SCONN288_H44441004_PIP-SCONN,HA
M_E_DQS_DP<2>            J6L2             175      SCONN288_H44441003_PIP-SCONN,HA
M_E_DQS_DP<2>            U5D1             EB79     SKX_EXT_B_BGA1-IC,TBD
M_E_DQS_DP<3>            J4A2             186      SCONN288_H44441004_PIP-SCONN,HA
M_E_DQS_DP<3>            J6L2             186      SCONN288_H44441003_PIP-SCONN,HA
M_E_DQS_DP<3>            U5D1             ED73     SKX_EXT_B_BGA1-IC,TBD
M_E_DQS_DP<4>            J4A2             245      SCONN288_H44441004_PIP-SCONN,HA
M_E_DQS_DP<4>            J6L2             245      SCONN288_H44441003_PIP-SCONN,HA
M_E_DQS_DP<4>            U5D1             DT41     SKX_EXT_B_BGA1-IC,TBD
M_E_DQS_DP<5>            J4A2             256      SCONN288_H44441004_PIP-SCONN,HA
M_E_DQS_DP<5>            J6L2             256      SCONN288_H44441003_PIP-SCONN,HA
M_E_DQS_DP<5>            U5D1             EC32     SKX_EXT_B_BGA1-IC,TBD
M_E_DQS_DP<6>            J4A2             267      SCONN288_H44441004_PIP-SCONN,HA
M_E_DQS_DP<6>            J6L2             267      SCONN288_H44441003_PIP-SCONN,HA
M_E_DQS_DP<6>            U5D1             EC26     SKX_EXT_B_BGA1-IC,TBD
M_E_DQS_DP<7>            J4A2             278      SCONN288_H44441004_PIP-SCONN,HA
M_E_DQS_DP<7>            J6L2             278      SCONN288_H44441003_PIP-SCONN,HA
M_E_DQS_DP<7>            U5D1             DJ26     SKX_EXT_B_BGA1-IC,TBD
M_E_DQS_DP<8>            J4A2             197      SCONN288_H44441004_PIP-SCONN,HA
M_E_DQS_DP<8>            J6L2             197      SCONN288_H44441003_PIP-SCONN,HA
M_E_DQS_DP<8>            U5D1             DY67     SKX_EXT_B_BGA1-IC,TBD
M_E_DQS_DP<9>            J4A2             7        SCONN288_H44441004_PIP-SCONN,HA
M_E_DQS_DP<9>            J6L2             7        SCONN288_H44441003_PIP-SCONN,HA
M_E_DQS_DP<9>            U5D1             CP79     SKX_EXT_B_BGA1-IC,TBD
M_E_DQS_DP<10>           J4A2             18       SCONN288_H44441004_PIP-SCONN,HA
M_E_DQS_DP<10>           J6L2             18       SCONN288_H44441003_PIP-SCONN,HA
M_E_DQS_DP<10>           U5D1             DD79     SKX_EXT_B_BGA1-IC,TBD
M_E_DQS_DP<11>           J4A2             29       SCONN288_H44441004_PIP-SCONN,HA
M_E_DQS_DP<11>           J6L2             29       SCONN288_H44441003_PIP-SCONN,HA
M_E_DQS_DP<11>           U5D1             DV79     SKX_EXT_B_BGA1-IC,TBD
M_E_DQS_DP<12>           J4A2             40       SCONN288_H44441004_PIP-SCONN,HA
M_E_DQS_DP<12>           J6L2             40       SCONN288_H44441003_PIP-SCONN,HA
M_E_DQS_DP<12>           U5D1             DY73     SKX_EXT_B_BGA1-IC,TBD
M_E_DQS_DP<13>           J4A2             99       SCONN288_H44441004_PIP-SCONN,HA
M_E_DQS_DP<13>           J6L2             99       SCONN288_H44441003_PIP-SCONN,HA
M_E_DQS_DP<13>           U5D1             DM41     SKX_EXT_B_BGA1-IC,TBD
M_E_DQS_DP<14>           J4A2             110      SCONN288_H44441004_PIP-SCONN,HA
M_E_DQS_DP<14>           J6L2             110      SCONN288_H44441003_PIP-SCONN,HA
M_E_DQS_DP<14>           U5D1             DW32     SKX_EXT_B_BGA1-IC,TBD
M_E_DQS_DP<15>           J4A2             121      SCONN288_H44441004_PIP-SCONN,HA
M_E_DQS_DP<15>           J6L2             121      SCONN288_H44441003_PIP-SCONN,HA
M_E_DQS_DP<15>           U5D1             DW26     SKX_EXT_B_BGA1-IC,TBD
M_E_DQS_DP<16>           J4A2             132      SCONN288_H44441004_PIP-SCONN,HA
M_E_DQS_DP<16>           J6L2             132      SCONN288_H44441003_PIP-SCONN,HA
M_E_DQS_DP<16>           U5D1             DE26     SKX_EXT_B_BGA1-IC,TBD
M_E_DQS_DP<17>           J4A2             51       SCONN288_H44441004_PIP-SCONN,HA
M_E_DQS_DP<17>           J6L2             51       SCONN288_H44441003_PIP-SCONN,HA
M_E_DQS_DP<17>           U5D1             DT67     SKX_EXT_B_BGA1-IC,TBD
M_E_ECC<0>               J4A2             194      SCONN288_H44441004_PIP-SCONN,HA
M_E_ECC<0>               J6L2             49       SCONN288_H44441003_PIP-SCONN,HA
M_E_ECC<0>               U5D1             DY69     SKX_EXT_B_BGA1-IC,TBD
M_E_ECC<1>               J4A2             49       SCONN288_H44441004_PIP-SCONN,HA
M_E_ECC<1>               J6L2             194      SCONN288_H44441003_PIP-SCONN,HA
M_E_ECC<1>               U5D1             EA68     SKX_EXT_B_BGA1-IC,TBD
M_E_ECC<2>               J4A2             201      SCONN288_H44441004_PIP-SCONN,HA
M_E_ECC<2>               J6L2             56       SCONN288_H44441003_PIP-SCONN,HA
M_E_ECC<2>               U5D1             DV65     SKX_EXT_B_BGA1-IC,TBD
M_E_ECC<3>               J4A2             56       SCONN288_H44441004_PIP-SCONN,HA
M_E_ECC<3>               J6L2             201      SCONN288_H44441003_PIP-SCONN,HA
M_E_ECC<3>               U5D1             DY65     SKX_EXT_B_BGA1-IC,TBD
M_E_ECC<4>               J4A2             192      SCONN288_H44441004_PIP-SCONN,HA
M_E_ECC<4>               J6L2             47       SCONN288_H44441003_PIP-SCONN,HA
M_E_ECC<4>               U5D1             DU68     SKX_EXT_B_BGA1-IC,TBD
M_E_ECC<5>               J4A2             47       SCONN288_H44441004_PIP-SCONN,HA
M_E_ECC<5>               J6L2             192      SCONN288_H44441003_PIP-SCONN,HA
M_E_ECC<5>               U5D1             DV69     SKX_EXT_B_BGA1-IC,TBD
M_E_ECC<6>               J4A2             199      SCONN288_H44441004_PIP-SCONN,HA
M_E_ECC<6>               J6L2             54       SCONN288_H44441003_PIP-SCONN,HA
M_E_ECC<6>               U5D1             DU66     SKX_EXT_B_BGA1-IC,TBD
M_E_ECC<7>               J4A2             54       SCONN288_H44441004_PIP-SCONN,HA
M_E_ECC<7>               J6L2             199      SCONN288_H44441003_PIP-SCONN,HA
M_E_ECC<7>               U5D1             EA66     SKX_EXT_B_BGA1-IC,TBD
M_E_MA<0>                J4A2             79       SCONN288_H44441004_PIP-SCONN,HA
M_E_MA<0>                J6L2             79       SCONN288_H44441003_PIP-SCONN,HA
M_E_MA<0>                U5D1             DW52     SKX_EXT_B_BGA1-IC,TBD
M_E_MA<1>                J4A2             72       SCONN288_H44441004_PIP-SCONN,HA
M_E_MA<1>                J6L2             72       SCONN288_H44441003_PIP-SCONN,HA
M_E_MA<1>                U5D1             DW58     SKX_EXT_B_BGA1-IC,TBD
M_E_MA<2>                J4A2             216      SCONN288_H44441004_PIP-SCONN,HA
M_E_MA<2>                J6L2             216      SCONN288_H44441003_PIP-SCONN,HA
M_E_MA<2>                U5D1             DV57     SKX_EXT_B_BGA1-IC,TBD
M_E_MA<3>                J4A2             71       SCONN288_H44441004_PIP-SCONN,HA
M_E_MA<3>                J6L2             71       SCONN288_H44441003_PIP-SCONN,HA
M_E_MA<3>                U5D1             DR58     SKX_EXT_B_BGA1-IC,TBD
M_E_MA<4>                J4A2             214      SCONN288_H44441004_PIP-SCONN,HA
M_E_MA<4>                J6L2             214      SCONN288_H44441003_PIP-SCONN,HA
M_E_MA<4>                U5D1             DT59     SKX_EXT_B_BGA1-IC,TBD
M_E_MA<5>                J4A2             213      SCONN288_H44441004_PIP-SCONN,HA
M_E_MA<5>                J6L2             213      SCONN288_H44441003_PIP-SCONN,HA
M_E_MA<5>                U5D1             DN58     SKX_EXT_B_BGA1-IC,TBD
M_E_MA<6>                J4A2             69       SCONN288_H44441004_PIP-SCONN,HA
M_E_MA<6>                J6L2             69       SCONN288_H44441003_PIP-SCONN,HA
M_E_MA<6>                U5D1             DM59     SKX_EXT_B_BGA1-IC,TBD
M_E_MA<7>                J4A2             211      SCONN288_H44441004_PIP-SCONN,HA
M_E_MA<7>                J6L2             211      SCONN288_H44441003_PIP-SCONN,HA
M_E_MA<7>                U5D1             DK61     SKX_EXT_B_BGA1-IC,TBD
M_E_MA<8>                J4A2             68       SCONN288_H44441004_PIP-SCONN,HA
M_E_MA<8>                J6L2             68       SCONN288_H44441003_PIP-SCONN,HA
M_E_MA<8>                U5D1             DJ60     SKX_EXT_B_BGA1-IC,TBD
M_E_MA<9>                J4A2             66       SCONN288_H44441004_PIP-SCONN,HA
M_E_MA<9>                J6L2             66       SCONN288_H44441003_PIP-SCONN,HA
M_E_MA<9>                U5D1             DV59     SKX_EXT_B_BGA1-IC,TBD
M_E_MA<10>               J4A2             225      SCONN288_H44441004_PIP-SCONN,HA
M_E_MA<10>               J6L2             225      SCONN288_H44441003_PIP-SCONN,HA
M_E_MA<10>               U5D1             DT55     SKX_EXT_B_BGA1-IC,TBD
M_E_MA<11>               J4A2             210      SCONN288_H44441004_PIP-SCONN,HA
M_E_MA<11>               J6L2             210      SCONN288_H44441003_PIP-SCONN,HA
M_E_MA<11>               U5D1             DR60     SKX_EXT_B_BGA1-IC,TBD
M_E_MA<12>               J4A2             65       SCONN288_H44441004_PIP-SCONN,HA
M_E_MA<12>               J6L2             65       SCONN288_H44441003_PIP-SCONN,HA
M_E_MA<12>               U5D1             DN60     SKX_EXT_B_BGA1-IC,TBD
M_E_MA<13>               J4A2             232      SCONN288_H44441004_PIP-SCONN,HA
M_E_MA<13>               J6L2             232      SCONN288_H44441003_PIP-SCONN,HA
M_E_MA<13>               U5D1             DT51     SKX_EXT_B_BGA1-IC,TBD
M_E_MA<14>               J4A2             228      SCONN288_H44441004_PIP-SCONN,HA
M_E_MA<14>               J6L2             228      SCONN288_H44441003_PIP-SCONN,HA
M_E_MA<14>               U5D1             DM51     SKX_EXT_B_BGA1-IC,TBD
M_E_MA<15>               J4A2             86       SCONN288_H44441004_PIP-SCONN,HA
M_E_MA<15>               J6L2             86       SCONN288_H44441003_PIP-SCONN,HA
M_E_MA<15>               U5D1             DR52     SKX_EXT_B_BGA1-IC,TBD
M_E_MA<16>               J4A2             82       SCONN288_H44441004_PIP-SCONN,HA
M_E_MA<16>               J6L2             82       SCONN288_H44441003_PIP-SCONN,HA
M_E_MA<16>               U5D1             DN52     SKX_EXT_B_BGA1-IC,TBD
M_E_MA<17>               J4A2             234      SCONN288_H44441004_PIP-SCONN,HA
M_E_MA<17>               J6L2             234      SCONN288_H44441003_PIP-SCONN,HA
M_E_MA<17>               U5D1             DR48     SKX_EXT_B_BGA1-IC,TBD
M_E_ODT<0>               J4A2             87       SCONN288_H44441004_PIP-SCONN,HA
M_E_ODT<0>               U5D1             DR50     SKX_EXT_B_BGA1-IC,TBD
M_E_ODT<1>               J4A2             91       SCONN288_H44441004_PIP-SCONN,HA
M_E_ODT<1>               U5D1             DN48     SKX_EXT_B_BGA1-IC,TBD
M_E_ODT<2>               J6L2             87       SCONN288_H44441003_PIP-SCONN,HA
M_E_ODT<2>               U5D1             DT49     SKX_EXT_B_BGA1-IC,TBD
M_E_ODT<3>               J6L2             91       SCONN288_H44441003_PIP-SCONN,HA
M_E_ODT<3>               U5D1             DM47     SKX_EXT_B_BGA1-IC,TBD
M_E_PAR                  J4A2             222      SCONN288_H44441004_PIP-SCONN,HA
M_E_PAR                  J6L2             222      SCONN288_H44441003_PIP-SCONN,HA
M_E_PAR                  U5D1             DV53     SKX_EXT_B_BGA1-IC,TBD
M_E_VREF                 C4A18            1        CAP_A_0402V-0.01UF,25V,10%,X7RA
M_E_VREF                 C6L6             1        CAP_A_0402V-0.01UF,25V,10%,X7RA
M_E_VREF                 J4A2             146      SCONN288_H44441004_PIP-SCONN,HA
M_E_VREF                 J6L2             146      SCONN288_H44441003_PIP-SCONN,HA
M_E_VREF                 R6L12            1        RES_0402-1.00K,1%,1/16W,CHIP,GA
M_E_VREF                 R6L13            2        RES_0402-1.00K,1%,1/16W,CHIP,GA
M_E_VREF                 R6L14            2        RES_0402-2,1.0%,1/16W,CHIP,G21A
M_F_ACT_N                J4A1             62       SCONN288_H44441004_PIP-SCONN,HA
M_F_ACT_N                J6L1             62       SCONN288_H44441003_PIP-SCONN,HA
M_F_ACT_N                U5D1             DC62     SKX_EXT_B_BGA1-IC,TBD
M_F_ALERT_N              J4A1             208      SCONN288_H44441004_PIP-SCONN,HA
M_F_ALERT_N              J6L1             208      SCONN288_H44441003_PIP-SCONN,HA
M_F_ALERT_N              U5D1             DD61     SKX_EXT_B_BGA1-IC,TBD
M_F_BA<0>                J4A1             81       SCONN288_H44441004_PIP-SCONN,HA
M_F_BA<0>                J6L1             81       SCONN288_H44441003_PIP-SCONN,HA
M_F_BA<0>                U5D1             DJ52     SKX_EXT_B_BGA1-IC,TBD
M_F_BA<1>                J4A1             224      SCONN288_H44441004_PIP-SCONN,HA
M_F_BA<1>                J6L1             224      SCONN288_H44441003_PIP-SCONN,HA
M_F_BA<1>                U5D1             DC56     SKX_EXT_B_BGA1-IC,TBD
M_F_BG<0>                J4A1             63       SCONN288_H44441004_PIP-SCONN,HA
M_F_BG<0>                J6L1             63       SCONN288_H44441003_PIP-SCONN,HA
M_F_BG<0>                U5D1             DA62     SKX_EXT_B_BGA1-IC,TBD
M_F_BG<1>                J4A1             207      SCONN288_H44441004_PIP-SCONN,HA
M_F_BG<1>                J6L1             207      SCONN288_H44441003_PIP-SCONN,HA
M_F_BG<1>                U5D1             DF61     SKX_EXT_B_BGA1-IC,TBD
M_F_C<2>                 J4A1             235      SCONN288_H44441004_PIP-SCONN,HA
M_F_C<2>                 J6L1             235      SCONN288_H44441003_PIP-SCONN,HA
M_F_C<2>                 U5D1             DF45     SKX_EXT_B_BGA1-IC,TBD
M_F_CKE<0>               J4A1             60       SCONN288_H44441004_PIP-SCONN,HA
M_F_CKE<0>               U5D1             DG62     SKX_EXT_B_BGA1-IC,TBD
M_F_CKE<1>               J4A1             203      SCONN288_H44441004_PIP-SCONN,HA
M_F_CKE<1>               U5D1             DD63     SKX_EXT_B_BGA1-IC,TBD
M_F_CKE<2>               J6L1             60       SCONN288_H44441003_PIP-SCONN,HA
M_F_CKE<2>               U5D1             DK63     SKX_EXT_B_BGA1-IC,TBD
M_F_CKE<3>               J6L1             203      SCONN288_H44441003_PIP-SCONN,HA
M_F_CKE<3>               U5D1             DF63     SKX_EXT_B_BGA1-IC,TBD
M_F_CLK_DN<0>            J4A1             75       SCONN288_H44441004_PIP-SCONN,HA
M_F_CLK_DN<0>            U5D1             DK55     SKX_EXT_B_BGA1-IC,TBD
M_F_CLK_DN<1>            J4A1             219      SCONN288_H44441004_PIP-SCONN,HA
M_F_CLK_DN<1>            U5D1             DF55     SKX_EXT_B_BGA1-IC,TBD
M_F_CLK_DN<2>            J6L1             75       SCONN288_H44441003_PIP-SCONN,HA
M_F_CLK_DN<2>            U5D1             DK57     SKX_EXT_B_BGA1-IC,TBD
M_F_CLK_DN<3>            J6L1             219      SCONN288_H44441003_PIP-SCONN,HA
M_F_CLK_DN<3>            U5D1             DF57     SKX_EXT_B_BGA1-IC,TBD
M_F_CLK_DP<0>            J4A1             74       SCONN288_H44441004_PIP-SCONN,HA
M_F_CLK_DP<0>            U5D1             DJ54     SKX_EXT_B_BGA1-IC,TBD
M_F_CLK_DP<1>            J4A1             218      SCONN288_H44441004_PIP-SCONN,HA
M_F_CLK_DP<1>            U5D1             DG54     SKX_EXT_B_BGA1-IC,TBD
M_F_CLK_DP<2>            J6L1             74       SCONN288_H44441003_PIP-SCONN,HA
M_F_CLK_DP<2>            U5D1             DJ56     SKX_EXT_B_BGA1-IC,TBD
M_F_CLK_DP<3>            J6L1             218      SCONN288_H44441003_PIP-SCONN,HA
M_F_CLK_DP<3>            U5D1             DG56     SKX_EXT_B_BGA1-IC,TBD
M_F_CPU_VREF             C6L2             1        CAP_A_0402V-0.01UF,25V,10%,X7RA
M_F_CPU_VREF             R6L3             1        RES_0402-2,1.0%,1/16W,CHIP,G21A
M_F_CPU_VREF             U5D1             CV61     SKX_EXT_B_BGA1-IC,TBD
M_F_CS_N<0>              J4A1             84       SCONN288_H44441004_PIP-SCONN,HA
M_F_CS_N<0>              U5D1             DK51     SKX_EXT_B_BGA1-IC,TBD
M_F_CS_N<1>              J4A1             89       SCONN288_H44441004_PIP-SCONN,HA
M_F_CS_N<1>              U5D1             DF49     SKX_EXT_B_BGA1-IC,TBD
M_F_CS_N<2>              J4A1             93       SCONN288_H44441004_PIP-SCONN,HA
M_F_CS_N<2>              U5D1             DJ46     SKX_EXT_B_BGA1-IC,TBD
M_F_CS_N<3>              J4A1             237      SCONN288_H44441004_PIP-SCONN,HA
M_F_CS_N<3>              U5D1             DG46     SKX_EXT_B_BGA1-IC,TBD
M_F_CS_N<4>              J6L1             84       SCONN288_H44441003_PIP-SCONN,HA
M_F_CS_N<4>              U5D1             DF51     SKX_EXT_B_BGA1-IC,TBD
M_F_CS_N<5>              J6L1             89       SCONN288_H44441003_PIP-SCONN,HA
M_F_CS_N<5>              U5D1             DJ48     SKX_EXT_B_BGA1-IC,TBD
M_F_CS_N<6>              J6L1             93       SCONN288_H44441003_PIP-SCONN,HA
M_F_CS_N<6>              U5D1             DM45     SKX_EXT_B_BGA1-IC,TBD
M_F_CS_N<7>              J6L1             237      SCONN288_H44441003_PIP-SCONN,HA
M_F_CS_N<7>              U5D1             DK45     SKX_EXT_B_BGA1-IC,TBD
M_F_DQ<0>                J4A1             150      SCONN288_H44441004_PIP-SCONN,HA
M_F_DQ<0>                J6L1             5        SCONN288_H44441003_PIP-SCONN,HA
M_F_DQ<0>                U5D1             CR74     SKX_EXT_B_BGA1-IC,TBD
M_F_DQ<1>                J4A1             5        SCONN288_H44441004_PIP-SCONN,HA
M_F_DQ<1>                J6L1             150      SCONN288_H44441003_PIP-SCONN,HA
M_F_DQ<1>                U5D1             CN76     SKX_EXT_B_BGA1-IC,TBD
M_F_DQ<2>                J4A1             157      SCONN288_H44441004_PIP-SCONN,HA
M_F_DQ<2>                J6L1             12       SCONN288_H44441003_PIP-SCONN,HA
M_F_DQ<2>                U5D1             CW76     SKX_EXT_B_BGA1-IC,TBD
M_F_DQ<3>                J4A1             12       SCONN288_H44441004_PIP-SCONN,HA
M_F_DQ<3>                J6L1             157      SCONN288_H44441003_PIP-SCONN,HA
M_F_DQ<3>                U5D1             CV77     SKX_EXT_B_BGA1-IC,TBD
M_F_DQ<4>                J4A1             148      SCONN288_H44441004_PIP-SCONN,HA
M_F_DQ<4>                J6L1             3        SCONN288_H44441003_PIP-SCONN,HA
M_F_DQ<4>                U5D1             CN74     SKX_EXT_B_BGA1-IC,TBD
M_F_DQ<5>                J4A1             3        SCONN288_H44441004_PIP-SCONN,HA
M_F_DQ<5>                J6L1             148      SCONN288_H44441003_PIP-SCONN,HA
M_F_DQ<5>                U5D1             CM75     SKX_EXT_B_BGA1-IC,TBD
M_F_DQ<6>                J4A1             155      SCONN288_H44441004_PIP-SCONN,HA
M_F_DQ<6>                J6L1             10       SCONN288_H44441003_PIP-SCONN,HA
M_F_DQ<6>                U5D1             CV75     SKX_EXT_B_BGA1-IC,TBD
M_F_DQ<7>                J4A1             10       SCONN288_H44441004_PIP-SCONN,HA
M_F_DQ<7>                J6L1             155      SCONN288_H44441003_PIP-SCONN,HA
M_F_DQ<7>                U5D1             CT77     SKX_EXT_B_BGA1-IC,TBD
M_F_DQ<8>                J4A1             161      SCONN288_H44441004_PIP-SCONN,HA
M_F_DQ<8>                J6L1             16       SCONN288_H44441003_PIP-SCONN,HA
M_F_DQ<8>                U5D1             DE74     SKX_EXT_B_BGA1-IC,TBD
M_F_DQ<9>                J4A1             16       SCONN288_H44441004_PIP-SCONN,HA
M_F_DQ<9>                J6L1             161      SCONN288_H44441003_PIP-SCONN,HA
M_F_DQ<9>                U5D1             DC76     SKX_EXT_B_BGA1-IC,TBD
M_F_DQ<10>               J4A1             168      SCONN288_H44441004_PIP-SCONN,HA
M_F_DQ<10>               J6L1             23       SCONN288_H44441003_PIP-SCONN,HA
M_F_DQ<10>               U5D1             DH75     SKX_EXT_B_BGA1-IC,TBD
M_F_DQ<11>               J4A1             23       SCONN288_H44441004_PIP-SCONN,HA
M_F_DQ<11>               J6L1             168      SCONN288_H44441003_PIP-SCONN,HA
M_F_DQ<11>               U5D1             DJ76     SKX_EXT_B_BGA1-IC,TBD
M_F_DQ<12>               J4A1             159      SCONN288_H44441004_PIP-SCONN,HA
M_F_DQ<12>               J6L1             14       SCONN288_H44441003_PIP-SCONN,HA
M_F_DQ<12>               U5D1             DC74     SKX_EXT_B_BGA1-IC,TBD
M_F_DQ<13>               J4A1             14       SCONN288_H44441004_PIP-SCONN,HA
M_F_DQ<13>               J6L1             159      SCONN288_H44441003_PIP-SCONN,HA
M_F_DQ<13>               U5D1             DB75     SKX_EXT_B_BGA1-IC,TBD
M_F_DQ<14>               J4A1             166      SCONN288_H44441004_PIP-SCONN,HA
M_F_DQ<14>               J6L1             21       SCONN288_H44441003_PIP-SCONN,HA
M_F_DQ<14>               U5D1             DF77     SKX_EXT_B_BGA1-IC,TBD
M_F_DQ<15>               J4A1             21       SCONN288_H44441004_PIP-SCONN,HA
M_F_DQ<15>               J6L1             166      SCONN288_H44441003_PIP-SCONN,HA
M_F_DQ<15>               U5D1             DH77     SKX_EXT_B_BGA1-IC,TBD
M_F_DQ<16>               J4A1             172      SCONN288_H44441004_PIP-SCONN,HA
M_F_DQ<16>               J6L1             27       SCONN288_H44441003_PIP-SCONN,HA
M_F_DQ<16>               U5D1             DG70     SKX_EXT_B_BGA1-IC,TBD
M_F_DQ<17>               J4A1             27       SCONN288_H44441004_PIP-SCONN,HA
M_F_DQ<17>               J6L1             172      SCONN288_H44441003_PIP-SCONN,HA
M_F_DQ<17>               U5D1             DJ72     SKX_EXT_B_BGA1-IC,TBD
M_F_DQ<18>               J4A1             179      SCONN288_H44441004_PIP-SCONN,HA
M_F_DQ<18>               J6L1             34       SCONN288_H44441003_PIP-SCONN,HA
M_F_DQ<18>               U5D1             DM69     SKX_EXT_B_BGA1-IC,TBD
M_F_DQ<19>               J4A1             34       SCONN288_H44441004_PIP-SCONN,HA
M_F_DQ<19>               J6L1             179      SCONN288_H44441003_PIP-SCONN,HA
M_F_DQ<19>               U5D1             DN70     SKX_EXT_B_BGA1-IC,TBD
M_F_DQ<20>               J4A1             170      SCONN288_H44441004_PIP-SCONN,HA
M_F_DQ<20>               J6L1             25       SCONN288_H44441003_PIP-SCONN,HA
M_F_DQ<20>               U5D1             DF71     SKX_EXT_B_BGA1-IC,TBD
M_F_DQ<21>               J4A1             25       SCONN288_H44441004_PIP-SCONN,HA
M_F_DQ<21>               J6L1             170      SCONN288_H44441003_PIP-SCONN,HA
M_F_DQ<21>               U5D1             DG72     SKX_EXT_B_BGA1-IC,TBD
M_F_DQ<22>               J4A1             177      SCONN288_H44441004_PIP-SCONN,HA
M_F_DQ<22>               J6L1             32       SCONN288_H44441003_PIP-SCONN,HA
M_F_DQ<22>               U5D1             DK69     SKX_EXT_B_BGA1-IC,TBD
M_F_DQ<23>               J4A1             32       SCONN288_H44441004_PIP-SCONN,HA
M_F_DQ<23>               J6L1             177      SCONN288_H44441003_PIP-SCONN,HA
M_F_DQ<23>               U5D1             DM71     SKX_EXT_B_BGA1-IC,TBD
M_F_DQ<24>               J4A1             183      SCONN288_H44441004_PIP-SCONN,HA
M_F_DQ<24>               J6L1             38       SCONN288_H44441003_PIP-SCONN,HA
M_F_DQ<24>               U5D1             CN66     SKX_EXT_B_BGA1-IC,TBD
M_F_DQ<25>               J4A1             38       SCONN288_H44441004_PIP-SCONN,HA
M_F_DQ<25>               J6L1             183      SCONN288_H44441003_PIP-SCONN,HA
M_F_DQ<25>               U5D1             CU66     SKX_EXT_B_BGA1-IC,TBD
M_F_DQ<26>               J4A1             190      SCONN288_H44441004_PIP-SCONN,HA
M_F_DQ<26>               J6L1             45       SCONN288_H44441003_PIP-SCONN,HA
M_F_DQ<26>               U5D1             CP63     SKX_EXT_B_BGA1-IC,TBD
M_F_DQ<27>               J4A1             45       SCONN288_H44441004_PIP-SCONN,HA
M_F_DQ<27>               J6L1             190      SCONN288_H44441003_PIP-SCONN,HA
M_F_DQ<27>               U5D1             CT63     SKX_EXT_B_BGA1-IC,TBD
M_F_DQ<28>               J4A1             181      SCONN288_H44441004_PIP-SCONN,HA
M_F_DQ<28>               J6L1             36       SCONN288_H44441003_PIP-SCONN,HA
M_F_DQ<28>               U5D1             CP67     SKX_EXT_B_BGA1-IC,TBD
M_F_DQ<29>               J4A1             36       SCONN288_H44441004_PIP-SCONN,HA
M_F_DQ<29>               J6L1             181      SCONN288_H44441003_PIP-SCONN,HA
M_F_DQ<29>               U5D1             CT67     SKX_EXT_B_BGA1-IC,TBD
M_F_DQ<30>               J4A1             188      SCONN288_H44441004_PIP-SCONN,HA
M_F_DQ<30>               J6L1             43       SCONN288_H44441003_PIP-SCONN,HA
M_F_DQ<30>               U5D1             CN64     SKX_EXT_B_BGA1-IC,TBD
M_F_DQ<31>               J4A1             43       SCONN288_H44441004_PIP-SCONN,HA
M_F_DQ<31>               J6L1             188      SCONN288_H44441003_PIP-SCONN,HA
M_F_DQ<31>               U5D1             CU64     SKX_EXT_B_BGA1-IC,TBD
M_F_DQ<32>               J4A1             242      SCONN288_H44441004_PIP-SCONN,HA
M_F_DQ<32>               J6L1             97       SCONN288_H44441003_PIP-SCONN,HA
M_F_DQ<32>               U5D1             DD41     SKX_EXT_B_BGA1-IC,TBD
M_F_DQ<33>               J4A1             97       SCONN288_H44441004_PIP-SCONN,HA
M_F_DQ<33>               J6L1             242      SCONN288_H44441003_PIP-SCONN,HA
M_F_DQ<33>               U5D1             DG42     SKX_EXT_B_BGA1-IC,TBD
M_F_DQ<34>               J4A1             249      SCONN288_H44441004_PIP-SCONN,HA
M_F_DQ<34>               J6L1             104      SCONN288_H44441003_PIP-SCONN,HA
M_F_DQ<34>               U5D1             DE38     SKX_EXT_B_BGA1-IC,TBD
M_F_DQ<35>               J4A1             104      SCONN288_H44441004_PIP-SCONN,HA
M_F_DQ<35>               J6L1             249      SCONN288_H44441003_PIP-SCONN,HA
M_F_DQ<35>               U5D1             DG38     SKX_EXT_B_BGA1-IC,TBD
M_F_DQ<36>               J4A1             240      SCONN288_H44441004_PIP-SCONN,HA
M_F_DQ<36>               J6L1             95       SCONN288_H44441003_PIP-SCONN,HA
M_F_DQ<36>               U5D1             DA42     SKX_EXT_B_BGA1-IC,TBD
M_F_DQ<37>               J4A1             95       SCONN288_H44441004_PIP-SCONN,HA
M_F_DQ<37>               J6L1             240      SCONN288_H44441003_PIP-SCONN,HA
M_F_DQ<37>               U5D1             DE42     SKX_EXT_B_BGA1-IC,TBD
M_F_DQ<38>               J4A1             247      SCONN288_H44441004_PIP-SCONN,HA
M_F_DQ<38>               J6L1             102      SCONN288_H44441003_PIP-SCONN,HA
M_F_DQ<38>               U5D1             DD39     SKX_EXT_B_BGA1-IC,TBD
M_F_DQ<39>               J4A1             102      SCONN288_H44441004_PIP-SCONN,HA
M_F_DQ<39>               J6L1             247      SCONN288_H44441003_PIP-SCONN,HA
M_F_DQ<39>               U5D1             DH39     SKX_EXT_B_BGA1-IC,TBD
M_F_DQ<40>               J4A1             253      SCONN288_H44441004_PIP-SCONN,HA
M_F_DQ<40>               J6L1             108      SCONN288_H44441003_PIP-SCONN,HA
M_F_DQ<40>               U5D1             DF33     SKX_EXT_B_BGA1-IC,TBD
M_F_DQ<41>               J4A1             108      SCONN288_H44441004_PIP-SCONN,HA
M_F_DQ<41>               J6L1             253      SCONN288_H44441003_PIP-SCONN,HA
M_F_DQ<41>               U5D1             DK33     SKX_EXT_B_BGA1-IC,TBD
M_F_DQ<42>               J4A1             260      SCONN288_H44441004_PIP-SCONN,HA
M_F_DQ<42>               J6L1             115      SCONN288_H44441003_PIP-SCONN,HA
M_F_DQ<42>               U5D1             DG30     SKX_EXT_B_BGA1-IC,TBD
M_F_DQ<43>               J4A1             115      SCONN288_H44441004_PIP-SCONN,HA
M_F_DQ<43>               J6L1             260      SCONN288_H44441003_PIP-SCONN,HA
M_F_DQ<43>               U5D1             DJ30     SKX_EXT_B_BGA1-IC,TBD
M_F_DQ<44>               J4A1             251      SCONN288_H44441004_PIP-SCONN,HA
M_F_DQ<44>               J6L1             106      SCONN288_H44441003_PIP-SCONN,HA
M_F_DQ<44>               U5D1             DG34     SKX_EXT_B_BGA1-IC,TBD
M_F_DQ<45>               J4A1             106      SCONN288_H44441004_PIP-SCONN,HA
M_F_DQ<45>               J6L1             251      SCONN288_H44441003_PIP-SCONN,HA
M_F_DQ<45>               U5D1             DJ34     SKX_EXT_B_BGA1-IC,TBD
M_F_DQ<46>               J4A1             258      SCONN288_H44441004_PIP-SCONN,HA
M_F_DQ<46>               J6L1             113      SCONN288_H44441003_PIP-SCONN,HA
M_F_DQ<46>               U5D1             DF31     SKX_EXT_B_BGA1-IC,TBD
M_F_DQ<47>               J4A1             113      SCONN288_H44441004_PIP-SCONN,HA
M_F_DQ<47>               J6L1             258      SCONN288_H44441003_PIP-SCONN,HA
M_F_DQ<47>               U5D1             DK31     SKX_EXT_B_BGA1-IC,TBD
M_F_DQ<48>               J4A1             264      SCONN288_H44441004_PIP-SCONN,HA
M_F_DQ<48>               J6L1             119      SCONN288_H44441003_PIP-SCONN,HA
M_F_DQ<48>               U5D1             CW36     SKX_EXT_B_BGA1-IC,TBD
M_F_DQ<49>               J4A1             119      SCONN288_H44441004_PIP-SCONN,HA
M_F_DQ<49>               J6L1             264      SCONN288_H44441003_PIP-SCONN,HA
M_F_DQ<49>               U5D1             DC36     SKX_EXT_B_BGA1-IC,TBD
M_F_DQ<50>               J4A1             271      SCONN288_H44441004_PIP-SCONN,HA
M_F_DQ<50>               J6L1             126      SCONN288_H44441003_PIP-SCONN,HA
M_F_DQ<50>               U5D1             CY33     SKX_EXT_B_BGA1-IC,TBD
M_F_DQ<51>               J4A1             126      SCONN288_H44441004_PIP-SCONN,HA
M_F_DQ<51>               J6L1             271      SCONN288_H44441003_PIP-SCONN,HA
M_F_DQ<51>               U5D1             DB33     SKX_EXT_B_BGA1-IC,TBD
M_F_DQ<52>               J4A1             262      SCONN288_H44441004_PIP-SCONN,HA
M_F_DQ<52>               J6L1             117      SCONN288_H44441003_PIP-SCONN,HA
M_F_DQ<52>               U5D1             CY37     SKX_EXT_B_BGA1-IC,TBD
M_F_DQ<53>               J4A1             117      SCONN288_H44441004_PIP-SCONN,HA
M_F_DQ<53>               J6L1             262      SCONN288_H44441003_PIP-SCONN,HA
M_F_DQ<53>               U5D1             DB37     SKX_EXT_B_BGA1-IC,TBD
M_F_DQ<54>               J4A1             269      SCONN288_H44441004_PIP-SCONN,HA
M_F_DQ<54>               J6L1             124      SCONN288_H44441003_PIP-SCONN,HA
M_F_DQ<54>               U5D1             CW34     SKX_EXT_B_BGA1-IC,TBD
M_F_DQ<55>               J4A1             124      SCONN288_H44441004_PIP-SCONN,HA
M_F_DQ<55>               J6L1             269      SCONN288_H44441003_PIP-SCONN,HA
M_F_DQ<55>               U5D1             DC34     SKX_EXT_B_BGA1-IC,TBD
M_F_DQ<56>               J4A1             275      SCONN288_H44441004_PIP-SCONN,HA
M_F_DQ<56>               J6L1             130      SCONN288_H44441003_PIP-SCONN,HA
M_F_DQ<56>               U5D1             CW30     SKX_EXT_B_BGA1-IC,TBD
M_F_DQ<57>               J4A1             130      SCONN288_H44441004_PIP-SCONN,HA
M_F_DQ<57>               J6L1             275      SCONN288_H44441003_PIP-SCONN,HA
M_F_DQ<57>               U5D1             DC30     SKX_EXT_B_BGA1-IC,TBD
M_F_DQ<58>               J4A1             282      SCONN288_H44441004_PIP-SCONN,HA
M_F_DQ<58>               J6L1             137      SCONN288_H44441003_PIP-SCONN,HA
M_F_DQ<58>               U5D1             CY27     SKX_EXT_B_BGA1-IC,TBD
M_F_DQ<59>               J4A1             137      SCONN288_H44441004_PIP-SCONN,HA
M_F_DQ<59>               J6L1             282      SCONN288_H44441003_PIP-SCONN,HA
M_F_DQ<59>               U5D1             DB27     SKX_EXT_B_BGA1-IC,TBD
M_F_DQ<60>               J4A1             273      SCONN288_H44441004_PIP-SCONN,HA
M_F_DQ<60>               J6L1             128      SCONN288_H44441003_PIP-SCONN,HA
M_F_DQ<60>               U5D1             CY31     SKX_EXT_B_BGA1-IC,TBD
M_F_DQ<61>               J4A1             128      SCONN288_H44441004_PIP-SCONN,HA
M_F_DQ<61>               J6L1             273      SCONN288_H44441003_PIP-SCONN,HA
M_F_DQ<61>               U5D1             DB31     SKX_EXT_B_BGA1-IC,TBD
M_F_DQ<62>               J4A1             280      SCONN288_H44441004_PIP-SCONN,HA
M_F_DQ<62>               J6L1             135      SCONN288_H44441003_PIP-SCONN,HA
M_F_DQ<62>               U5D1             CW28     SKX_EXT_B_BGA1-IC,TBD
M_F_DQ<63>               J4A1             135      SCONN288_H44441004_PIP-SCONN,HA
M_F_DQ<63>               J6L1             280      SCONN288_H44441003_PIP-SCONN,HA
M_F_DQ<63>               U5D1             DC28     SKX_EXT_B_BGA1-IC,TBD
M_F_DQS_DN<0>            J4A1             152      SCONN288_H44441004_PIP-SCONN,HA
M_F_DQS_DN<0>            J6L1             152      SCONN288_H44441003_PIP-SCONN,HA
M_F_DQS_DN<0>            U5D1             CP77     SKX_EXT_B_BGA1-IC,TBD
M_F_DQS_DN<1>            J4A1             163      SCONN288_H44441004_PIP-SCONN,HA
M_F_DQS_DN<1>            J6L1             163      SCONN288_H44441003_PIP-SCONN,HA
M_F_DQS_DN<1>            U5D1             DD77     SKX_EXT_B_BGA1-IC,TBD
M_F_DQS_DN<2>            J4A1             174      SCONN288_H44441004_PIP-SCONN,HA
M_F_DQS_DN<2>            J6L1             174      SCONN288_H44441003_PIP-SCONN,HA
M_F_DQS_DN<2>            U5D1             DL72     SKX_EXT_B_BGA1-IC,TBD
M_F_DQS_DN<3>            J4A1             185      SCONN288_H44441004_PIP-SCONN,HA
M_F_DQS_DN<3>            J6L1             185      SCONN288_H44441003_PIP-SCONN,HA
M_F_DQS_DN<3>            U5D1             CV65     SKX_EXT_B_BGA1-IC,TBD
M_F_DQS_DN<4>            J4A1             244      SCONN288_H44441004_PIP-SCONN,HA
M_F_DQS_DN<4>            J6L1             244      SCONN288_H44441003_PIP-SCONN,HA
M_F_DQS_DN<4>            U5D1             DG40     SKX_EXT_B_BGA1-IC,TBD
M_F_DQS_DN<5>            J4A1             255      SCONN288_H44441004_PIP-SCONN,HA
M_F_DQS_DN<5>            J6L1             255      SCONN288_H44441003_PIP-SCONN,HA
M_F_DQS_DN<5>            U5D1             DL32     SKX_EXT_B_BGA1-IC,TBD
M_F_DQS_DN<6>            J4A1             266      SCONN288_H44441004_PIP-SCONN,HA
M_F_DQS_DN<6>            J6L1             266      SCONN288_H44441003_PIP-SCONN,HA
M_F_DQS_DN<6>            U5D1             DD35     SKX_EXT_B_BGA1-IC,TBD
M_F_DQS_DN<7>            J4A1             277      SCONN288_H44441004_PIP-SCONN,HA
M_F_DQS_DN<7>            J6L1             277      SCONN288_H44441003_PIP-SCONN,HA
M_F_DQS_DN<7>            U5D1             DD29     SKX_EXT_B_BGA1-IC,TBD
M_F_DQS_DN<8>            J4A1             196      SCONN288_H44441004_PIP-SCONN,HA
M_F_DQS_DN<8>            J6L1             196      SCONN288_H44441003_PIP-SCONN,HA
M_F_DQS_DN<8>            U5D1             CN70     SKX_EXT_B_BGA1-IC,TBD
M_F_DQS_DN<9>            J4A1             8        SCONN288_H44441004_PIP-SCONN,HA
M_F_DQS_DN<9>            J6L1             8        SCONN288_H44441003_PIP-SCONN,HA
M_F_DQS_DN<9>            U5D1             CT75     SKX_EXT_B_BGA1-IC,TBD
M_F_DQS_DN<10>           J4A1             19       SCONN288_H44441004_PIP-SCONN,HA
M_F_DQS_DN<10>           J6L1             19       SCONN288_H44441003_PIP-SCONN,HA
M_F_DQS_DN<10>           U5D1             DF75     SKX_EXT_B_BGA1-IC,TBD
M_F_DQS_DN<11>           J4A1             30       SCONN288_H44441004_PIP-SCONN,HA
M_F_DQS_DN<11>           J6L1             30       SCONN288_H44441003_PIP-SCONN,HA
M_F_DQS_DN<11>           U5D1             DJ70     SKX_EXT_B_BGA1-IC,TBD
M_F_DQS_DN<12>           J4A1             41       SCONN288_H44441004_PIP-SCONN,HA
M_F_DQS_DN<12>           J6L1             41       SCONN288_H44441003_PIP-SCONN,HA
M_F_DQS_DN<12>           U5D1             CP65     SKX_EXT_B_BGA1-IC,TBD
M_F_DQS_DN<13>           J4A1             100      SCONN288_H44441004_PIP-SCONN,HA
M_F_DQS_DN<13>           J6L1             100      SCONN288_H44441003_PIP-SCONN,HA
M_F_DQS_DN<13>           U5D1             DE40     SKX_EXT_B_BGA1-IC,TBD
M_F_DQS_DN<14>           J4A1             111      SCONN288_H44441004_PIP-SCONN,HA
M_F_DQS_DN<14>           J6L1             111      SCONN288_H44441003_PIP-SCONN,HA
M_F_DQS_DN<14>           U5D1             DG32     SKX_EXT_B_BGA1-IC,TBD
M_F_DQS_DN<15>           J4A1             122      SCONN288_H44441004_PIP-SCONN,HA
M_F_DQS_DN<15>           J6L1             122      SCONN288_H44441003_PIP-SCONN,HA
M_F_DQS_DN<15>           U5D1             CY35     SKX_EXT_B_BGA1-IC,TBD
M_F_DQS_DN<16>           J4A1             133      SCONN288_H44441004_PIP-SCONN,HA
M_F_DQS_DN<16>           J6L1             133      SCONN288_H44441003_PIP-SCONN,HA
M_F_DQS_DN<16>           U5D1             CY29     SKX_EXT_B_BGA1-IC,TBD
M_F_DQS_DN<17>           J4A1             52       SCONN288_H44441004_PIP-SCONN,HA
M_F_DQS_DN<17>           J6L1             52       SCONN288_H44441003_PIP-SCONN,HA
M_F_DQS_DN<17>           U5D1             CJ70     SKX_EXT_B_BGA1-IC,TBD
M_F_DQS_DP<0>            J4A1             153      SCONN288_H44441004_PIP-SCONN,HA
M_F_DQS_DP<0>            J6L1             153      SCONN288_H44441003_PIP-SCONN,HA
M_F_DQS_DP<0>            U5D1             CR76     SKX_EXT_B_BGA1-IC,TBD
M_F_DQS_DP<1>            J4A1             164      SCONN288_H44441004_PIP-SCONN,HA
M_F_DQS_DP<1>            J6L1             164      SCONN288_H44441003_PIP-SCONN,HA
M_F_DQS_DP<1>            U5D1             DE76     SKX_EXT_B_BGA1-IC,TBD
M_F_DQS_DP<2>            J4A1             175      SCONN288_H44441004_PIP-SCONN,HA
M_F_DQS_DP<2>            J6L1             175      SCONN288_H44441003_PIP-SCONN,HA
M_F_DQS_DP<2>            U5D1             DK71     SKX_EXT_B_BGA1-IC,TBD
M_F_DQS_DP<3>            J4A1             186      SCONN288_H44441004_PIP-SCONN,HA
M_F_DQS_DP<3>            J6L1             186      SCONN288_H44441003_PIP-SCONN,HA
M_F_DQS_DP<3>            U5D1             CT65     SKX_EXT_B_BGA1-IC,TBD
M_F_DQS_DP<4>            J4A1             245      SCONN288_H44441004_PIP-SCONN,HA
M_F_DQS_DP<4>            J6L1             245      SCONN288_H44441003_PIP-SCONN,HA
M_F_DQS_DP<4>            U5D1             DJ40     SKX_EXT_B_BGA1-IC,TBD
M_F_DQS_DP<5>            J4A1             256      SCONN288_H44441004_PIP-SCONN,HA
M_F_DQS_DP<5>            J6L1             256      SCONN288_H44441003_PIP-SCONN,HA
M_F_DQS_DP<5>            U5D1             DJ32     SKX_EXT_B_BGA1-IC,TBD
M_F_DQS_DP<6>            J4A1             267      SCONN288_H44441004_PIP-SCONN,HA
M_F_DQS_DP<6>            J6L1             267      SCONN288_H44441003_PIP-SCONN,HA
M_F_DQS_DP<6>            U5D1             DB35     SKX_EXT_B_BGA1-IC,TBD
M_F_DQS_DP<7>            J4A1             278      SCONN288_H44441004_PIP-SCONN,HA
M_F_DQS_DP<7>            J6L1             278      SCONN288_H44441003_PIP-SCONN,HA
M_F_DQS_DP<7>            U5D1             DB29     SKX_EXT_B_BGA1-IC,TBD
M_F_DQS_DP<8>            J4A1             197      SCONN288_H44441004_PIP-SCONN,HA
M_F_DQS_DP<8>            J6L1             197      SCONN288_H44441003_PIP-SCONN,HA
M_F_DQS_DP<8>            U5D1             CL70     SKX_EXT_B_BGA1-IC,TBD
M_F_DQS_DP<9>            J4A1             7        SCONN288_H44441004_PIP-SCONN,HA
M_F_DQS_DP<9>            J6L1             7        SCONN288_H44441003_PIP-SCONN,HA
M_F_DQS_DP<9>            U5D1             CU74     SKX_EXT_B_BGA1-IC,TBD
M_F_DQS_DP<10>           J4A1             18       SCONN288_H44441004_PIP-SCONN,HA
M_F_DQS_DP<10>           J6L1             18       SCONN288_H44441003_PIP-SCONN,HA
M_F_DQS_DP<10>           U5D1             DG74     SKX_EXT_B_BGA1-IC,TBD
M_F_DQS_DP<11>           J4A1             29       SCONN288_H44441004_PIP-SCONN,HA
M_F_DQS_DP<11>           J6L1             29       SCONN288_H44441003_PIP-SCONN,HA
M_F_DQS_DP<11>           U5D1             DH69     SKX_EXT_B_BGA1-IC,TBD
M_F_DQS_DP<12>           J4A1             40       SCONN288_H44441004_PIP-SCONN,HA
M_F_DQS_DP<12>           J6L1             40       SCONN288_H44441003_PIP-SCONN,HA
M_F_DQS_DP<12>           U5D1             CM65     SKX_EXT_B_BGA1-IC,TBD
M_F_DQS_DP<13>           J4A1             99       SCONN288_H44441004_PIP-SCONN,HA
M_F_DQS_DP<13>           J6L1             99       SCONN288_H44441003_PIP-SCONN,HA
M_F_DQS_DP<13>           U5D1             DC40     SKX_EXT_B_BGA1-IC,TBD
M_F_DQS_DP<14>           J4A1             110      SCONN288_H44441004_PIP-SCONN,HA
M_F_DQS_DP<14>           J6L1             110      SCONN288_H44441003_PIP-SCONN,HA
M_F_DQS_DP<14>           U5D1             DE32     SKX_EXT_B_BGA1-IC,TBD
M_F_DQS_DP<15>           J4A1             121      SCONN288_H44441004_PIP-SCONN,HA
M_F_DQS_DP<15>           J6L1             121      SCONN288_H44441003_PIP-SCONN,HA
M_F_DQS_DP<15>           U5D1             CV35     SKX_EXT_B_BGA1-IC,TBD
M_F_DQS_DP<16>           J4A1             132      SCONN288_H44441004_PIP-SCONN,HA
M_F_DQS_DP<16>           J6L1             132      SCONN288_H44441003_PIP-SCONN,HA
M_F_DQS_DP<16>           U5D1             CV29     SKX_EXT_B_BGA1-IC,TBD
M_F_DQS_DP<17>           J4A1             51       SCONN288_H44441004_PIP-SCONN,HA
M_F_DQS_DP<17>           J6L1             51       SCONN288_H44441003_PIP-SCONN,HA
M_F_DQS_DP<17>           U5D1             CG70     SKX_EXT_B_BGA1-IC,TBD
M_F_ECC<0>               J4A1             194      SCONN288_H44441004_PIP-SCONN,HA
M_F_ECC<0>               J6L1             49       SCONN288_H44441003_PIP-SCONN,HA
M_F_ECC<0>               U5D1             CH71     SKX_EXT_B_BGA1-IC,TBD
M_F_ECC<1>               J4A1             49       SCONN288_H44441004_PIP-SCONN,HA
M_F_ECC<1>               J6L1             194      SCONN288_H44441003_PIP-SCONN,HA
M_F_ECC<1>               U5D1             CM71     SKX_EXT_B_BGA1-IC,TBD
M_F_ECC<2>               J4A1             201      SCONN288_H44441004_PIP-SCONN,HA
M_F_ECC<2>               J6L1             56       SCONN288_H44441003_PIP-SCONN,HA
M_F_ECC<2>               U5D1             CJ68     SKX_EXT_B_BGA1-IC,TBD
M_F_ECC<3>               J4A1             56       SCONN288_H44441004_PIP-SCONN,HA
M_F_ECC<3>               J6L1             201      SCONN288_H44441003_PIP-SCONN,HA
M_F_ECC<3>               U5D1             CL68     SKX_EXT_B_BGA1-IC,TBD
M_F_ECC<4>               J4A1             192      SCONN288_H44441004_PIP-SCONN,HA
M_F_ECC<4>               J6L1             47       SCONN288_H44441003_PIP-SCONN,HA
M_F_ECC<4>               U5D1             CJ72     SKX_EXT_B_BGA1-IC,TBD
M_F_ECC<5>               J4A1             47       SCONN288_H44441004_PIP-SCONN,HA
M_F_ECC<5>               J6L1             192      SCONN288_H44441003_PIP-SCONN,HA
M_F_ECC<5>               U5D1             CL72     SKX_EXT_B_BGA1-IC,TBD
M_F_ECC<6>               J4A1             199      SCONN288_H44441004_PIP-SCONN,HA
M_F_ECC<6>               J6L1             54       SCONN288_H44441003_PIP-SCONN,HA
M_F_ECC<6>               U5D1             CH69     SKX_EXT_B_BGA1-IC,TBD
M_F_ECC<7>               J4A1             54       SCONN288_H44441004_PIP-SCONN,HA
M_F_ECC<7>               J6L1             199      SCONN288_H44441003_PIP-SCONN,HA
M_F_ECC<7>               U5D1             CM69     SKX_EXT_B_BGA1-IC,TBD
M_F_MA<0>                J4A1             79       SCONN288_H44441004_PIP-SCONN,HA
M_F_MA<0>                J6L1             79       SCONN288_H44441003_PIP-SCONN,HA
M_F_MA<0>                U5D1             DF53     SKX_EXT_B_BGA1-IC,TBD
M_F_MA<1>                J4A1             72       SCONN288_H44441004_PIP-SCONN,HA
M_F_MA<1>                J6L1             72       SCONN288_H44441003_PIP-SCONN,HA
M_F_MA<1>                U5D1             DC58     SKX_EXT_B_BGA1-IC,TBD
M_F_MA<2>                J4A1             216      SCONN288_H44441004_PIP-SCONN,HA
M_F_MA<2>                J6L1             216      SCONN288_H44441003_PIP-SCONN,HA
M_F_MA<2>                U5D1             DD57     SKX_EXT_B_BGA1-IC,TBD
M_F_MA<3>                J4A1             71       SCONN288_H44441004_PIP-SCONN,HA
M_F_MA<3>                J6L1             71       SCONN288_H44441003_PIP-SCONN,HA
M_F_MA<3>                U5D1             DG58     SKX_EXT_B_BGA1-IC,TBD
M_F_MA<4>                J4A1             214      SCONN288_H44441004_PIP-SCONN,HA
M_F_MA<4>                J6L1             214      SCONN288_H44441003_PIP-SCONN,HA
M_F_MA<4>                U5D1             DJ58     SKX_EXT_B_BGA1-IC,TBD
M_F_MA<5>                J4A1             213      SCONN288_H44441004_PIP-SCONN,HA
M_F_MA<5>                J6L1             213      SCONN288_H44441003_PIP-SCONN,HA
M_F_MA<5>                U5D1             DF59     SKX_EXT_B_BGA1-IC,TBD
M_F_MA<6>                J4A1             69       SCONN288_H44441004_PIP-SCONN,HA
M_F_MA<6>                J6L1             69       SCONN288_H44441003_PIP-SCONN,HA
M_F_MA<6>                U5D1             DK59     SKX_EXT_B_BGA1-IC,TBD
M_F_MA<7>                J4A1             211      SCONN288_H44441004_PIP-SCONN,HA
M_F_MA<7>                J6L1             211      SCONN288_H44441003_PIP-SCONN,HA
M_F_MA<7>                U5D1             DC60     SKX_EXT_B_BGA1-IC,TBD
M_F_MA<8>                J4A1             68       SCONN288_H44441004_PIP-SCONN,HA
M_F_MA<8>                J6L1             68       SCONN288_H44441003_PIP-SCONN,HA
M_F_MA<8>                U5D1             DD59     SKX_EXT_B_BGA1-IC,TBD
M_F_MA<9>                J4A1             66       SCONN288_H44441004_PIP-SCONN,HA
M_F_MA<9>                J6L1             66       SCONN288_H44441003_PIP-SCONN,HA
M_F_MA<9>                U5D1             DA58     SKX_EXT_B_BGA1-IC,TBD
M_F_MA<10>               J4A1             225      SCONN288_H44441004_PIP-SCONN,HA
M_F_MA<10>               J6L1             225      SCONN288_H44441003_PIP-SCONN,HA
M_F_MA<10>               U5D1             DD55     SKX_EXT_B_BGA1-IC,TBD
M_F_MA<11>               J4A1             210      SCONN288_H44441004_PIP-SCONN,HA
M_F_MA<11>               J6L1             210      SCONN288_H44441003_PIP-SCONN,HA
M_F_MA<11>               U5D1             DA60     SKX_EXT_B_BGA1-IC,TBD
M_F_MA<12>               J4A1             65       SCONN288_H44441004_PIP-SCONN,HA
M_F_MA<12>               J6L1             65       SCONN288_H44441003_PIP-SCONN,HA
M_F_MA<12>               U5D1             DG60     SKX_EXT_B_BGA1-IC,TBD
M_F_MA<13>               J4A1             232      SCONN288_H44441004_PIP-SCONN,HA
M_F_MA<13>               J6L1             232      SCONN288_H44441003_PIP-SCONN,HA
M_F_MA<13>               U5D1             DD53     SKX_EXT_B_BGA1-IC,TBD
M_F_MA<14>               J4A1             228      SCONN288_H44441004_PIP-SCONN,HA
M_F_MA<14>               J6L1             228      SCONN288_H44441003_PIP-SCONN,HA
M_F_MA<14>               U5D1             DJ50     SKX_EXT_B_BGA1-IC,TBD
M_F_MA<15>               J4A1             86       SCONN288_H44441004_PIP-SCONN,HA
M_F_MA<15>               J6L1             86       SCONN288_H44441003_PIP-SCONN,HA
M_F_MA<15>               U5D1             DC54     SKX_EXT_B_BGA1-IC,TBD
M_F_MA<16>               J4A1             82       SCONN288_H44441004_PIP-SCONN,HA
M_F_MA<16>               J6L1             82       SCONN288_H44441003_PIP-SCONN,HA
M_F_MA<16>               U5D1             DG52     SKX_EXT_B_BGA1-IC,TBD
M_F_MA<17>               J4A1             234      SCONN288_H44441004_PIP-SCONN,HA
M_F_MA<17>               J6L1             234      SCONN288_H44441003_PIP-SCONN,HA
M_F_MA<17>               U5D1             DE46     SKX_EXT_B_BGA1-IC,TBD
M_F_ODT<0>               J4A1             87       SCONN288_H44441004_PIP-SCONN,HA
M_F_ODT<0>               U5D1             DG50     SKX_EXT_B_BGA1-IC,TBD
M_F_ODT<1>               J4A1             91       SCONN288_H44441004_PIP-SCONN,HA
M_F_ODT<1>               U5D1             DG48     SKX_EXT_B_BGA1-IC,TBD
M_F_ODT<2>               J6L1             87       SCONN288_H44441003_PIP-SCONN,HA
M_F_ODT<2>               U5D1             DK49     SKX_EXT_B_BGA1-IC,TBD
M_F_ODT<3>               J6L1             91       SCONN288_H44441003_PIP-SCONN,HA
M_F_ODT<3>               U5D1             DF47     SKX_EXT_B_BGA1-IC,TBD
M_F_PAR                  J4A1             222      SCONN288_H44441004_PIP-SCONN,HA
M_F_PAR                  J6L1             222      SCONN288_H44441003_PIP-SCONN,HA
M_F_PAR                  U5D1             DK53     SKX_EXT_B_BGA1-IC,TBD
M_F_VREF                 C4A5             1        CAP_A_0402V-0.01UF,25V,10%,X7RA
M_F_VREF                 C6L1             1        CAP_A_0402V-0.01UF,25V,10%,X7RA
M_F_VREF                 J4A1             146      SCONN288_H44441004_PIP-SCONN,HA
M_F_VREF                 J6L1             146      SCONN288_H44441003_PIP-SCONN,HA
M_F_VREF                 R6L1             1        RES_0402-1.00K,1%,1/16W,CHIP,GA
M_F_VREF                 R6L2             2        RES_0402-1.00K,1%,1/16W,CHIP,GA
M_F_VREF                 R6L3             2        RES_0402-2,1.0%,1/16W,CHIP,G21A
M_GHJ_RST_N              J1G1             58       SCONN288_H44441004_PIP-SCONN,HA
M_GHJ_RST_N              J1G2             58       SCONN288_H44441004_PIP-SCONN,HA
M_GHJ_RST_N              J1G3             58       SCONN288_H44441004_PIP-SCONN,HA
M_GHJ_RST_N              J9T1             58       SCONN288_H44441003_PIP-SCONN,HA
M_GHJ_RST_N              J9U1             58       SCONN288_H44441003_PIP-SCONN,HA
M_GHJ_RST_N              J9U2             58       SCONN288_H44441003_PIP-SCONN,HA
M_GHJ_RST_N              U2D1             U64      SKX_EXT_B_BGA1-IC,TBD
M_G_ACT_N                J1G1             62       SCONN288_H44441004_PIP-SCONN,HA
M_G_ACT_N                J9T1             62       SCONN288_H44441003_PIP-SCONN,HA
M_G_ACT_N                U2D1             J60      SKX_EXT_B_BGA1-IC,TBD
M_G_ALERT_N              J1G1             208      SCONN288_H44441004_PIP-SCONN,HA
M_G_ALERT_N              J9T1             208      SCONN288_H44441003_PIP-SCONN,HA
M_G_ALERT_N              U2D1             B61      SKX_EXT_B_BGA1-IC,TBD
M_G_BA<0>                J1G1             81       SCONN288_H44441004_PIP-SCONN,HA
M_G_BA<0>                J9T1             81       SCONN288_H44441003_PIP-SCONN,HA
M_G_BA<0>                U2D1             C52      SKX_EXT_B_BGA1-IC,TBD
M_G_BA<1>                J1G1             224      SCONN288_H44441004_PIP-SCONN,HA
M_G_BA<1>                J9T1             224      SCONN288_H44441003_PIP-SCONN,HA
M_G_BA<1>                U2D1             G54      SKX_EXT_B_BGA1-IC,TBD
M_G_BG<0>                J1G1             63       SCONN288_H44441004_PIP-SCONN,HA
M_G_BG<0>                J9T1             63       SCONN288_H44441003_PIP-SCONN,HA
M_G_BG<0>                U2D1             D61      SKX_EXT_B_BGA1-IC,TBD
M_G_BG<1>                J1G1             207      SCONN288_H44441004_PIP-SCONN,HA
M_G_BG<1>                J9T1             207      SCONN288_H44441003_PIP-SCONN,HA
M_G_BG<1>                U2D1             F63      SKX_EXT_B_BGA1-IC,TBD
M_G_C<2>                 J1G1             235      SCONN288_H44441004_PIP-SCONN,HA
M_G_C<2>                 J9T1             235      SCONN288_H44441003_PIP-SCONN,HA
M_G_C<2>                 U2D1             G46      SKX_EXT_B_BGA1-IC,TBD
M_G_CKE<0>               J1G1             60       SCONN288_H44441004_PIP-SCONN,HA
M_G_CKE<0>               U2D1             C62      SKX_EXT_B_BGA1-IC,TBD
M_G_CKE<1>               J1G1             203      SCONN288_H44441004_PIP-SCONN,HA
M_G_CKE<1>               U2D1             C64      SKX_EXT_B_BGA1-IC,TBD
M_G_CKE<2>               J9T1             60       SCONN288_H44441003_PIP-SCONN,HA
M_G_CKE<2>               U2D1             B63      SKX_EXT_B_BGA1-IC,TBD
M_G_CKE<3>               J9T1             203      SCONN288_H44441003_PIP-SCONN,HA
M_G_CKE<3>               U2D1             D63      SKX_EXT_B_BGA1-IC,TBD
M_G_CLK_DN<0>            J1G1             75       SCONN288_H44441004_PIP-SCONN,HA
M_G_CLK_DN<0>            U2D1             F55      SKX_EXT_B_BGA1-IC,TBD
M_G_CLK_DN<1>            J1G1             219      SCONN288_H44441004_PIP-SCONN,HA
M_G_CLK_DN<1>            U2D1             C54      SKX_EXT_B_BGA1-IC,TBD
M_G_CLK_DN<2>            J9T1             75       SCONN288_H44441003_PIP-SCONN,HA
M_G_CLK_DN<2>            U2D1             J56      SKX_EXT_B_BGA1-IC,TBD
M_G_CLK_DN<3>            J9T1             219      SCONN288_H44441003_PIP-SCONN,HA
M_G_CLK_DN<3>            U2D1             C56      SKX_EXT_B_BGA1-IC,TBD
M_G_CLK_DP<0>            J1G1             74       SCONN288_H44441004_PIP-SCONN,HA
M_G_CLK_DP<0>            U2D1             D55      SKX_EXT_B_BGA1-IC,TBD
M_G_CLK_DP<1>            J1G1             218      SCONN288_H44441004_PIP-SCONN,HA
M_G_CLK_DP<1>            U2D1             B55      SKX_EXT_B_BGA1-IC,TBD
M_G_CLK_DP<2>            J9T1             74       SCONN288_H44441003_PIP-SCONN,HA
M_G_CLK_DP<2>            U2D1             G56      SKX_EXT_B_BGA1-IC,TBD
M_G_CLK_DP<3>            J9T1             218      SCONN288_H44441003_PIP-SCONN,HA
M_G_CLK_DP<3>            U2D1             B57      SKX_EXT_B_BGA1-IC,TBD
M_G_CPU_VREF             C1F19            1        CAP_A_0402V-0.01UF,25V,10%,X7RA
M_G_CPU_VREF             R1F4             1        RES_0402-2,1.0%,1/16W,CHIP,G21A
M_G_CPU_VREF             U2D1             AJ64     SKX_EXT_B_BGA1-IC,TBD
M_G_CS_N<0>              J1G1             84       SCONN288_H44441004_PIP-SCONN,HA
M_G_CS_N<0>              U2D1             G52      SKX_EXT_B_BGA1-IC,TBD
M_G_CS_N<1>              J1G1             89       SCONN288_H44441004_PIP-SCONN,HA
M_G_CS_N<1>              U2D1             F49      SKX_EXT_B_BGA1-IC,TBD
M_G_CS_N<2>              J1G1             93       SCONN288_H44441004_PIP-SCONN,HA
M_G_CS_N<2>              U2D1             D47      SKX_EXT_B_BGA1-IC,TBD
M_G_CS_N<3>              J1G1             237      SCONN288_H44441004_PIP-SCONN,HA
M_G_CS_N<3>              U2D1             F47      SKX_EXT_B_BGA1-IC,TBD
M_G_CS_N<4>              J9T1             84       SCONN288_H44441003_PIP-SCONN,HA
M_G_CS_N<4>              U2D1             B51      SKX_EXT_B_BGA1-IC,TBD
M_G_CS_N<5>              J9T1             89       SCONN288_H44441003_PIP-SCONN,HA
M_G_CS_N<5>              U2D1             D49      SKX_EXT_B_BGA1-IC,TBD
M_G_CS_N<6>              J9T1             93       SCONN288_H44441003_PIP-SCONN,HA
M_G_CS_N<6>              U2D1             F45      SKX_EXT_B_BGA1-IC,TBD
M_G_CS_N<7>              J9T1             237      SCONN288_H44441003_PIP-SCONN,HA
M_G_CS_N<7>              U2D1             K45      SKX_EXT_B_BGA1-IC,TBD
M_G_DQ<0>                J1G1             150      SCONN288_H44441004_PIP-SCONN,HA
M_G_DQ<0>                J9T1             5        SCONN288_H44441003_PIP-SCONN,HA
M_G_DQ<0>                U2D1             AN86     SKX_EXT_B_BGA1-IC,TBD
M_G_DQ<1>                J1G1             5        SCONN288_H44441004_PIP-SCONN,HA
M_G_DQ<1>                J9T1             150      SCONN288_H44441003_PIP-SCONN,HA
M_G_DQ<1>                U2D1             AN84     SKX_EXT_B_BGA1-IC,TBD
M_G_DQ<2>                J1G1             157      SCONN288_H44441004_PIP-SCONN,HA
M_G_DQ<2>                J9T1             12       SCONN288_H44441003_PIP-SCONN,HA
M_G_DQ<2>                U2D1             AE86     SKX_EXT_B_BGA1-IC,TBD
M_G_DQ<3>                J1G1             12       SCONN288_H44441004_PIP-SCONN,HA
M_G_DQ<3>                J9T1             157      SCONN288_H44441003_PIP-SCONN,HA
M_G_DQ<3>                U2D1             AE84     SKX_EXT_B_BGA1-IC,TBD
M_G_DQ<4>                J1G1             148      SCONN288_H44441004_PIP-SCONN,HA
M_G_DQ<4>                J9T1             3        SCONN288_H44441003_PIP-SCONN,HA
M_G_DQ<4>                U2D1             AR86     SKX_EXT_B_BGA1-IC,TBD
M_G_DQ<5>                J1G1             3        SCONN288_H44441004_PIP-SCONN,HA
M_G_DQ<5>                J9T1             148      SCONN288_H44441003_PIP-SCONN,HA
M_G_DQ<5>                U2D1             AR84     SKX_EXT_B_BGA1-IC,TBD
M_G_DQ<6>                J1G1             155      SCONN288_H44441004_PIP-SCONN,HA
M_G_DQ<6>                J9T1             10       SCONN288_H44441003_PIP-SCONN,HA
M_G_DQ<6>                U2D1             AG86     SKX_EXT_B_BGA1-IC,TBD
M_G_DQ<7>                J1G1             10       SCONN288_H44441004_PIP-SCONN,HA
M_G_DQ<7>                J9T1             155      SCONN288_H44441003_PIP-SCONN,HA
M_G_DQ<7>                U2D1             AG84     SKX_EXT_B_BGA1-IC,TBD
M_G_DQ<8>                J1G1             161      SCONN288_H44441004_PIP-SCONN,HA
M_G_DQ<8>                J9T1             16       SCONN288_H44441003_PIP-SCONN,HA
M_G_DQ<8>                U2D1             W86      SKX_EXT_B_BGA1-IC,TBD
M_G_DQ<9>                J1G1             16       SCONN288_H44441004_PIP-SCONN,HA
M_G_DQ<9>                J9T1             161      SCONN288_H44441003_PIP-SCONN,HA
M_G_DQ<9>                U2D1             W84      SKX_EXT_B_BGA1-IC,TBD
M_G_DQ<10>               J1G1             168      SCONN288_H44441004_PIP-SCONN,HA
M_G_DQ<10>               J9T1             23       SCONN288_H44441003_PIP-SCONN,HA
M_G_DQ<10>               U2D1             L86      SKX_EXT_B_BGA1-IC,TBD
M_G_DQ<11>               J1G1             23       SCONN288_H44441004_PIP-SCONN,HA
M_G_DQ<11>               J9T1             168      SCONN288_H44441003_PIP-SCONN,HA
M_G_DQ<11>               U2D1             L84      SKX_EXT_B_BGA1-IC,TBD
M_G_DQ<12>               J1G1             159      SCONN288_H44441004_PIP-SCONN,HA
M_G_DQ<12>               J9T1             14       SCONN288_H44441003_PIP-SCONN,HA
M_G_DQ<12>               U2D1             AA86     SKX_EXT_B_BGA1-IC,TBD
M_G_DQ<13>               J1G1             14       SCONN288_H44441004_PIP-SCONN,HA
M_G_DQ<13>               J9T1             159      SCONN288_H44441003_PIP-SCONN,HA
M_G_DQ<13>               U2D1             AA84     SKX_EXT_B_BGA1-IC,TBD
M_G_DQ<14>               J1G1             166      SCONN288_H44441004_PIP-SCONN,HA
M_G_DQ<14>               J9T1             21       SCONN288_H44441003_PIP-SCONN,HA
M_G_DQ<14>               U2D1             N86      SKX_EXT_B_BGA1-IC,TBD
M_G_DQ<15>               J1G1             21       SCONN288_H44441004_PIP-SCONN,HA
M_G_DQ<15>               J9T1             166      SCONN288_H44441003_PIP-SCONN,HA
M_G_DQ<15>               U2D1             N84      SKX_EXT_B_BGA1-IC,TBD
M_G_DQ<16>               J1G1             172      SCONN288_H44441004_PIP-SCONN,HA
M_G_DQ<16>               J9T1             27       SCONN288_H44441003_PIP-SCONN,HA
M_G_DQ<16>               U2D1             V81      SKX_EXT_B_BGA1-IC,TBD
M_G_DQ<17>               J1G1             27       SCONN288_H44441004_PIP-SCONN,HA
M_G_DQ<17>               J9T1             172      SCONN288_H44441003_PIP-SCONN,HA
M_G_DQ<17>               U2D1             T79      SKX_EXT_B_BGA1-IC,TBD
M_G_DQ<18>               J1G1             179      SCONN288_H44441004_PIP-SCONN,HA
M_G_DQ<18>               J9T1             34       SCONN288_H44441003_PIP-SCONN,HA
M_G_DQ<18>               U2D1             N82      SKX_EXT_B_BGA1-IC,TBD
M_G_DQ<19>               J1G1             34       SCONN288_H44441004_PIP-SCONN,HA
M_G_DQ<19>               J9T1             179      SCONN288_H44441003_PIP-SCONN,HA
M_G_DQ<19>               U2D1             M81      SKX_EXT_B_BGA1-IC,TBD
M_G_DQ<20>               J1G1             170      SCONN288_H44441004_PIP-SCONN,HA
M_G_DQ<20>               J9T1             25       SCONN288_H44441003_PIP-SCONN,HA
M_G_DQ<20>               U2D1             W80      SKX_EXT_B_BGA1-IC,TBD
M_G_DQ<21>               J1G1             25       SCONN288_H44441004_PIP-SCONN,HA
M_G_DQ<21>               J9T1             170      SCONN288_H44441003_PIP-SCONN,HA
M_G_DQ<21>               U2D1             V79      SKX_EXT_B_BGA1-IC,TBD
M_G_DQ<22>               J1G1             177      SCONN288_H44441004_PIP-SCONN,HA
M_G_DQ<22>               J9T1             32       SCONN288_H44441003_PIP-SCONN,HA
M_G_DQ<22>               U2D1             R82      SKX_EXT_B_BGA1-IC,TBD
M_G_DQ<23>               J1G1             32       SCONN288_H44441004_PIP-SCONN,HA
M_G_DQ<23>               J9T1             177      SCONN288_H44441003_PIP-SCONN,HA
M_G_DQ<23>               U2D1             N80      SKX_EXT_B_BGA1-IC,TBD
M_G_DQ<24>               J1G1             183      SCONN288_H44441004_PIP-SCONN,HA
M_G_DQ<24>               J9T1             38       SCONN288_H44441003_PIP-SCONN,HA
M_G_DQ<24>               U2D1             L76      SKX_EXT_B_BGA1-IC,TBD
M_G_DQ<25>               J1G1             38       SCONN288_H44441004_PIP-SCONN,HA
M_G_DQ<25>               J9T1             183      SCONN288_H44441003_PIP-SCONN,HA
M_G_DQ<25>               U2D1             R76      SKX_EXT_B_BGA1-IC,TBD
M_G_DQ<26>               J1G1             190      SCONN288_H44441004_PIP-SCONN,HA
M_G_DQ<26>               J9T1             45       SCONN288_H44441003_PIP-SCONN,HA
M_G_DQ<26>               U2D1             M73      SKX_EXT_B_BGA1-IC,TBD
M_G_DQ<27>               J1G1             45       SCONN288_H44441004_PIP-SCONN,HA
M_G_DQ<27>               J9T1             190      SCONN288_H44441003_PIP-SCONN,HA
M_G_DQ<27>               U2D1             P73      SKX_EXT_B_BGA1-IC,TBD
M_G_DQ<28>               J1G1             181      SCONN288_H44441004_PIP-SCONN,HA
M_G_DQ<28>               J9T1             36       SCONN288_H44441003_PIP-SCONN,HA
M_G_DQ<28>               U2D1             M77      SKX_EXT_B_BGA1-IC,TBD
M_G_DQ<29>               J1G1             36       SCONN288_H44441004_PIP-SCONN,HA
M_G_DQ<29>               J9T1             181      SCONN288_H44441003_PIP-SCONN,HA
M_G_DQ<29>               U2D1             P77      SKX_EXT_B_BGA1-IC,TBD
M_G_DQ<30>               J1G1             188      SCONN288_H44441004_PIP-SCONN,HA
M_G_DQ<30>               J9T1             43       SCONN288_H44441003_PIP-SCONN,HA
M_G_DQ<30>               U2D1             L74      SKX_EXT_B_BGA1-IC,TBD
M_G_DQ<31>               J1G1             43       SCONN288_H44441004_PIP-SCONN,HA
M_G_DQ<31>               J9T1             188      SCONN288_H44441003_PIP-SCONN,HA
M_G_DQ<31>               U2D1             R74      SKX_EXT_B_BGA1-IC,TBD
M_G_DQ<32>               J1G1             242      SCONN288_H44441004_PIP-SCONN,HA
M_G_DQ<32>               J9T1             97       SCONN288_H44441003_PIP-SCONN,HA
M_G_DQ<32>               U2D1             C42      SKX_EXT_B_BGA1-IC,TBD
M_G_DQ<33>               J1G1             97       SCONN288_H44441004_PIP-SCONN,HA
M_G_DQ<33>               J9T1             242      SCONN288_H44441003_PIP-SCONN,HA
M_G_DQ<33>               U2D1             B41      SKX_EXT_B_BGA1-IC,TBD
M_G_DQ<34>               J1G1             249      SCONN288_H44441004_PIP-SCONN,HA
M_G_DQ<34>               J9T1             104      SCONN288_H44441003_PIP-SCONN,HA
M_G_DQ<34>               U2D1             C38      SKX_EXT_B_BGA1-IC,TBD
M_G_DQ<35>               J1G1             104      SCONN288_H44441004_PIP-SCONN,HA
M_G_DQ<35>               J9T1             249      SCONN288_H44441003_PIP-SCONN,HA
M_G_DQ<35>               U2D1             E38      SKX_EXT_B_BGA1-IC,TBD
M_G_DQ<36>               J1G1             240      SCONN288_H44441004_PIP-SCONN,HA
M_G_DQ<36>               J9T1             95       SCONN288_H44441003_PIP-SCONN,HA
M_G_DQ<36>               U2D1             E42      SKX_EXT_B_BGA1-IC,TBD
M_G_DQ<37>               J1G1             95       SCONN288_H44441004_PIP-SCONN,HA
M_G_DQ<37>               J9T1             240      SCONN288_H44441003_PIP-SCONN,HA
M_G_DQ<37>               U2D1             F41      SKX_EXT_B_BGA1-IC,TBD
M_G_DQ<38>               J1G1             247      SCONN288_H44441004_PIP-SCONN,HA
M_G_DQ<38>               J9T1             102      SCONN288_H44441003_PIP-SCONN,HA
M_G_DQ<38>               U2D1             B39      SKX_EXT_B_BGA1-IC,TBD
M_G_DQ<39>               J1G1             102      SCONN288_H44441004_PIP-SCONN,HA
M_G_DQ<39>               J9T1             247      SCONN288_H44441003_PIP-SCONN,HA
M_G_DQ<39>               U2D1             F39      SKX_EXT_B_BGA1-IC,TBD
M_G_DQ<40>               J1G1             253      SCONN288_H44441004_PIP-SCONN,HA
M_G_DQ<40>               J9T1             108      SCONN288_H44441003_PIP-SCONN,HA
M_G_DQ<40>               U2D1             K37      SKX_EXT_B_BGA1-IC,TBD
M_G_DQ<41>               J1G1             108      SCONN288_H44441004_PIP-SCONN,HA
M_G_DQ<41>               J9T1             253      SCONN288_H44441003_PIP-SCONN,HA
M_G_DQ<41>               U2D1             P37      SKX_EXT_B_BGA1-IC,TBD
M_G_DQ<42>               J1G1             260      SCONN288_H44441004_PIP-SCONN,HA
M_G_DQ<42>               J9T1             115      SCONN288_H44441003_PIP-SCONN,HA
M_G_DQ<42>               U2D1             L34      SKX_EXT_B_BGA1-IC,TBD
M_G_DQ<43>               J1G1             115      SCONN288_H44441004_PIP-SCONN,HA
M_G_DQ<43>               J9T1             260      SCONN288_H44441003_PIP-SCONN,HA
M_G_DQ<43>               U2D1             N34      SKX_EXT_B_BGA1-IC,TBD
M_G_DQ<44>               J1G1             251      SCONN288_H44441004_PIP-SCONN,HA
M_G_DQ<44>               J9T1             106      SCONN288_H44441003_PIP-SCONN,HA
M_G_DQ<44>               U2D1             L38      SKX_EXT_B_BGA1-IC,TBD
M_G_DQ<45>               J1G1             106      SCONN288_H44441004_PIP-SCONN,HA
M_G_DQ<45>               J9T1             251      SCONN288_H44441003_PIP-SCONN,HA
M_G_DQ<45>               U2D1             N38      SKX_EXT_B_BGA1-IC,TBD
M_G_DQ<46>               J1G1             258      SCONN288_H44441004_PIP-SCONN,HA
M_G_DQ<46>               J9T1             113      SCONN288_H44441003_PIP-SCONN,HA
M_G_DQ<46>               U2D1             K35      SKX_EXT_B_BGA1-IC,TBD
M_G_DQ<47>               J1G1             113      SCONN288_H44441004_PIP-SCONN,HA
M_G_DQ<47>               J9T1             258      SCONN288_H44441003_PIP-SCONN,HA
M_G_DQ<47>               U2D1             P35      SKX_EXT_B_BGA1-IC,TBD
M_G_DQ<48>               J1G1             264      SCONN288_H44441004_PIP-SCONN,HA
M_G_DQ<48>               J9T1             119      SCONN288_H44441003_PIP-SCONN,HA
M_G_DQ<48>               U2D1             K31      SKX_EXT_B_BGA1-IC,TBD
M_G_DQ<49>               J1G1             119      SCONN288_H44441004_PIP-SCONN,HA
M_G_DQ<49>               J9T1             264      SCONN288_H44441003_PIP-SCONN,HA
M_G_DQ<49>               U2D1             P31      SKX_EXT_B_BGA1-IC,TBD
M_G_DQ<50>               J1G1             271      SCONN288_H44441004_PIP-SCONN,HA
M_G_DQ<50>               J9T1             126      SCONN288_H44441003_PIP-SCONN,HA
M_G_DQ<50>               U2D1             L28      SKX_EXT_B_BGA1-IC,TBD
M_G_DQ<51>               J1G1             126      SCONN288_H44441004_PIP-SCONN,HA
M_G_DQ<51>               J9T1             271      SCONN288_H44441003_PIP-SCONN,HA
M_G_DQ<51>               U2D1             N28      SKX_EXT_B_BGA1-IC,TBD
M_G_DQ<52>               J1G1             262      SCONN288_H44441004_PIP-SCONN,HA
M_G_DQ<52>               J9T1             117      SCONN288_H44441003_PIP-SCONN,HA
M_G_DQ<52>               U2D1             L32      SKX_EXT_B_BGA1-IC,TBD
M_G_DQ<53>               J1G1             117      SCONN288_H44441004_PIP-SCONN,HA
M_G_DQ<53>               J9T1             262      SCONN288_H44441003_PIP-SCONN,HA
M_G_DQ<53>               U2D1             N32      SKX_EXT_B_BGA1-IC,TBD
M_G_DQ<54>               J1G1             269      SCONN288_H44441004_PIP-SCONN,HA
M_G_DQ<54>               J9T1             124      SCONN288_H44441003_PIP-SCONN,HA
M_G_DQ<54>               U2D1             K29      SKX_EXT_B_BGA1-IC,TBD
M_G_DQ<55>               J1G1             124      SCONN288_H44441004_PIP-SCONN,HA
M_G_DQ<55>               J9T1             269      SCONN288_H44441003_PIP-SCONN,HA
M_G_DQ<55>               U2D1             P29      SKX_EXT_B_BGA1-IC,TBD
M_G_DQ<56>               J1G1             275      SCONN288_H44441004_PIP-SCONN,HA
M_G_DQ<56>               J9T1             130      SCONN288_H44441003_PIP-SCONN,HA
M_G_DQ<56>               U2D1             K25      SKX_EXT_B_BGA1-IC,TBD
M_G_DQ<57>               J1G1             130      SCONN288_H44441004_PIP-SCONN,HA
M_G_DQ<57>               J9T1             275      SCONN288_H44441003_PIP-SCONN,HA
M_G_DQ<57>               U2D1             P25      SKX_EXT_B_BGA1-IC,TBD
M_G_DQ<58>               J1G1             282      SCONN288_H44441004_PIP-SCONN,HA
M_G_DQ<58>               J9T1             137      SCONN288_H44441003_PIP-SCONN,HA
M_G_DQ<58>               U2D1             P23      SKX_EXT_B_BGA1-IC,TBD
M_G_DQ<59>               J1G1             137      SCONN288_H44441004_PIP-SCONN,HA
M_G_DQ<59>               J9T1             282      SCONN288_H44441003_PIP-SCONN,HA
M_G_DQ<59>               U2D1             T23      SKX_EXT_B_BGA1-IC,TBD
M_G_DQ<60>               J1G1             273      SCONN288_H44441004_PIP-SCONN,HA
M_G_DQ<60>               J9T1             128      SCONN288_H44441003_PIP-SCONN,HA
M_G_DQ<60>               U2D1             L26      SKX_EXT_B_BGA1-IC,TBD
M_G_DQ<61>               J1G1             128      SCONN288_H44441004_PIP-SCONN,HA
M_G_DQ<61>               J9T1             273      SCONN288_H44441003_PIP-SCONN,HA
M_G_DQ<61>               U2D1             N26      SKX_EXT_B_BGA1-IC,TBD
M_G_DQ<62>               J1G1             280      SCONN288_H44441004_PIP-SCONN,HA
M_G_DQ<62>               J9T1             135      SCONN288_H44441003_PIP-SCONN,HA
M_G_DQ<62>               U2D1             H23      SKX_EXT_B_BGA1-IC,TBD
M_G_DQ<63>               J1G1             135      SCONN288_H44441004_PIP-SCONN,HA
M_G_DQ<63>               J9T1             280      SCONN288_H44441003_PIP-SCONN,HA
M_G_DQ<63>               U2D1             K23      SKX_EXT_B_BGA1-IC,TBD
M_G_DQS_DN<0>            J1G1             152      SCONN288_H44441004_PIP-SCONN,HA
M_G_DQS_DN<0>            J9T1             152      SCONN288_H44441003_PIP-SCONN,HA
M_G_DQS_DN<0>            U2D1             AJ84     SKX_EXT_B_BGA1-IC,TBD
M_G_DQS_DN<1>            J1G1             163      SCONN288_H44441004_PIP-SCONN,HA
M_G_DQS_DN<1>            J9T1             163      SCONN288_H44441003_PIP-SCONN,HA
M_G_DQS_DN<1>            U2D1             R84      SKX_EXT_B_BGA1-IC,TBD
M_G_DQS_DN<2>            J1G1             174      SCONN288_H44441004_PIP-SCONN,HA
M_G_DQS_DN<2>            J9T1             174      SCONN288_H44441003_PIP-SCONN,HA
M_G_DQS_DN<2>            U2D1             P79      SKX_EXT_B_BGA1-IC,TBD
M_G_DQS_DN<3>            J1G1             185      SCONN288_H44441004_PIP-SCONN,HA
M_G_DQS_DN<3>            J9T1             185      SCONN288_H44441003_PIP-SCONN,HA
M_G_DQS_DN<3>            U2D1             T75      SKX_EXT_B_BGA1-IC,TBD
M_G_DQS_DN<4>            J1G1             244      SCONN288_H44441004_PIP-SCONN,HA
M_G_DQS_DN<4>            J9T1             244      SCONN288_H44441003_PIP-SCONN,HA
M_G_DQS_DN<4>            U2D1             G40      SKX_EXT_B_BGA1-IC,TBD
M_G_DQS_DN<5>            J1G1             255      SCONN288_H44441004_PIP-SCONN,HA
M_G_DQS_DN<5>            J9T1             255      SCONN288_H44441003_PIP-SCONN,HA
M_G_DQS_DN<5>            U2D1             R36      SKX_EXT_B_BGA1-IC,TBD
M_G_DQS_DN<6>            J1G1             266      SCONN288_H44441004_PIP-SCONN,HA
M_G_DQS_DN<6>            J9T1             266      SCONN288_H44441003_PIP-SCONN,HA
M_G_DQS_DN<6>            U2D1             R30      SKX_EXT_B_BGA1-IC,TBD
M_G_DQS_DN<7>            J1G1             277      SCONN288_H44441004_PIP-SCONN,HA
M_G_DQS_DN<7>            J9T1             277      SCONN288_H44441003_PIP-SCONN,HA
M_G_DQS_DN<7>            U2D1             N24      SKX_EXT_B_BGA1-IC,TBD
M_G_DQS_DN<8>            J1G1             196      SCONN288_H44441004_PIP-SCONN,HA
M_G_DQS_DN<8>            J9T1             196      SCONN288_H44441003_PIP-SCONN,HA
M_G_DQS_DN<8>            U2D1             AH67     SKX_EXT_B_BGA1-IC,TBD
M_G_DQS_DN<9>            J1G1             8        SCONN288_H44441004_PIP-SCONN,HA
M_G_DQS_DN<9>            J9T1             8        SCONN288_H44441003_PIP-SCONN,HA
M_G_DQS_DN<9>            U2D1             AL84     SKX_EXT_B_BGA1-IC,TBD
M_G_DQS_DN<10>           J1G1             19       SCONN288_H44441004_PIP-SCONN,HA
M_G_DQS_DN<10>           J9T1             19       SCONN288_H44441003_PIP-SCONN,HA
M_G_DQS_DN<10>           U2D1             U84      SKX_EXT_B_BGA1-IC,TBD
M_G_DQS_DN<11>           J1G1             30       SCONN288_H44441004_PIP-SCONN,HA
M_G_DQS_DN<11>           J9T1             30       SCONN288_H44441003_PIP-SCONN,HA
M_G_DQS_DN<11>           U2D1             U82      SKX_EXT_B_BGA1-IC,TBD
M_G_DQS_DN<12>           J1G1             41       SCONN288_H44441004_PIP-SCONN,HA
M_G_DQS_DN<12>           J9T1             41       SCONN288_H44441003_PIP-SCONN,HA
M_G_DQS_DN<12>           U2D1             K75      SKX_EXT_B_BGA1-IC,TBD
M_G_DQS_DN<13>           J1G1             100      SCONN288_H44441004_PIP-SCONN,HA
M_G_DQS_DN<13>           J9T1             100      SCONN288_H44441003_PIP-SCONN,HA
M_G_DQS_DN<13>           U2D1             A40      SKX_EXT_B_BGA1-IC,TBD
M_G_DQS_DN<14>           J1G1             111      SCONN288_H44441004_PIP-SCONN,HA
M_G_DQS_DN<14>           J9T1             111      SCONN288_H44441003_PIP-SCONN,HA
M_G_DQS_DN<14>           U2D1             J36      SKX_EXT_B_BGA1-IC,TBD
M_G_DQS_DN<15>           J1G1             122      SCONN288_H44441004_PIP-SCONN,HA
M_G_DQS_DN<15>           J9T1             122      SCONN288_H44441003_PIP-SCONN,HA
M_G_DQS_DN<15>           U2D1             J30      SKX_EXT_B_BGA1-IC,TBD
M_G_DQS_DN<16>           J1G1             133      SCONN288_H44441004_PIP-SCONN,HA
M_G_DQS_DN<16>           J9T1             133      SCONN288_H44441003_PIP-SCONN,HA
M_G_DQS_DN<16>           U2D1             J24      SKX_EXT_B_BGA1-IC,TBD
M_G_DQS_DN<17>           J1G1             52       SCONN288_H44441004_PIP-SCONN,HA
M_G_DQS_DN<17>           J9T1             52       SCONN288_H44441003_PIP-SCONN,HA
M_G_DQS_DN<17>           U2D1             AB67     SKX_EXT_B_BGA1-IC,TBD
M_G_DQS_DP<0>            J1G1             153      SCONN288_H44441004_PIP-SCONN,HA
M_G_DQS_DP<0>            J9T1             153      SCONN288_H44441003_PIP-SCONN,HA
M_G_DQS_DP<0>            U2D1             AH85     SKX_EXT_B_BGA1-IC,TBD
M_G_DQS_DP<1>            J1G1             164      SCONN288_H44441004_PIP-SCONN,HA
M_G_DQS_DP<1>            J9T1             164      SCONN288_H44441003_PIP-SCONN,HA
M_G_DQS_DP<1>            U2D1             P85      SKX_EXT_B_BGA1-IC,TBD
M_G_DQS_DP<2>            J1G1             175      SCONN288_H44441004_PIP-SCONN,HA
M_G_DQS_DP<2>            J9T1             175      SCONN288_H44441003_PIP-SCONN,HA
M_G_DQS_DP<2>            U2D1             R80      SKX_EXT_B_BGA1-IC,TBD
M_G_DQS_DP<3>            J1G1             186      SCONN288_H44441004_PIP-SCONN,HA
M_G_DQS_DP<3>            J9T1             186      SCONN288_H44441003_PIP-SCONN,HA
M_G_DQS_DP<3>            U2D1             P75      SKX_EXT_B_BGA1-IC,TBD
M_G_DQS_DP<4>            J1G1             245      SCONN288_H44441004_PIP-SCONN,HA
M_G_DQS_DP<4>            J9T1             245      SCONN288_H44441003_PIP-SCONN,HA
M_G_DQS_DP<4>            U2D1             E40      SKX_EXT_B_BGA1-IC,TBD
M_G_DQS_DP<5>            J1G1             256      SCONN288_H44441004_PIP-SCONN,HA
M_G_DQS_DP<5>            J9T1             256      SCONN288_H44441003_PIP-SCONN,HA
M_G_DQS_DP<5>            U2D1             N36      SKX_EXT_B_BGA1-IC,TBD
M_G_DQS_DP<6>            J1G1             267      SCONN288_H44441004_PIP-SCONN,HA
M_G_DQS_DP<6>            J9T1             267      SCONN288_H44441003_PIP-SCONN,HA
M_G_DQS_DP<6>            U2D1             N30      SKX_EXT_B_BGA1-IC,TBD
M_G_DQS_DP<7>            J1G1             278      SCONN288_H44441004_PIP-SCONN,HA
M_G_DQS_DP<7>            J9T1             278      SCONN288_H44441003_PIP-SCONN,HA
M_G_DQS_DP<7>            U2D1             R24      SKX_EXT_B_BGA1-IC,TBD
M_G_DQS_DP<8>            J1G1             197      SCONN288_H44441004_PIP-SCONN,HA
M_G_DQS_DP<8>            J9T1             197      SCONN288_H44441003_PIP-SCONN,HA
M_G_DQS_DP<8>            U2D1             AF67     SKX_EXT_B_BGA1-IC,TBD
M_G_DQS_DP<9>            J1G1             7        SCONN288_H44441004_PIP-SCONN,HA
M_G_DQS_DP<9>            J9T1             7        SCONN288_H44441003_PIP-SCONN,HA
M_G_DQS_DP<9>            U2D1             AM85     SKX_EXT_B_BGA1-IC,TBD
M_G_DQS_DP<10>           J1G1             18       SCONN288_H44441004_PIP-SCONN,HA
M_G_DQS_DP<10>           J9T1             18       SCONN288_H44441003_PIP-SCONN,HA
M_G_DQS_DP<10>           U2D1             V85      SKX_EXT_B_BGA1-IC,TBD
M_G_DQS_DP<11>           J1G1             29       SCONN288_H44441004_PIP-SCONN,HA
M_G_DQS_DP<11>           J9T1             29       SCONN288_H44441003_PIP-SCONN,HA
M_G_DQS_DP<11>           U2D1             T81      SKX_EXT_B_BGA1-IC,TBD
M_G_DQS_DP<12>           J1G1             40       SCONN288_H44441004_PIP-SCONN,HA
M_G_DQS_DP<12>           J9T1             40       SCONN288_H44441003_PIP-SCONN,HA
M_G_DQS_DP<12>           U2D1             M75      SKX_EXT_B_BGA1-IC,TBD
M_G_DQS_DP<13>           J1G1             99       SCONN288_H44441004_PIP-SCONN,HA
M_G_DQS_DP<13>           J9T1             99       SCONN288_H44441003_PIP-SCONN,HA
M_G_DQS_DP<13>           U2D1             C40      SKX_EXT_B_BGA1-IC,TBD
M_G_DQS_DP<14>           J1G1             110      SCONN288_H44441004_PIP-SCONN,HA
M_G_DQS_DP<14>           J9T1             110      SCONN288_H44441003_PIP-SCONN,HA
M_G_DQS_DP<14>           U2D1             L36      SKX_EXT_B_BGA1-IC,TBD
M_G_DQS_DP<15>           J1G1             121      SCONN288_H44441004_PIP-SCONN,HA
M_G_DQS_DP<15>           J9T1             121      SCONN288_H44441003_PIP-SCONN,HA
M_G_DQS_DP<15>           U2D1             L30      SKX_EXT_B_BGA1-IC,TBD
M_G_DQS_DP<16>           J1G1             132      SCONN288_H44441004_PIP-SCONN,HA
M_G_DQS_DP<16>           J9T1             132      SCONN288_H44441003_PIP-SCONN,HA
M_G_DQS_DP<16>           U2D1             L24      SKX_EXT_B_BGA1-IC,TBD
M_G_DQS_DP<17>           J1G1             51       SCONN288_H44441004_PIP-SCONN,HA
M_G_DQS_DP<17>           J9T1             51       SCONN288_H44441003_PIP-SCONN,HA
M_G_DQS_DP<17>           U2D1             AD67     SKX_EXT_B_BGA1-IC,TBD
M_G_ECC<0>               J1G1             194      SCONN288_H44441004_PIP-SCONN,HA
M_G_ECC<0>               J9T1             49       SCONN288_H44441003_PIP-SCONN,HA
M_G_ECC<0>               U2D1             AC68     SKX_EXT_B_BGA1-IC,TBD
M_G_ECC<1>               J1G1             49       SCONN288_H44441004_PIP-SCONN,HA
M_G_ECC<1>               J9T1             194      SCONN288_H44441003_PIP-SCONN,HA
M_G_ECC<1>               U2D1             AG68     SKX_EXT_B_BGA1-IC,TBD
M_G_ECC<2>               J1G1             201      SCONN288_H44441004_PIP-SCONN,HA
M_G_ECC<2>               J9T1             56       SCONN288_H44441003_PIP-SCONN,HA
M_G_ECC<2>               U2D1             AD65     SKX_EXT_B_BGA1-IC,TBD
M_G_ECC<3>               J1G1             56       SCONN288_H44441004_PIP-SCONN,HA
M_G_ECC<3>               J9T1             201      SCONN288_H44441003_PIP-SCONN,HA
M_G_ECC<3>               U2D1             AF65     SKX_EXT_B_BGA1-IC,TBD
M_G_ECC<4>               J1G1             192      SCONN288_H44441004_PIP-SCONN,HA
M_G_ECC<4>               J9T1             47       SCONN288_H44441003_PIP-SCONN,HA
M_G_ECC<4>               U2D1             AD69     SKX_EXT_B_BGA1-IC,TBD
M_G_ECC<5>               J1G1             47       SCONN288_H44441004_PIP-SCONN,HA
M_G_ECC<5>               J9T1             192      SCONN288_H44441003_PIP-SCONN,HA
M_G_ECC<5>               U2D1             AF69     SKX_EXT_B_BGA1-IC,TBD
M_G_ECC<6>               J1G1             199      SCONN288_H44441004_PIP-SCONN,HA
M_G_ECC<6>               J9T1             54       SCONN288_H44441003_PIP-SCONN,HA
M_G_ECC<6>               U2D1             AC66     SKX_EXT_B_BGA1-IC,TBD
M_G_ECC<7>               J1G1             54       SCONN288_H44441004_PIP-SCONN,HA
M_G_ECC<7>               J9T1             199      SCONN288_H44441003_PIP-SCONN,HA
M_G_ECC<7>               U2D1             AG66     SKX_EXT_B_BGA1-IC,TBD
M_G_MA<0>                J1G1             79       SCONN288_H44441004_PIP-SCONN,HA
M_G_MA<0>                J9T1             79       SCONN288_H44441003_PIP-SCONN,HA
M_G_MA<0>                U2D1             F53      SKX_EXT_B_BGA1-IC,TBD
M_G_MA<1>                J1G1             72       SCONN288_H44441004_PIP-SCONN,HA
M_G_MA<1>                J9T1             72       SCONN288_H44441003_PIP-SCONN,HA
M_G_MA<1>                U2D1             F57      SKX_EXT_B_BGA1-IC,TBD
M_G_MA<2>                J1G1             216      SCONN288_H44441004_PIP-SCONN,HA
M_G_MA<2>                J9T1             216      SCONN288_H44441003_PIP-SCONN,HA
M_G_MA<2>                U2D1             D57      SKX_EXT_B_BGA1-IC,TBD
M_G_MA<3>                J1G1             71       SCONN288_H44441004_PIP-SCONN,HA
M_G_MA<3>                J9T1             71       SCONN288_H44441003_PIP-SCONN,HA
M_G_MA<3>                U2D1             C58      SKX_EXT_B_BGA1-IC,TBD
M_G_MA<4>                J1G1             214      SCONN288_H44441004_PIP-SCONN,HA
M_G_MA<4>                J9T1             214      SCONN288_H44441003_PIP-SCONN,HA
M_G_MA<4>                U2D1             G58      SKX_EXT_B_BGA1-IC,TBD
M_G_MA<5>                J1G1             213      SCONN288_H44441004_PIP-SCONN,HA
M_G_MA<5>                J9T1             213      SCONN288_H44441003_PIP-SCONN,HA
M_G_MA<5>                U2D1             F59      SKX_EXT_B_BGA1-IC,TBD
M_G_MA<6>                J1G1             69       SCONN288_H44441004_PIP-SCONN,HA
M_G_MA<6>                J9T1             69       SCONN288_H44441003_PIP-SCONN,HA
M_G_MA<6>                U2D1             D59      SKX_EXT_B_BGA1-IC,TBD
M_G_MA<7>                J1G1             211      SCONN288_H44441004_PIP-SCONN,HA
M_G_MA<7>                J9T1             211      SCONN288_H44441003_PIP-SCONN,HA
M_G_MA<7>                U2D1             G60      SKX_EXT_B_BGA1-IC,TBD
M_G_MA<8>                J1G1             68       SCONN288_H44441004_PIP-SCONN,HA
M_G_MA<8>                J9T1             68       SCONN288_H44441003_PIP-SCONN,HA
M_G_MA<8>                U2D1             C60      SKX_EXT_B_BGA1-IC,TBD
M_G_MA<9>                J1G1             66       SCONN288_H44441004_PIP-SCONN,HA
M_G_MA<9>                J9T1             66       SCONN288_H44441003_PIP-SCONN,HA
M_G_MA<9>                U2D1             F61      SKX_EXT_B_BGA1-IC,TBD
M_G_MA<10>               J1G1             225      SCONN288_H44441004_PIP-SCONN,HA
M_G_MA<10>               J9T1             225      SCONN288_H44441003_PIP-SCONN,HA
M_G_MA<10>               U2D1             J54      SKX_EXT_B_BGA1-IC,TBD
M_G_MA<11>               J1G1             210      SCONN288_H44441004_PIP-SCONN,HA
M_G_MA<11>               J9T1             210      SCONN288_H44441003_PIP-SCONN,HA
M_G_MA<11>               U2D1             G62      SKX_EXT_B_BGA1-IC,TBD
M_G_MA<12>               J1G1             65       SCONN288_H44441004_PIP-SCONN,HA
M_G_MA<12>               J9T1             65       SCONN288_H44441003_PIP-SCONN,HA
M_G_MA<12>               U2D1             J64      SKX_EXT_B_BGA1-IC,TBD
M_G_MA<13>               J1G1             232      SCONN288_H44441004_PIP-SCONN,HA
M_G_MA<13>               J9T1             232      SCONN288_H44441003_PIP-SCONN,HA
M_G_MA<13>               U2D1             J48      SKX_EXT_B_BGA1-IC,TBD
M_G_MA<14>               J1G1             228      SCONN288_H44441004_PIP-SCONN,HA
M_G_MA<14>               J9T1             228      SCONN288_H44441003_PIP-SCONN,HA
M_G_MA<14>               U2D1             F51      SKX_EXT_B_BGA1-IC,TBD
M_G_MA<15>               J1G1             86       SCONN288_H44441004_PIP-SCONN,HA
M_G_MA<15>               J9T1             86       SCONN288_H44441003_PIP-SCONN,HA
M_G_MA<15>               U2D1             K49      SKX_EXT_B_BGA1-IC,TBD
M_G_MA<16>               J1G1             82       SCONN288_H44441004_PIP-SCONN,HA
M_G_MA<16>               J9T1             82       SCONN288_H44441003_PIP-SCONN,HA
M_G_MA<16>               U2D1             D51      SKX_EXT_B_BGA1-IC,TBD
M_G_MA<17>               J1G1             234      SCONN288_H44441004_PIP-SCONN,HA
M_G_MA<17>               J9T1             234      SCONN288_H44441003_PIP-SCONN,HA
M_G_MA<17>               U2D1             K47      SKX_EXT_B_BGA1-IC,TBD
M_G_ODT<0>               J1G1             87       SCONN288_H44441004_PIP-SCONN,HA
M_G_ODT<0>               U2D1             C50      SKX_EXT_B_BGA1-IC,TBD
M_G_ODT<1>               J1G1             91       SCONN288_H44441004_PIP-SCONN,HA
M_G_ODT<1>               U2D1             C48      SKX_EXT_B_BGA1-IC,TBD
M_G_ODT<2>               J9T1             87       SCONN288_H44441003_PIP-SCONN,HA
M_G_ODT<2>               U2D1             G50      SKX_EXT_B_BGA1-IC,TBD
M_G_ODT<3>               J9T1             91       SCONN288_H44441003_PIP-SCONN,HA
M_G_ODT<3>               U2D1             G48      SKX_EXT_B_BGA1-IC,TBD
M_G_PAR                  J1G1             222      SCONN288_H44441004_PIP-SCONN,HA
M_G_PAR                  J9T1             222      SCONN288_H44441003_PIP-SCONN,HA
M_G_PAR                  U2D1             D53      SKX_EXT_B_BGA1-IC,TBD
M_G_VREF                 C1F22            1        CAP_A_0402V-0.01UF,25V,10%,X7RA
M_G_VREF                 C9T7             1        CAP_A_0402V-0.01UF,25V,10%,X7RA
M_G_VREF                 J1G1             146      SCONN288_H44441004_PIP-SCONN,HA
M_G_VREF                 J9T1             146      SCONN288_H44441003_PIP-SCONN,HA
M_G_VREF                 R1F4             2        RES_0402-2,1.0%,1/16W,CHIP,G21A
M_G_VREF                 R1F5             2        RES_0402-1.00K,1%,1/16W,CHIP,GA
M_G_VREF                 R1F6             1        RES_0402-1.00K,1%,1/16W,CHIP,GA
M_H_ACT_N                J1G2             62       SCONN288_H44441004_PIP-SCONN,HA
M_H_ACT_N                J9U1             62       SCONN288_H44441003_PIP-SCONN,HA
M_H_ACT_N                U2D1             T63      SKX_EXT_B_BGA1-IC,TBD
M_H_ALERT_N              J1G2             208      SCONN288_H44441004_PIP-SCONN,HA
M_H_ALERT_N              J9U1             208      SCONN288_H44441003_PIP-SCONN,HA
M_H_ALERT_N              U2D1             W62      SKX_EXT_B_BGA1-IC,TBD
M_H_BA<0>                J1G2             81       SCONN288_H44441004_PIP-SCONN,HA
M_H_BA<0>                J9U1             81       SCONN288_H44441003_PIP-SCONN,HA
M_H_BA<0>                U2D1             T53      SKX_EXT_B_BGA1-IC,TBD
M_H_BA<1>                J1G2             224      SCONN288_H44441004_PIP-SCONN,HA
M_H_BA<1>                J9U1             224      SCONN288_H44441003_PIP-SCONN,HA
M_H_BA<1>                U2D1             K55      SKX_EXT_B_BGA1-IC,TBD
M_H_BG<0>                J1G2             63       SCONN288_H44441004_PIP-SCONN,HA
M_H_BG<0>                J9U1             63       SCONN288_H44441003_PIP-SCONN,HA
M_H_BG<0>                U2D1             M61      SKX_EXT_B_BGA1-IC,TBD
M_H_BG<1>                J1G2             207      SCONN288_H44441004_PIP-SCONN,HA
M_H_BG<1>                J9U1             207      SCONN288_H44441003_PIP-SCONN,HA
M_H_BG<1>                U2D1             N60      SKX_EXT_B_BGA1-IC,TBD
M_H_C<2>                 J1G2             235      SCONN288_H44441004_PIP-SCONN,HA
M_H_C<2>                 J9U1             235      SCONN288_H44441003_PIP-SCONN,HA
M_H_C<2>                 U2D1             M47      SKX_EXT_B_BGA1-IC,TBD
M_H_CKE<0>               J1G2             60       SCONN288_H44441004_PIP-SCONN,HA
M_H_CKE<0>               U2D1             N62      SKX_EXT_B_BGA1-IC,TBD
M_H_CKE<1>               J1G2             203      SCONN288_H44441004_PIP-SCONN,HA
M_H_CKE<1>               U2D1             R64      SKX_EXT_B_BGA1-IC,TBD
M_H_CKE<2>               J9U1             60       SCONN288_H44441003_PIP-SCONN,HA
M_H_CKE<2>               U2D1             K63      SKX_EXT_B_BGA1-IC,TBD
M_H_CKE<3>               J9U1             203      SCONN288_H44441003_PIP-SCONN,HA
M_H_CKE<3>               U2D1             L64      SKX_EXT_B_BGA1-IC,TBD
M_H_CLK_DN<0>            J1G2             75       SCONN288_H44441004_PIP-SCONN,HA
M_H_CLK_DN<0>            U2D1             M53      SKX_EXT_B_BGA1-IC,TBD
M_H_CLK_DN<1>            J1G2             219      SCONN288_H44441004_PIP-SCONN,HA
M_H_CLK_DN<1>            U2D1             R54      SKX_EXT_B_BGA1-IC,TBD
M_H_CLK_DN<2>            J9U1             75       SCONN288_H44441003_PIP-SCONN,HA
M_H_CLK_DN<2>            U2D1             N56      SKX_EXT_B_BGA1-IC,TBD
M_H_CLK_DN<3>            J9U1             219      SCONN288_H44441003_PIP-SCONN,HA
M_H_CLK_DN<3>            U2D1             R56      SKX_EXT_B_BGA1-IC,TBD
M_H_CLK_DP<0>            J1G2             74       SCONN288_H44441004_PIP-SCONN,HA
M_H_CLK_DP<0>            U2D1             N54      SKX_EXT_B_BGA1-IC,TBD
M_H_CLK_DP<1>            J1G2             218      SCONN288_H44441004_PIP-SCONN,HA
M_H_CLK_DP<1>            U2D1             T55      SKX_EXT_B_BGA1-IC,TBD
M_H_CLK_DP<2>            J9U1             74       SCONN288_H44441003_PIP-SCONN,HA
M_H_CLK_DP<2>            U2D1             M57      SKX_EXT_B_BGA1-IC,TBD
M_H_CLK_DP<3>            J9U1             218      SCONN288_H44441003_PIP-SCONN,HA
M_H_CLK_DP<3>            U2D1             T57      SKX_EXT_B_BGA1-IC,TBD
M_H_CPU_VREF             C1G8             1        CAP_A_0402V-0.01UF,25V,10%,X7RA
M_H_CPU_VREF             R1G1             1        RES_0402-2,1.0%,1/16W,CHIP,G21A
M_H_CPU_VREF             U2D1             AK63     SKX_EXT_B_BGA1-IC,TBD
M_H_CS_N<0>              J1G2             84       SCONN288_H44441004_PIP-SCONN,HA
M_H_CS_N<0>              U2D1             K51      SKX_EXT_B_BGA1-IC,TBD
M_H_CS_N<1>              J1G2             89       SCONN288_H44441004_PIP-SCONN,HA
M_H_CS_N<1>              U2D1             R50      SKX_EXT_B_BGA1-IC,TBD
M_H_CS_N<2>              J1G2             93       SCONN288_H44441004_PIP-SCONN,HA
M_H_CS_N<2>              U2D1             N46      SKX_EXT_B_BGA1-IC,TBD
M_H_CS_N<3>              J1G2             237      SCONN288_H44441004_PIP-SCONN,HA
M_H_CS_N<3>              U2D1             V47      SKX_EXT_B_BGA1-IC,TBD
M_H_CS_N<4>              J9U1             84       SCONN288_H44441003_PIP-SCONN,HA
M_H_CS_N<4>              U2D1             J50      SKX_EXT_B_BGA1-IC,TBD
M_H_CS_N<5>              J9U1             89       SCONN288_H44441003_PIP-SCONN,HA
M_H_CS_N<5>              U2D1             T49      SKX_EXT_B_BGA1-IC,TBD
M_H_CS_N<6>              J9U1             93       SCONN288_H44441003_PIP-SCONN,HA
M_H_CS_N<6>              U2D1             M45      SKX_EXT_B_BGA1-IC,TBD
M_H_CS_N<7>              J9U1             237      SCONN288_H44441003_PIP-SCONN,HA
M_H_CS_N<7>              U2D1             R46      SKX_EXT_B_BGA1-IC,TBD
M_H_DQ<0>                J1G2             150      SCONN288_H44441004_PIP-SCONN,HA
M_H_DQ<0>                J9U1             5        SCONN288_H44441003_PIP-SCONN,HA
M_H_DQ<0>                U2D1             AV81     SKX_EXT_B_BGA1-IC,TBD
M_H_DQ<1>                J1G2             5        SCONN288_H44441004_PIP-SCONN,HA
M_H_DQ<1>                J9U1             150      SCONN288_H44441003_PIP-SCONN,HA
M_H_DQ<1>                U2D1             AT79     SKX_EXT_B_BGA1-IC,TBD
M_H_DQ<2>                J1G2             157      SCONN288_H44441004_PIP-SCONN,HA
M_H_DQ<2>                J9U1             12       SCONN288_H44441003_PIP-SCONN,HA
M_H_DQ<2>                U2D1             AN82     SKX_EXT_B_BGA1-IC,TBD
M_H_DQ<3>                J1G2             12       SCONN288_H44441004_PIP-SCONN,HA
M_H_DQ<3>                J9U1             157      SCONN288_H44441003_PIP-SCONN,HA
M_H_DQ<3>                U2D1             AM81     SKX_EXT_B_BGA1-IC,TBD
M_H_DQ<4>                J1G2             148      SCONN288_H44441004_PIP-SCONN,HA
M_H_DQ<4>                J9U1             3        SCONN288_H44441003_PIP-SCONN,HA
M_H_DQ<4>                U2D1             AW80     SKX_EXT_B_BGA1-IC,TBD
M_H_DQ<5>                J1G2             3        SCONN288_H44441004_PIP-SCONN,HA
M_H_DQ<5>                J9U1             148      SCONN288_H44441003_PIP-SCONN,HA
M_H_DQ<5>                U2D1             AV79     SKX_EXT_B_BGA1-IC,TBD
M_H_DQ<6>                J1G2             155      SCONN288_H44441004_PIP-SCONN,HA
M_H_DQ<6>                J9U1             10       SCONN288_H44441003_PIP-SCONN,HA
M_H_DQ<6>                U2D1             AR82     SKX_EXT_B_BGA1-IC,TBD
M_H_DQ<7>                J1G2             10       SCONN288_H44441004_PIP-SCONN,HA
M_H_DQ<7>                J9U1             155      SCONN288_H44441003_PIP-SCONN,HA
M_H_DQ<7>                U2D1             AN80     SKX_EXT_B_BGA1-IC,TBD
M_H_DQ<8>                J1G2             161      SCONN288_H44441004_PIP-SCONN,HA
M_H_DQ<8>                J9U1             16       SCONN288_H44441003_PIP-SCONN,HA
M_H_DQ<8>                U2D1             AH81     SKX_EXT_B_BGA1-IC,TBD
M_H_DQ<9>                J1G2             16       SCONN288_H44441004_PIP-SCONN,HA
M_H_DQ<9>                J9U1             161      SCONN288_H44441003_PIP-SCONN,HA
M_H_DQ<9>                U2D1             AF79     SKX_EXT_B_BGA1-IC,TBD
M_H_DQ<10>               J1G2             168      SCONN288_H44441004_PIP-SCONN,HA
M_H_DQ<10>               J9U1             23       SCONN288_H44441003_PIP-SCONN,HA
M_H_DQ<10>               U2D1             AC82     SKX_EXT_B_BGA1-IC,TBD
M_H_DQ<11>               J1G2             23       SCONN288_H44441004_PIP-SCONN,HA
M_H_DQ<11>               J9U1             168      SCONN288_H44441003_PIP-SCONN,HA
M_H_DQ<11>               U2D1             AB81     SKX_EXT_B_BGA1-IC,TBD
M_H_DQ<12>               J1G2             159      SCONN288_H44441004_PIP-SCONN,HA
M_H_DQ<12>               J9U1             14       SCONN288_H44441003_PIP-SCONN,HA
M_H_DQ<12>               U2D1             AJ80     SKX_EXT_B_BGA1-IC,TBD
M_H_DQ<13>               J1G2             14       SCONN288_H44441004_PIP-SCONN,HA
M_H_DQ<13>               J9U1             159      SCONN288_H44441003_PIP-SCONN,HA
M_H_DQ<13>               U2D1             AH79     SKX_EXT_B_BGA1-IC,TBD
M_H_DQ<14>               J1G2             166      SCONN288_H44441004_PIP-SCONN,HA
M_H_DQ<14>               J9U1             21       SCONN288_H44441003_PIP-SCONN,HA
M_H_DQ<14>               U2D1             AE82     SKX_EXT_B_BGA1-IC,TBD
M_H_DQ<15>               J1G2             21       SCONN288_H44441004_PIP-SCONN,HA
M_H_DQ<15>               J9U1             166      SCONN288_H44441003_PIP-SCONN,HA
M_H_DQ<15>               U2D1             AC80     SKX_EXT_B_BGA1-IC,TBD
M_H_DQ<16>               J1G2             172      SCONN288_H44441004_PIP-SCONN,HA
M_H_DQ<16>               J9U1             27       SCONN288_H44441003_PIP-SCONN,HA
M_H_DQ<16>               U2D1             E80      SKX_EXT_B_BGA1-IC,TBD
M_H_DQ<17>               J1G2             27       SCONN288_H44441004_PIP-SCONN,HA
M_H_DQ<17>               J9U1             172      SCONN288_H44441003_PIP-SCONN,HA
M_H_DQ<17>               U2D1             J80      SKX_EXT_B_BGA1-IC,TBD
M_H_DQ<18>               J1G2             179      SCONN288_H44441004_PIP-SCONN,HA
M_H_DQ<18>               J9U1             34       SCONN288_H44441003_PIP-SCONN,HA
M_H_DQ<18>               U2D1             F77      SKX_EXT_B_BGA1-IC,TBD
M_H_DQ<19>               J1G2             34       SCONN288_H44441004_PIP-SCONN,HA
M_H_DQ<19>               J9U1             179      SCONN288_H44441003_PIP-SCONN,HA
M_H_DQ<19>               U2D1             H77      SKX_EXT_B_BGA1-IC,TBD
M_H_DQ<20>               J1G2             170      SCONN288_H44441004_PIP-SCONN,HA
M_H_DQ<20>               J9U1             25       SCONN288_H44441003_PIP-SCONN,HA
M_H_DQ<20>               U2D1             F81      SKX_EXT_B_BGA1-IC,TBD
M_H_DQ<21>               J1G2             25       SCONN288_H44441004_PIP-SCONN,HA
M_H_DQ<21>               J9U1             170      SCONN288_H44441003_PIP-SCONN,HA
M_H_DQ<21>               U2D1             H81      SKX_EXT_B_BGA1-IC,TBD
M_H_DQ<22>               J1G2             177      SCONN288_H44441004_PIP-SCONN,HA
M_H_DQ<22>               J9U1             32       SCONN288_H44441003_PIP-SCONN,HA
M_H_DQ<22>               U2D1             E78      SKX_EXT_B_BGA1-IC,TBD
M_H_DQ<23>               J1G2             32       SCONN288_H44441004_PIP-SCONN,HA
M_H_DQ<23>               J9U1             177      SCONN288_H44441003_PIP-SCONN,HA
M_H_DQ<23>               U2D1             J78      SKX_EXT_B_BGA1-IC,TBD
M_H_DQ<24>               J1G2             183      SCONN288_H44441004_PIP-SCONN,HA
M_H_DQ<24>               J9U1             38       SCONN288_H44441003_PIP-SCONN,HA
M_H_DQ<24>               U2D1             D75      SKX_EXT_B_BGA1-IC,TBD
M_H_DQ<25>               J1G2             38       SCONN288_H44441004_PIP-SCONN,HA
M_H_DQ<25>               J9U1             183      SCONN288_H44441003_PIP-SCONN,HA
M_H_DQ<25>               U2D1             C74      SKX_EXT_B_BGA1-IC,TBD
M_H_DQ<26>               J1G2             190      SCONN288_H44441004_PIP-SCONN,HA
M_H_DQ<26>               J9U1             45       SCONN288_H44441003_PIP-SCONN,HA
M_H_DQ<26>               U2D1             D71      SKX_EXT_B_BGA1-IC,TBD
M_H_DQ<27>               J1G2             45       SCONN288_H44441004_PIP-SCONN,HA
M_H_DQ<27>               J9U1             190      SCONN288_H44441003_PIP-SCONN,HA
M_H_DQ<27>               U2D1             F71      SKX_EXT_B_BGA1-IC,TBD
M_H_DQ<28>               J1G2             181      SCONN288_H44441004_PIP-SCONN,HA
M_H_DQ<28>               J9U1             36       SCONN288_H44441003_PIP-SCONN,HA
M_H_DQ<28>               U2D1             F75      SKX_EXT_B_BGA1-IC,TBD
M_H_DQ<29>               J1G2             36       SCONN288_H44441004_PIP-SCONN,HA
M_H_DQ<29>               J9U1             181      SCONN288_H44441003_PIP-SCONN,HA
M_H_DQ<29>               U2D1             G74      SKX_EXT_B_BGA1-IC,TBD
M_H_DQ<30>               J1G2             188      SCONN288_H44441004_PIP-SCONN,HA
M_H_DQ<30>               J9U1             43       SCONN288_H44441003_PIP-SCONN,HA
M_H_DQ<30>               U2D1             C72      SKX_EXT_B_BGA1-IC,TBD
M_H_DQ<31>               J1G2             43       SCONN288_H44441004_PIP-SCONN,HA
M_H_DQ<31>               J9U1             188      SCONN288_H44441003_PIP-SCONN,HA
M_H_DQ<31>               U2D1             G72      SKX_EXT_B_BGA1-IC,TBD
M_H_DQ<32>               J1G2             242      SCONN288_H44441004_PIP-SCONN,HA
M_H_DQ<32>               J9U1             97       SCONN288_H44441003_PIP-SCONN,HA
M_H_DQ<32>               U2D1             K43      SKX_EXT_B_BGA1-IC,TBD
M_H_DQ<33>               J1G2             97       SCONN288_H44441004_PIP-SCONN,HA
M_H_DQ<33>               J9U1             242      SCONN288_H44441003_PIP-SCONN,HA
M_H_DQ<33>               U2D1             H43      SKX_EXT_B_BGA1-IC,TBD
M_H_DQ<34>               J1G2             249      SCONN288_H44441004_PIP-SCONN,HA
M_H_DQ<34>               J9U1             104      SCONN288_H44441003_PIP-SCONN,HA
M_H_DQ<34>               U2D1             L40      SKX_EXT_B_BGA1-IC,TBD
M_H_DQ<35>               J1G2             104      SCONN288_H44441004_PIP-SCONN,HA
M_H_DQ<35>               J9U1             249      SCONN288_H44441003_PIP-SCONN,HA
M_H_DQ<35>               U2D1             N40      SKX_EXT_B_BGA1-IC,TBD
M_H_DQ<36>               J1G2             240      SCONN288_H44441004_PIP-SCONN,HA
M_H_DQ<36>               J9U1             95       SCONN288_H44441003_PIP-SCONN,HA
M_H_DQ<36>               U2D1             P43      SKX_EXT_B_BGA1-IC,TBD
M_H_DQ<37>               J1G2             95       SCONN288_H44441004_PIP-SCONN,HA
M_H_DQ<37>               J9U1             240      SCONN288_H44441003_PIP-SCONN,HA
M_H_DQ<37>               U2D1             T43      SKX_EXT_B_BGA1-IC,TBD
M_H_DQ<38>               J1G2             247      SCONN288_H44441004_PIP-SCONN,HA
M_H_DQ<38>               J9U1             102      SCONN288_H44441003_PIP-SCONN,HA
M_H_DQ<38>               U2D1             K41      SKX_EXT_B_BGA1-IC,TBD
M_H_DQ<39>               J1G2             102      SCONN288_H44441004_PIP-SCONN,HA
M_H_DQ<39>               J9U1             247      SCONN288_H44441003_PIP-SCONN,HA
M_H_DQ<39>               U2D1             P41      SKX_EXT_B_BGA1-IC,TBD
M_H_DQ<40>               J1G2             253      SCONN288_H44441004_PIP-SCONN,HA
M_H_DQ<40>               J9U1             108      SCONN288_H44441003_PIP-SCONN,HA
M_H_DQ<40>               U2D1             C36      SKX_EXT_B_BGA1-IC,TBD
M_H_DQ<41>               J1G2             108      SCONN288_H44441004_PIP-SCONN,HA
M_H_DQ<41>               J9U1             253      SCONN288_H44441003_PIP-SCONN,HA
M_H_DQ<41>               U2D1             B35      SKX_EXT_B_BGA1-IC,TBD
M_H_DQ<42>               J1G2             260      SCONN288_H44441004_PIP-SCONN,HA
M_H_DQ<42>               J9U1             115      SCONN288_H44441003_PIP-SCONN,HA
M_H_DQ<42>               U2D1             C32      SKX_EXT_B_BGA1-IC,TBD
M_H_DQ<43>               J1G2             115      SCONN288_H44441004_PIP-SCONN,HA
M_H_DQ<43>               J9U1             260      SCONN288_H44441003_PIP-SCONN,HA
M_H_DQ<43>               U2D1             E32      SKX_EXT_B_BGA1-IC,TBD
M_H_DQ<44>               J1G2             251      SCONN288_H44441004_PIP-SCONN,HA
M_H_DQ<44>               J9U1             106      SCONN288_H44441003_PIP-SCONN,HA
M_H_DQ<44>               U2D1             E36      SKX_EXT_B_BGA1-IC,TBD
M_H_DQ<45>               J1G2             106      SCONN288_H44441004_PIP-SCONN,HA
M_H_DQ<45>               J9U1             251      SCONN288_H44441003_PIP-SCONN,HA
M_H_DQ<45>               U2D1             F35      SKX_EXT_B_BGA1-IC,TBD
M_H_DQ<46>               J1G2             258      SCONN288_H44441004_PIP-SCONN,HA
M_H_DQ<46>               J9U1             113      SCONN288_H44441003_PIP-SCONN,HA
M_H_DQ<46>               U2D1             B33      SKX_EXT_B_BGA1-IC,TBD
M_H_DQ<47>               J1G2             113      SCONN288_H44441004_PIP-SCONN,HA
M_H_DQ<47>               J9U1             258      SCONN288_H44441003_PIP-SCONN,HA
M_H_DQ<47>               U2D1             F33      SKX_EXT_B_BGA1-IC,TBD
M_H_DQ<48>               J1G2             264      SCONN288_H44441004_PIP-SCONN,HA
M_H_DQ<48>               J9U1             119      SCONN288_H44441003_PIP-SCONN,HA
M_H_DQ<48>               U2D1             C30      SKX_EXT_B_BGA1-IC,TBD
M_H_DQ<49>               J1G2             119      SCONN288_H44441004_PIP-SCONN,HA
M_H_DQ<49>               J9U1             264      SCONN288_H44441003_PIP-SCONN,HA
M_H_DQ<49>               U2D1             B29      SKX_EXT_B_BGA1-IC,TBD
M_H_DQ<50>               J1G2             271      SCONN288_H44441004_PIP-SCONN,HA
M_H_DQ<50>               J9U1             126      SCONN288_H44441003_PIP-SCONN,HA
M_H_DQ<50>               U2D1             C26      SKX_EXT_B_BGA1-IC,TBD
M_H_DQ<51>               J1G2             126      SCONN288_H44441004_PIP-SCONN,HA
M_H_DQ<51>               J9U1             271      SCONN288_H44441003_PIP-SCONN,HA
M_H_DQ<51>               U2D1             E26      SKX_EXT_B_BGA1-IC,TBD
M_H_DQ<52>               J1G2             262      SCONN288_H44441004_PIP-SCONN,HA
M_H_DQ<52>               J9U1             117      SCONN288_H44441003_PIP-SCONN,HA
M_H_DQ<52>               U2D1             E30      SKX_EXT_B_BGA1-IC,TBD
M_H_DQ<53>               J1G2             117      SCONN288_H44441004_PIP-SCONN,HA
M_H_DQ<53>               J9U1             262      SCONN288_H44441003_PIP-SCONN,HA
M_H_DQ<53>               U2D1             F29      SKX_EXT_B_BGA1-IC,TBD
M_H_DQ<54>               J1G2             269      SCONN288_H44441004_PIP-SCONN,HA
M_H_DQ<54>               J9U1             124      SCONN288_H44441003_PIP-SCONN,HA
M_H_DQ<54>               U2D1             B27      SKX_EXT_B_BGA1-IC,TBD
M_H_DQ<55>               J1G2             124      SCONN288_H44441004_PIP-SCONN,HA
M_H_DQ<55>               J9U1             269      SCONN288_H44441003_PIP-SCONN,HA
M_H_DQ<55>               U2D1             F27      SKX_EXT_B_BGA1-IC,TBD
M_H_DQ<56>               J1G2             275      SCONN288_H44441004_PIP-SCONN,HA
M_H_DQ<56>               J9U1             130      SCONN288_H44441003_PIP-SCONN,HA
M_H_DQ<56>               U2D1             U28      SKX_EXT_B_BGA1-IC,TBD
M_H_DQ<57>               J1G2             130      SCONN288_H44441004_PIP-SCONN,HA
M_H_DQ<57>               J9U1             275      SCONN288_H44441003_PIP-SCONN,HA
M_H_DQ<57>               U2D1             AA28     SKX_EXT_B_BGA1-IC,TBD
M_H_DQ<58>               J1G2             282      SCONN288_H44441004_PIP-SCONN,HA
M_H_DQ<58>               J9U1             137      SCONN288_H44441003_PIP-SCONN,HA
M_H_DQ<58>               U2D1             V25      SKX_EXT_B_BGA1-IC,TBD
M_H_DQ<59>               J1G2             137      SCONN288_H44441004_PIP-SCONN,HA
M_H_DQ<59>               J9U1             282      SCONN288_H44441003_PIP-SCONN,HA
M_H_DQ<59>               U2D1             Y25      SKX_EXT_B_BGA1-IC,TBD
M_H_DQ<60>               J1G2             273      SCONN288_H44441004_PIP-SCONN,HA
M_H_DQ<60>               J9U1             128      SCONN288_H44441003_PIP-SCONN,HA
M_H_DQ<60>               U2D1             V29      SKX_EXT_B_BGA1-IC,TBD
M_H_DQ<61>               J1G2             128      SCONN288_H44441004_PIP-SCONN,HA
M_H_DQ<61>               J9U1             273      SCONN288_H44441003_PIP-SCONN,HA
M_H_DQ<61>               U2D1             Y29      SKX_EXT_B_BGA1-IC,TBD
M_H_DQ<62>               J1G2             280      SCONN288_H44441004_PIP-SCONN,HA
M_H_DQ<62>               J9U1             135      SCONN288_H44441003_PIP-SCONN,HA
M_H_DQ<62>               U2D1             U26      SKX_EXT_B_BGA1-IC,TBD
M_H_DQ<63>               J1G2             135      SCONN288_H44441004_PIP-SCONN,HA
M_H_DQ<63>               J9U1             280      SCONN288_H44441003_PIP-SCONN,HA
M_H_DQ<63>               U2D1             AA26     SKX_EXT_B_BGA1-IC,TBD
M_H_DQS_DN<0>            J1G2             152      SCONN288_H44441004_PIP-SCONN,HA
M_H_DQS_DN<0>            J9U1             152      SCONN288_H44441003_PIP-SCONN,HA
M_H_DQS_DN<0>            U2D1             AP79     SKX_EXT_B_BGA1-IC,TBD
M_H_DQS_DN<1>            J1G2             163      SCONN288_H44441004_PIP-SCONN,HA
M_H_DQS_DN<1>            J9U1             163      SCONN288_H44441003_PIP-SCONN,HA
M_H_DQS_DN<1>            U2D1             AD79     SKX_EXT_B_BGA1-IC,TBD
M_H_DQS_DN<2>            J1G2             174      SCONN288_H44441004_PIP-SCONN,HA
M_H_DQS_DN<2>            J9U1             174      SCONN288_H44441003_PIP-SCONN,HA
M_H_DQS_DN<2>            U2D1             K79      SKX_EXT_B_BGA1-IC,TBD
M_H_DQS_DN<3>            J1G2             185      SCONN288_H44441004_PIP-SCONN,HA
M_H_DQS_DN<3>            J9U1             185      SCONN288_H44441003_PIP-SCONN,HA
M_H_DQS_DN<3>            U2D1             H73      SKX_EXT_B_BGA1-IC,TBD
M_H_DQS_DN<4>            J1G2             244      SCONN288_H44441004_PIP-SCONN,HA
M_H_DQS_DN<4>            J9U1             244      SCONN288_H44441003_PIP-SCONN,HA
M_H_DQS_DN<4>            U2D1             N42      SKX_EXT_B_BGA1-IC,TBD
M_H_DQS_DN<5>            J1G2             255      SCONN288_H44441004_PIP-SCONN,HA
M_H_DQS_DN<5>            J9U1             255      SCONN288_H44441003_PIP-SCONN,HA
M_H_DQS_DN<5>            U2D1             G34      SKX_EXT_B_BGA1-IC,TBD
M_H_DQS_DN<6>            J1G2             266      SCONN288_H44441004_PIP-SCONN,HA
M_H_DQS_DN<6>            J9U1             266      SCONN288_H44441003_PIP-SCONN,HA
M_H_DQS_DN<6>            U2D1             G28      SKX_EXT_B_BGA1-IC,TBD
M_H_DQS_DN<7>            J1G2             277      SCONN288_H44441004_PIP-SCONN,HA
M_H_DQS_DN<7>            J9U1             277      SCONN288_H44441003_PIP-SCONN,HA
M_H_DQS_DN<7>            U2D1             AB27     SKX_EXT_B_BGA1-IC,TBD
M_H_DQS_DN<8>            J1G2             196      SCONN288_H44441004_PIP-SCONN,HA
M_H_DQS_DN<8>            J9U1             196      SCONN288_H44441003_PIP-SCONN,HA
M_H_DQS_DN<8>            U2D1             N68      SKX_EXT_B_BGA1-IC,TBD
M_H_DQS_DN<9>            J1G2             8        SCONN288_H44441004_PIP-SCONN,HA
M_H_DQS_DN<9>            J9U1             8        SCONN288_H44441003_PIP-SCONN,HA
M_H_DQS_DN<9>            U2D1             AU82     SKX_EXT_B_BGA1-IC,TBD
M_H_DQS_DN<10>           J1G2             19       SCONN288_H44441004_PIP-SCONN,HA
M_H_DQS_DN<10>           J9U1             19       SCONN288_H44441003_PIP-SCONN,HA
M_H_DQS_DN<10>           U2D1             AG82     SKX_EXT_B_BGA1-IC,TBD
M_H_DQS_DN<11>           J1G2             30       SCONN288_H44441004_PIP-SCONN,HA
M_H_DQS_DN<11>           J9U1             30       SCONN288_H44441003_PIP-SCONN,HA
M_H_DQS_DN<11>           U2D1             D79      SKX_EXT_B_BGA1-IC,TBD
M_H_DQS_DN<12>           J1G2             41       SCONN288_H44441004_PIP-SCONN,HA
M_H_DQS_DN<12>           J9U1             41       SCONN288_H44441003_PIP-SCONN,HA
M_H_DQS_DN<12>           U2D1             B73      SKX_EXT_B_BGA1-IC,TBD
M_H_DQS_DN<13>           J1G2             100      SCONN288_H44441004_PIP-SCONN,HA
M_H_DQS_DN<13>           J9U1             100      SCONN288_H44441003_PIP-SCONN,HA
M_H_DQS_DN<13>           U2D1             J42      SKX_EXT_B_BGA1-IC,TBD
M_H_DQS_DN<14>           J1G2             111      SCONN288_H44441004_PIP-SCONN,HA
M_H_DQS_DN<14>           J9U1             111      SCONN288_H44441003_PIP-SCONN,HA
M_H_DQS_DN<14>           U2D1             A34      SKX_EXT_B_BGA1-IC,TBD
M_H_DQS_DN<15>           J1G2             122      SCONN288_H44441004_PIP-SCONN,HA
M_H_DQS_DN<15>           J9U1             122      SCONN288_H44441003_PIP-SCONN,HA
M_H_DQS_DN<15>           U2D1             A28      SKX_EXT_B_BGA1-IC,TBD
M_H_DQS_DN<16>           J1G2             133      SCONN288_H44441004_PIP-SCONN,HA
M_H_DQS_DN<16>           J9U1             133      SCONN288_H44441003_PIP-SCONN,HA
M_H_DQS_DN<16>           U2D1             T27      SKX_EXT_B_BGA1-IC,TBD
M_H_DQS_DN<17>           J1G2             52       SCONN288_H44441004_PIP-SCONN,HA
M_H_DQS_DN<17>           J9U1             52       SCONN288_H44441003_PIP-SCONN,HA
M_H_DQS_DN<17>           U2D1             G68      SKX_EXT_B_BGA1-IC,TBD
M_H_DQS_DP<0>            J1G2             153      SCONN288_H44441004_PIP-SCONN,HA
M_H_DQS_DP<0>            J9U1             153      SCONN288_H44441003_PIP-SCONN,HA
M_H_DQS_DP<0>            U2D1             AR80     SKX_EXT_B_BGA1-IC,TBD
M_H_DQS_DP<1>            J1G2             164      SCONN288_H44441004_PIP-SCONN,HA
M_H_DQS_DP<1>            J9U1             164      SCONN288_H44441003_PIP-SCONN,HA
M_H_DQS_DP<1>            U2D1             AE80     SKX_EXT_B_BGA1-IC,TBD
M_H_DQS_DP<2>            J1G2             175      SCONN288_H44441004_PIP-SCONN,HA
M_H_DQS_DP<2>            J9U1             175      SCONN288_H44441003_PIP-SCONN,HA
M_H_DQS_DP<2>            U2D1             H79      SKX_EXT_B_BGA1-IC,TBD
M_H_DQS_DP<3>            J1G2             186      SCONN288_H44441004_PIP-SCONN,HA
M_H_DQS_DP<3>            J9U1             186      SCONN288_H44441003_PIP-SCONN,HA
M_H_DQS_DP<3>            U2D1             F73      SKX_EXT_B_BGA1-IC,TBD
M_H_DQS_DP<4>            J1G2             245      SCONN288_H44441004_PIP-SCONN,HA
M_H_DQS_DP<4>            J9U1             245      SCONN288_H44441003_PIP-SCONN,HA
M_H_DQS_DP<4>            U2D1             R42      SKX_EXT_B_BGA1-IC,TBD
M_H_DQS_DP<5>            J1G2             256      SCONN288_H44441004_PIP-SCONN,HA
M_H_DQS_DP<5>            J9U1             256      SCONN288_H44441003_PIP-SCONN,HA
M_H_DQS_DP<5>            U2D1             E34      SKX_EXT_B_BGA1-IC,TBD
M_H_DQS_DP<6>            J1G2             267      SCONN288_H44441004_PIP-SCONN,HA
M_H_DQS_DP<6>            J9U1             267      SCONN288_H44441003_PIP-SCONN,HA
M_H_DQS_DP<6>            U2D1             E28      SKX_EXT_B_BGA1-IC,TBD
M_H_DQS_DP<7>            J1G2             278      SCONN288_H44441004_PIP-SCONN,HA
M_H_DQS_DP<7>            J9U1             278      SCONN288_H44441003_PIP-SCONN,HA
M_H_DQS_DP<7>            U2D1             Y27      SKX_EXT_B_BGA1-IC,TBD
M_H_DQS_DP<8>            J1G2             197      SCONN288_H44441004_PIP-SCONN,HA
M_H_DQS_DP<8>            J9U1             197      SCONN288_H44441003_PIP-SCONN,HA
M_H_DQS_DP<8>            U2D1             L68      SKX_EXT_B_BGA1-IC,TBD
M_H_DQS_DP<9>            J1G2             7        SCONN288_H44441004_PIP-SCONN,HA
M_H_DQS_DP<9>            J9U1             7        SCONN288_H44441003_PIP-SCONN,HA
M_H_DQS_DP<9>            U2D1             AT81     SKX_EXT_B_BGA1-IC,TBD
M_H_DQS_DP<10>           J1G2             18       SCONN288_H44441004_PIP-SCONN,HA
M_H_DQS_DP<10>           J9U1             18       SCONN288_H44441003_PIP-SCONN,HA
M_H_DQS_DP<10>           U2D1             AF81     SKX_EXT_B_BGA1-IC,TBD
M_H_DQS_DP<11>           J1G2             29       SCONN288_H44441004_PIP-SCONN,HA
M_H_DQS_DP<11>           J9U1             29       SCONN288_H44441003_PIP-SCONN,HA
M_H_DQS_DP<11>           U2D1             F79      SKX_EXT_B_BGA1-IC,TBD
M_H_DQS_DP<12>           J1G2             40       SCONN288_H44441004_PIP-SCONN,HA
M_H_DQS_DP<12>           J9U1             40       SCONN288_H44441003_PIP-SCONN,HA
M_H_DQS_DP<12>           U2D1             D73      SKX_EXT_B_BGA1-IC,TBD
M_H_DQS_DP<13>           J1G2             99       SCONN288_H44441004_PIP-SCONN,HA
M_H_DQS_DP<13>           J9U1             99       SCONN288_H44441003_PIP-SCONN,HA
M_H_DQS_DP<13>           U2D1             L42      SKX_EXT_B_BGA1-IC,TBD
M_H_DQS_DP<14>           J1G2             110      SCONN288_H44441004_PIP-SCONN,HA
M_H_DQS_DP<14>           J9U1             110      SCONN288_H44441003_PIP-SCONN,HA
M_H_DQS_DP<14>           U2D1             C34      SKX_EXT_B_BGA1-IC,TBD
M_H_DQS_DP<15>           J1G2             121      SCONN288_H44441004_PIP-SCONN,HA
M_H_DQS_DP<15>           J9U1             121      SCONN288_H44441003_PIP-SCONN,HA
M_H_DQS_DP<15>           U2D1             C28      SKX_EXT_B_BGA1-IC,TBD
M_H_DQS_DP<16>           J1G2             132      SCONN288_H44441004_PIP-SCONN,HA
M_H_DQS_DP<16>           J9U1             132      SCONN288_H44441003_PIP-SCONN,HA
M_H_DQS_DP<16>           U2D1             V27      SKX_EXT_B_BGA1-IC,TBD
M_H_DQS_DP<17>           J1G2             51       SCONN288_H44441004_PIP-SCONN,HA
M_H_DQS_DP<17>           J9U1             51       SCONN288_H44441003_PIP-SCONN,HA
M_H_DQS_DP<17>           U2D1             J68      SKX_EXT_B_BGA1-IC,TBD
M_H_ECC<0>               J1G2             194      SCONN288_H44441004_PIP-SCONN,HA
M_H_ECC<0>               J9U1             49       SCONN288_H44441003_PIP-SCONN,HA
M_H_ECC<0>               U2D1             J70      SKX_EXT_B_BGA1-IC,TBD
M_H_ECC<1>               J1G2             49       SCONN288_H44441004_PIP-SCONN,HA
M_H_ECC<1>               J9U1             194      SCONN288_H44441003_PIP-SCONN,HA
M_H_ECC<1>               U2D1             H69      SKX_EXT_B_BGA1-IC,TBD
M_H_ECC<2>               J1G2             201      SCONN288_H44441004_PIP-SCONN,HA
M_H_ECC<2>               J9U1             56       SCONN288_H44441003_PIP-SCONN,HA
M_H_ECC<2>               U2D1             J66      SKX_EXT_B_BGA1-IC,TBD
M_H_ECC<3>               J1G2             56       SCONN288_H44441004_PIP-SCONN,HA
M_H_ECC<3>               J9U1             201      SCONN288_H44441003_PIP-SCONN,HA
M_H_ECC<3>               U2D1             L66      SKX_EXT_B_BGA1-IC,TBD
M_H_ECC<4>               J1G2             192      SCONN288_H44441004_PIP-SCONN,HA
M_H_ECC<4>               J9U1             47       SCONN288_H44441003_PIP-SCONN,HA
M_H_ECC<4>               U2D1             L70      SKX_EXT_B_BGA1-IC,TBD
M_H_ECC<5>               J1G2             47       SCONN288_H44441004_PIP-SCONN,HA
M_H_ECC<5>               J9U1             192      SCONN288_H44441003_PIP-SCONN,HA
M_H_ECC<5>               U2D1             M69      SKX_EXT_B_BGA1-IC,TBD
M_H_ECC<6>               J1G2             199      SCONN288_H44441004_PIP-SCONN,HA
M_H_ECC<6>               J9U1             54       SCONN288_H44441003_PIP-SCONN,HA
M_H_ECC<6>               U2D1             H67      SKX_EXT_B_BGA1-IC,TBD
M_H_ECC<7>               J1G2             54       SCONN288_H44441004_PIP-SCONN,HA
M_H_ECC<7>               J9U1             199      SCONN288_H44441003_PIP-SCONN,HA
M_H_ECC<7>               U2D1             M67      SKX_EXT_B_BGA1-IC,TBD
M_H_MA<0>                J1G2             79       SCONN288_H44441004_PIP-SCONN,HA
M_H_MA<0>                J9U1             79       SCONN288_H44441003_PIP-SCONN,HA
M_H_MA<0>                U2D1             J52      SKX_EXT_B_BGA1-IC,TBD
M_H_MA<1>                J1G2             72       SCONN288_H44441004_PIP-SCONN,HA
M_H_MA<1>                J9U1             72       SCONN288_H44441003_PIP-SCONN,HA
M_H_MA<1>                U2D1             J58      SKX_EXT_B_BGA1-IC,TBD
M_H_MA<2>                J1G2             216      SCONN288_H44441004_PIP-SCONN,HA
M_H_MA<2>                J9U1             216      SCONN288_H44441003_PIP-SCONN,HA
M_H_MA<2>                U2D1             K57      SKX_EXT_B_BGA1-IC,TBD
M_H_MA<3>                J1G2             71       SCONN288_H44441004_PIP-SCONN,HA
M_H_MA<3>                J9U1             71       SCONN288_H44441003_PIP-SCONN,HA
M_H_MA<3>                U2D1             N58      SKX_EXT_B_BGA1-IC,TBD
M_H_MA<4>                J1G2             214      SCONN288_H44441004_PIP-SCONN,HA
M_H_MA<4>                J9U1             214      SCONN288_H44441003_PIP-SCONN,HA
M_H_MA<4>                U2D1             M59      SKX_EXT_B_BGA1-IC,TBD
M_H_MA<5>                J1G2             213      SCONN288_H44441004_PIP-SCONN,HA
M_H_MA<5>                J9U1             213      SCONN288_H44441003_PIP-SCONN,HA
M_H_MA<5>                U2D1             R58      SKX_EXT_B_BGA1-IC,TBD
M_H_MA<6>                J1G2             69       SCONN288_H44441004_PIP-SCONN,HA
M_H_MA<6>                J9U1             69       SCONN288_H44441003_PIP-SCONN,HA
M_H_MA<6>                U2D1             T59      SKX_EXT_B_BGA1-IC,TBD
M_H_MA<7>                J1G2             211      SCONN288_H44441004_PIP-SCONN,HA
M_H_MA<7>                J9U1             211      SCONN288_H44441003_PIP-SCONN,HA
M_H_MA<7>                U2D1             V61      SKX_EXT_B_BGA1-IC,TBD
M_H_MA<8>                J1G2             68       SCONN288_H44441004_PIP-SCONN,HA
M_H_MA<8>                J9U1             68       SCONN288_H44441003_PIP-SCONN,HA
M_H_MA<8>                U2D1             W60      SKX_EXT_B_BGA1-IC,TBD
M_H_MA<9>                J1G2             66       SCONN288_H44441004_PIP-SCONN,HA
M_H_MA<9>                J9U1             66       SCONN288_H44441003_PIP-SCONN,HA
M_H_MA<9>                U2D1             K59      SKX_EXT_B_BGA1-IC,TBD
M_H_MA<10>               J1G2             225      SCONN288_H44441004_PIP-SCONN,HA
M_H_MA<10>               J9U1             225      SCONN288_H44441003_PIP-SCONN,HA
M_H_MA<10>               U2D1             M55      SKX_EXT_B_BGA1-IC,TBD
M_H_MA<11>               J1G2             210      SCONN288_H44441004_PIP-SCONN,HA
M_H_MA<11>               J9U1             210      SCONN288_H44441003_PIP-SCONN,HA
M_H_MA<11>               U2D1             R60      SKX_EXT_B_BGA1-IC,TBD
M_H_MA<12>               J1G2             65       SCONN288_H44441004_PIP-SCONN,HA
M_H_MA<12>               J9U1             65       SCONN288_H44441003_PIP-SCONN,HA
M_H_MA<12>               U2D1             T61      SKX_EXT_B_BGA1-IC,TBD
M_H_MA<13>               J1G2             232      SCONN288_H44441004_PIP-SCONN,HA
M_H_MA<13>               J9U1             232      SCONN288_H44441003_PIP-SCONN,HA
M_H_MA<13>               U2D1             M51      SKX_EXT_B_BGA1-IC,TBD
M_H_MA<14>               J1G2             228      SCONN288_H44441004_PIP-SCONN,HA
M_H_MA<14>               J9U1             228      SCONN288_H44441003_PIP-SCONN,HA
M_H_MA<14>               U2D1             T51      SKX_EXT_B_BGA1-IC,TBD
M_H_MA<15>               J1G2             86       SCONN288_H44441004_PIP-SCONN,HA
M_H_MA<15>               J9U1             86       SCONN288_H44441003_PIP-SCONN,HA
M_H_MA<15>               U2D1             N52      SKX_EXT_B_BGA1-IC,TBD
M_H_MA<16>               J1G2             82       SCONN288_H44441004_PIP-SCONN,HA
M_H_MA<16>               J9U1             82       SCONN288_H44441003_PIP-SCONN,HA
M_H_MA<16>               U2D1             R52      SKX_EXT_B_BGA1-IC,TBD
M_H_MA<17>               J1G2             234      SCONN288_H44441004_PIP-SCONN,HA
M_H_MA<17>               J9U1             234      SCONN288_H44441003_PIP-SCONN,HA
M_H_MA<17>               U2D1             N48      SKX_EXT_B_BGA1-IC,TBD
M_H_ODT<0>               J1G2             87       SCONN288_H44441004_PIP-SCONN,HA
M_H_ODT<0>               U2D1             N50      SKX_EXT_B_BGA1-IC,TBD
M_H_ODT<1>               J1G2             91       SCONN288_H44441004_PIP-SCONN,HA
M_H_ODT<1>               U2D1             R48      SKX_EXT_B_BGA1-IC,TBD
M_H_ODT<2>               J9U1             87       SCONN288_H44441003_PIP-SCONN,HA
M_H_ODT<2>               U2D1             M49      SKX_EXT_B_BGA1-IC,TBD
M_H_ODT<3>               J9U1             91       SCONN288_H44441003_PIP-SCONN,HA
M_H_ODT<3>               U2D1             T47      SKX_EXT_B_BGA1-IC,TBD
M_H_PAR                  J1G2             222      SCONN288_H44441004_PIP-SCONN,HA
M_H_PAR                  J9U1             222      SCONN288_H44441003_PIP-SCONN,HA
M_H_PAR                  U2D1             K53      SKX_EXT_B_BGA1-IC,TBD
M_H_VREF                 C1G10            1        CAP_A_0402V-0.01UF,25V,10%,X7RA
M_H_VREF                 C9U7             1        CAP_A_0402V-0.01UF,25V,10%,X7RA
M_H_VREF                 J1G2             146      SCONN288_H44441004_PIP-SCONN,HA
M_H_VREF                 J9U1             146      SCONN288_H44441003_PIP-SCONN,HA
M_H_VREF                 R1G1             2        RES_0402-2,1.0%,1/16W,CHIP,G21A
M_H_VREF                 R1G2             2        RES_0402-1.00K,1%,1/16W,CHIP,GA
M_H_VREF                 R1G3             1        RES_0402-1.00K,1%,1/16W,CHIP,GA
M_J_ACT_N                J1G3             62       SCONN288_H44441004_PIP-SCONN,HA
M_J_ACT_N                J9U2             62       SCONN288_H44441003_PIP-SCONN,HA
M_J_ACT_N                U2D1             AB61     SKX_EXT_B_BGA1-IC,TBD
M_J_ALERT_N              J1G3             208      SCONN288_H44441004_PIP-SCONN,HA
M_J_ALERT_N              J9U2             208      SCONN288_H44441003_PIP-SCONN,HA
M_J_ALERT_N              U2D1             AD61     SKX_EXT_B_BGA1-IC,TBD
M_J_BA<0>                J1G3             81       SCONN288_H44441004_PIP-SCONN,HA
M_J_BA<0>                J9U2             81       SCONN288_H44441003_PIP-SCONN,HA
M_J_BA<0>                U2D1             W52      SKX_EXT_B_BGA1-IC,TBD
M_J_BA<1>                J1G3             224      SCONN288_H44441004_PIP-SCONN,HA
M_J_BA<1>                J9U2             224      SCONN288_H44441003_PIP-SCONN,HA
M_J_BA<1>                U2D1             AE56     SKX_EXT_B_BGA1-IC,TBD
M_J_BG<0>                J1G3             63       SCONN288_H44441004_PIP-SCONN,HA
M_J_BG<0>                J9U2             63       SCONN288_H44441003_PIP-SCONN,HA
M_J_BG<0>                U2D1             AA60     SKX_EXT_B_BGA1-IC,TBD
M_J_BG<1>                J1G3             207      SCONN288_H44441004_PIP-SCONN,HA
M_J_BG<1>                J9U2             207      SCONN288_H44441003_PIP-SCONN,HA
M_J_BG<1>                U2D1             AE62     SKX_EXT_B_BGA1-IC,TBD
M_J_C<2>                 J1G3             235      SCONN288_H44441004_PIP-SCONN,HA
M_J_C<2>                 J9U2             235      SCONN288_H44441003_PIP-SCONN,HA
M_J_C<2>                 U2D1             AB45     SKX_EXT_B_BGA1-IC,TBD
M_J_CKE<0>               J1G3             60       SCONN288_H44441004_PIP-SCONN,HA
M_J_CKE<0>               U2D1             AA62     SKX_EXT_B_BGA1-IC,TBD
M_J_CKE<1>               J1G3             203      SCONN288_H44441004_PIP-SCONN,HA
M_J_CKE<1>               U2D1             AD63     SKX_EXT_B_BGA1-IC,TBD
M_J_CKE<2>               J9U2             60       SCONN288_H44441003_PIP-SCONN,HA
M_J_CKE<2>               U2D1             V63      SKX_EXT_B_BGA1-IC,TBD
M_J_CKE<3>               J9U2             203      SCONN288_H44441003_PIP-SCONN,HA
M_J_CKE<3>               U2D1             AB63     SKX_EXT_B_BGA1-IC,TBD
M_J_CLK_DN<0>            J1G3             75       SCONN288_H44441004_PIP-SCONN,HA
M_J_CLK_DN<0>            U2D1             AA54     SKX_EXT_B_BGA1-IC,TBD
M_J_CLK_DN<1>            J1G3             219      SCONN288_H44441004_PIP-SCONN,HA
M_J_CLK_DN<1>            U2D1             W54      SKX_EXT_B_BGA1-IC,TBD
M_J_CLK_DN<2>            J9U2             75       SCONN288_H44441003_PIP-SCONN,HA
M_J_CLK_DN<2>            U2D1             AA56     SKX_EXT_B_BGA1-IC,TBD
M_J_CLK_DN<3>            J9U2             219      SCONN288_H44441003_PIP-SCONN,HA
M_J_CLK_DN<3>            U2D1             W56      SKX_EXT_B_BGA1-IC,TBD
M_J_CLK_DP<0>            J1G3             74       SCONN288_H44441004_PIP-SCONN,HA
M_J_CLK_DP<0>            U2D1             AB55     SKX_EXT_B_BGA1-IC,TBD
M_J_CLK_DP<1>            J1G3             218      SCONN288_H44441004_PIP-SCONN,HA
M_J_CLK_DP<1>            U2D1             V55      SKX_EXT_B_BGA1-IC,TBD
M_J_CLK_DP<2>            J9U2             74       SCONN288_H44441003_PIP-SCONN,HA
M_J_CLK_DP<2>            U2D1             AB57     SKX_EXT_B_BGA1-IC,TBD
M_J_CLK_DP<3>            J9U2             218      SCONN288_H44441003_PIP-SCONN,HA
M_J_CLK_DP<3>            U2D1             V57      SKX_EXT_B_BGA1-IC,TBD
M_J_CPU_VREF             C1G18            1        CAP_A_0402V-0.01UF,25V,10%,X7RA
M_J_CPU_VREF             R1G14            1        RES_0402-2,1.0%,1/16W,CHIP,G21A
M_J_CPU_VREF             U2D1             AH63     SKX_EXT_B_BGA1-IC,TBD
M_J_CS_N<0>              J1G3             84       SCONN288_H44441004_PIP-SCONN,HA
M_J_CS_N<0>              U2D1             V51      SKX_EXT_B_BGA1-IC,TBD
M_J_CS_N<1>              J1G3             89       SCONN288_H44441004_PIP-SCONN,HA
M_J_CS_N<1>              U2D1             AB49     SKX_EXT_B_BGA1-IC,TBD
M_J_CS_N<2>              J1G3             93       SCONN288_H44441004_PIP-SCONN,HA
M_J_CS_N<2>              U2D1             W46      SKX_EXT_B_BGA1-IC,TBD
M_J_CS_N<3>              J1G3             237      SCONN288_H44441004_PIP-SCONN,HA
M_J_CS_N<3>              U2D1             AA46     SKX_EXT_B_BGA1-IC,TBD
M_J_CS_N<4>              J9U2             84       SCONN288_H44441003_PIP-SCONN,HA
M_J_CS_N<4>              U2D1             AB51     SKX_EXT_B_BGA1-IC,TBD
M_J_CS_N<5>              J9U2             89       SCONN288_H44441003_PIP-SCONN,HA
M_J_CS_N<5>              U2D1             W48      SKX_EXT_B_BGA1-IC,TBD
M_J_CS_N<6>              J9U2             93       SCONN288_H44441003_PIP-SCONN,HA
M_J_CS_N<6>              U2D1             T45      SKX_EXT_B_BGA1-IC,TBD
M_J_CS_N<7>              J9U2             237      SCONN288_H44441003_PIP-SCONN,HA
M_J_CS_N<7>              U2D1             V45      SKX_EXT_B_BGA1-IC,TBD
M_J_DQ<0>                J1G3             150      SCONN288_H44441004_PIP-SCONN,HA
M_J_DQ<0>                J9U2             5        SCONN288_H44441003_PIP-SCONN,HA
M_J_DQ<0>                U2D1             AR76     SKX_EXT_B_BGA1-IC,TBD
M_J_DQ<1>                J1G3             5        SCONN288_H44441004_PIP-SCONN,HA
M_J_DQ<1>                J9U2             150      SCONN288_H44441003_PIP-SCONN,HA
M_J_DQ<1>                U2D1             AN74     SKX_EXT_B_BGA1-IC,TBD
M_J_DQ<2>                J1G3             157      SCONN288_H44441004_PIP-SCONN,HA
M_J_DQ<2>                J9U2             12       SCONN288_H44441003_PIP-SCONN,HA
M_J_DQ<2>                U2D1             AK77     SKX_EXT_B_BGA1-IC,TBD
M_J_DQ<3>                J1G3             12       SCONN288_H44441004_PIP-SCONN,HA
M_J_DQ<3>                J9U2             157      SCONN288_H44441003_PIP-SCONN,HA
M_J_DQ<3>                U2D1             AJ76     SKX_EXT_B_BGA1-IC,TBD
M_J_DQ<4>                J1G3             148      SCONN288_H44441004_PIP-SCONN,HA
M_J_DQ<4>                J9U2             3        SCONN288_H44441003_PIP-SCONN,HA
M_J_DQ<4>                U2D1             AT75     SKX_EXT_B_BGA1-IC,TBD
M_J_DQ<5>                J1G3             3        SCONN288_H44441004_PIP-SCONN,HA
M_J_DQ<5>                J9U2             148      SCONN288_H44441003_PIP-SCONN,HA
M_J_DQ<5>                U2D1             AR74     SKX_EXT_B_BGA1-IC,TBD
M_J_DQ<6>                J1G3             155      SCONN288_H44441004_PIP-SCONN,HA
M_J_DQ<6>                J9U2             10       SCONN288_H44441003_PIP-SCONN,HA
M_J_DQ<6>                U2D1             AM77     SKX_EXT_B_BGA1-IC,TBD
M_J_DQ<7>                J1G3             10       SCONN288_H44441004_PIP-SCONN,HA
M_J_DQ<7>                J9U2             155      SCONN288_H44441003_PIP-SCONN,HA
M_J_DQ<7>                U2D1             AK75     SKX_EXT_B_BGA1-IC,TBD
M_J_DQ<8>                J1G3             161      SCONN288_H44441004_PIP-SCONN,HA
M_J_DQ<8>                J9U2             16       SCONN288_H44441003_PIP-SCONN,HA
M_J_DQ<8>                U2D1             AE76     SKX_EXT_B_BGA1-IC,TBD
M_J_DQ<9>                J1G3             16       SCONN288_H44441004_PIP-SCONN,HA
M_J_DQ<9>                J9U2             161      SCONN288_H44441003_PIP-SCONN,HA
M_J_DQ<9>                U2D1             AC74     SKX_EXT_B_BGA1-IC,TBD
M_J_DQ<10>               J1G3             168      SCONN288_H44441004_PIP-SCONN,HA
M_J_DQ<10>               J9U2             23       SCONN288_H44441003_PIP-SCONN,HA
M_J_DQ<10>               U2D1             Y77      SKX_EXT_B_BGA1-IC,TBD
M_J_DQ<11>               J1G3             23       SCONN288_H44441004_PIP-SCONN,HA
M_J_DQ<11>               J9U2             168      SCONN288_H44441003_PIP-SCONN,HA
M_J_DQ<11>               U2D1             W76      SKX_EXT_B_BGA1-IC,TBD
M_J_DQ<12>               J1G3             159      SCONN288_H44441004_PIP-SCONN,HA
M_J_DQ<12>               J9U2             14       SCONN288_H44441003_PIP-SCONN,HA
M_J_DQ<12>               U2D1             AF75     SKX_EXT_B_BGA1-IC,TBD
M_J_DQ<13>               J1G3             14       SCONN288_H44441004_PIP-SCONN,HA
M_J_DQ<13>               J9U2             159      SCONN288_H44441003_PIP-SCONN,HA
M_J_DQ<13>               U2D1             AE74     SKX_EXT_B_BGA1-IC,TBD
M_J_DQ<14>               J1G3             166      SCONN288_H44441004_PIP-SCONN,HA
M_J_DQ<14>               J9U2             21       SCONN288_H44441003_PIP-SCONN,HA
M_J_DQ<14>               U2D1             AB77     SKX_EXT_B_BGA1-IC,TBD
M_J_DQ<15>               J1G3             21       SCONN288_H44441004_PIP-SCONN,HA
M_J_DQ<15>               J9U2             166      SCONN288_H44441003_PIP-SCONN,HA
M_J_DQ<15>               U2D1             Y75      SKX_EXT_B_BGA1-IC,TBD
M_J_DQ<16>               J1G3             172      SCONN288_H44441004_PIP-SCONN,HA
M_J_DQ<16>               J9U2             27       SCONN288_H44441003_PIP-SCONN,HA
M_J_DQ<16>               U2D1             W72      SKX_EXT_B_BGA1-IC,TBD
M_J_DQ<17>               J1G3             27       SCONN288_H44441004_PIP-SCONN,HA
M_J_DQ<17>               J9U2             172      SCONN288_H44441003_PIP-SCONN,HA
M_J_DQ<17>               U2D1             AA70     SKX_EXT_B_BGA1-IC,TBD
M_J_DQ<18>               J1G3             179      SCONN288_H44441004_PIP-SCONN,HA
M_J_DQ<18>               J9U2             34       SCONN288_H44441003_PIP-SCONN,HA
M_J_DQ<18>               U2D1             R70      SKX_EXT_B_BGA1-IC,TBD
M_J_DQ<19>               J1G3             34       SCONN288_H44441004_PIP-SCONN,HA
M_J_DQ<19>               J9U2             179      SCONN288_H44441003_PIP-SCONN,HA
M_J_DQ<19>               U2D1             T69      SKX_EXT_B_BGA1-IC,TBD
M_J_DQ<20>               J1G3             170      SCONN288_H44441004_PIP-SCONN,HA
M_J_DQ<20>               J9U2             25       SCONN288_H44441003_PIP-SCONN,HA
M_J_DQ<20>               U2D1             AA72     SKX_EXT_B_BGA1-IC,TBD
M_J_DQ<21>               J1G3             25       SCONN288_H44441004_PIP-SCONN,HA
M_J_DQ<21>               J9U2             170      SCONN288_H44441003_PIP-SCONN,HA
M_J_DQ<21>               U2D1             AB71     SKX_EXT_B_BGA1-IC,TBD
M_J_DQ<22>               J1G3             177      SCONN288_H44441004_PIP-SCONN,HA
M_J_DQ<22>               J9U2             32       SCONN288_H44441003_PIP-SCONN,HA
M_J_DQ<22>               U2D1             T71      SKX_EXT_B_BGA1-IC,TBD
M_J_DQ<23>               J1G3             32       SCONN288_H44441004_PIP-SCONN,HA
M_J_DQ<23>               J9U2             177      SCONN288_H44441003_PIP-SCONN,HA
M_J_DQ<23>               U2D1             V69      SKX_EXT_B_BGA1-IC,TBD
M_J_DQ<24>               J1G3             183      SCONN288_H44441004_PIP-SCONN,HA
M_J_DQ<24>               J9U2             38       SCONN288_H44441003_PIP-SCONN,HA
M_J_DQ<24>               U2D1             AM67     SKX_EXT_B_BGA1-IC,TBD
M_J_DQ<25>               J1G3             38       SCONN288_H44441004_PIP-SCONN,HA
M_J_DQ<25>               J9U2             183      SCONN288_H44441003_PIP-SCONN,HA
M_J_DQ<25>               U2D1             AT67     SKX_EXT_B_BGA1-IC,TBD
M_J_DQ<26>               J1G3             190      SCONN288_H44441004_PIP-SCONN,HA
M_J_DQ<26>               J9U2             45       SCONN288_H44441003_PIP-SCONN,HA
M_J_DQ<26>               U2D1             AN64     SKX_EXT_B_BGA1-IC,TBD
M_J_DQ<27>               J1G3             45       SCONN288_H44441004_PIP-SCONN,HA
M_J_DQ<27>               J9U2             190      SCONN288_H44441003_PIP-SCONN,HA
M_J_DQ<27>               U2D1             AR64     SKX_EXT_B_BGA1-IC,TBD
M_J_DQ<28>               J1G3             181      SCONN288_H44441004_PIP-SCONN,HA
M_J_DQ<28>               J9U2             36       SCONN288_H44441003_PIP-SCONN,HA
M_J_DQ<28>               U2D1             AN68     SKX_EXT_B_BGA1-IC,TBD
M_J_DQ<29>               J1G3             36       SCONN288_H44441004_PIP-SCONN,HA
M_J_DQ<29>               J9U2             181      SCONN288_H44441003_PIP-SCONN,HA
M_J_DQ<29>               U2D1             AR68     SKX_EXT_B_BGA1-IC,TBD
M_J_DQ<30>               J1G3             188      SCONN288_H44441004_PIP-SCONN,HA
M_J_DQ<30>               J9U2             43       SCONN288_H44441003_PIP-SCONN,HA
M_J_DQ<30>               U2D1             AM65     SKX_EXT_B_BGA1-IC,TBD
M_J_DQ<31>               J1G3             43       SCONN288_H44441004_PIP-SCONN,HA
M_J_DQ<31>               J9U2             188      SCONN288_H44441003_PIP-SCONN,HA
M_J_DQ<31>               U2D1             AT65     SKX_EXT_B_BGA1-IC,TBD
M_J_DQ<32>               J1G3             242      SCONN288_H44441004_PIP-SCONN,HA
M_J_DQ<32>               J9U2             97       SCONN288_H44441003_PIP-SCONN,HA
M_J_DQ<32>               U2D1             U40      SKX_EXT_B_BGA1-IC,TBD
M_J_DQ<33>               J1G3             97       SCONN288_H44441004_PIP-SCONN,HA
M_J_DQ<33>               J9U2             242      SCONN288_H44441003_PIP-SCONN,HA
M_J_DQ<33>               U2D1             AA40     SKX_EXT_B_BGA1-IC,TBD
M_J_DQ<34>               J1G3             249      SCONN288_H44441004_PIP-SCONN,HA
M_J_DQ<34>               J9U2             104      SCONN288_H44441003_PIP-SCONN,HA
M_J_DQ<34>               U2D1             V37      SKX_EXT_B_BGA1-IC,TBD
M_J_DQ<35>               J1G3             104      SCONN288_H44441004_PIP-SCONN,HA
M_J_DQ<35>               J9U2             249      SCONN288_H44441003_PIP-SCONN,HA
M_J_DQ<35>               U2D1             Y37      SKX_EXT_B_BGA1-IC,TBD
M_J_DQ<36>               J1G3             240      SCONN288_H44441004_PIP-SCONN,HA
M_J_DQ<36>               J9U2             95       SCONN288_H44441003_PIP-SCONN,HA
M_J_DQ<36>               U2D1             V41      SKX_EXT_B_BGA1-IC,TBD
M_J_DQ<37>               J1G3             95       SCONN288_H44441004_PIP-SCONN,HA
M_J_DQ<37>               J9U2             240      SCONN288_H44441003_PIP-SCONN,HA
M_J_DQ<37>               U2D1             Y41      SKX_EXT_B_BGA1-IC,TBD
M_J_DQ<38>               J1G3             247      SCONN288_H44441004_PIP-SCONN,HA
M_J_DQ<38>               J9U2             102      SCONN288_H44441003_PIP-SCONN,HA
M_J_DQ<38>               U2D1             U38      SKX_EXT_B_BGA1-IC,TBD
M_J_DQ<39>               J1G3             102      SCONN288_H44441004_PIP-SCONN,HA
M_J_DQ<39>               J9U2             247      SCONN288_H44441003_PIP-SCONN,HA
M_J_DQ<39>               U2D1             AA38     SKX_EXT_B_BGA1-IC,TBD
M_J_DQ<40>               J1G3             253      SCONN288_H44441004_PIP-SCONN,HA
M_J_DQ<40>               J9U2             108      SCONN288_H44441003_PIP-SCONN,HA
M_J_DQ<40>               U2D1             U34      SKX_EXT_B_BGA1-IC,TBD
M_J_DQ<41>               J1G3             108      SCONN288_H44441004_PIP-SCONN,HA
M_J_DQ<41>               J9U2             253      SCONN288_H44441003_PIP-SCONN,HA
M_J_DQ<41>               U2D1             AA34     SKX_EXT_B_BGA1-IC,TBD
M_J_DQ<42>               J1G3             260      SCONN288_H44441004_PIP-SCONN,HA
M_J_DQ<42>               J9U2             115      SCONN288_H44441003_PIP-SCONN,HA
M_J_DQ<42>               U2D1             V31      SKX_EXT_B_BGA1-IC,TBD
M_J_DQ<43>               J1G3             115      SCONN288_H44441004_PIP-SCONN,HA
M_J_DQ<43>               J9U2             260      SCONN288_H44441003_PIP-SCONN,HA
M_J_DQ<43>               U2D1             Y31      SKX_EXT_B_BGA1-IC,TBD
M_J_DQ<44>               J1G3             251      SCONN288_H44441004_PIP-SCONN,HA
M_J_DQ<44>               J9U2             106      SCONN288_H44441003_PIP-SCONN,HA
M_J_DQ<44>               U2D1             V35      SKX_EXT_B_BGA1-IC,TBD
M_J_DQ<45>               J1G3             106      SCONN288_H44441004_PIP-SCONN,HA
M_J_DQ<45>               J9U2             251      SCONN288_H44441003_PIP-SCONN,HA
M_J_DQ<45>               U2D1             Y35      SKX_EXT_B_BGA1-IC,TBD
M_J_DQ<46>               J1G3             258      SCONN288_H44441004_PIP-SCONN,HA
M_J_DQ<46>               J9U2             113      SCONN288_H44441003_PIP-SCONN,HA
M_J_DQ<46>               U2D1             U32      SKX_EXT_B_BGA1-IC,TBD
M_J_DQ<47>               J1G3             113      SCONN288_H44441004_PIP-SCONN,HA
M_J_DQ<47>               J9U2             258      SCONN288_H44441003_PIP-SCONN,HA
M_J_DQ<47>               U2D1             AA32     SKX_EXT_B_BGA1-IC,TBD
M_J_DQ<48>               J1G3             264      SCONN288_H44441004_PIP-SCONN,HA
M_J_DQ<48>               J9U2             119      SCONN288_H44441003_PIP-SCONN,HA
M_J_DQ<48>               U2D1             AD31     SKX_EXT_B_BGA1-IC,TBD
M_J_DQ<49>               J1G3             119      SCONN288_H44441004_PIP-SCONN,HA
M_J_DQ<49>               J9U2             264      SCONN288_H44441003_PIP-SCONN,HA
M_J_DQ<49>               U2D1             AH31     SKX_EXT_B_BGA1-IC,TBD
M_J_DQ<50>               J1G3             271      SCONN288_H44441004_PIP-SCONN,HA
M_J_DQ<50>               J9U2             126      SCONN288_H44441003_PIP-SCONN,HA
M_J_DQ<50>               U2D1             AE28     SKX_EXT_B_BGA1-IC,TBD
M_J_DQ<51>               J1G3             126      SCONN288_H44441004_PIP-SCONN,HA
M_J_DQ<51>               J9U2             271      SCONN288_H44441003_PIP-SCONN,HA
M_J_DQ<51>               U2D1             AG28     SKX_EXT_B_BGA1-IC,TBD
M_J_DQ<52>               J1G3             262      SCONN288_H44441004_PIP-SCONN,HA
M_J_DQ<52>               J9U2             117      SCONN288_H44441003_PIP-SCONN,HA
M_J_DQ<52>               U2D1             AE32     SKX_EXT_B_BGA1-IC,TBD
M_J_DQ<53>               J1G3             117      SCONN288_H44441004_PIP-SCONN,HA
M_J_DQ<53>               J9U2             262      SCONN288_H44441003_PIP-SCONN,HA
M_J_DQ<53>               U2D1             AG32     SKX_EXT_B_BGA1-IC,TBD
M_J_DQ<54>               J1G3             269      SCONN288_H44441004_PIP-SCONN,HA
M_J_DQ<54>               J9U2             124      SCONN288_H44441003_PIP-SCONN,HA
M_J_DQ<54>               U2D1             AD29     SKX_EXT_B_BGA1-IC,TBD
M_J_DQ<55>               J1G3             124      SCONN288_H44441004_PIP-SCONN,HA
M_J_DQ<55>               J9U2             269      SCONN288_H44441003_PIP-SCONN,HA
M_J_DQ<55>               U2D1             AH29     SKX_EXT_B_BGA1-IC,TBD
M_J_DQ<56>               J1G3             275      SCONN288_H44441004_PIP-SCONN,HA
M_J_DQ<56>               J9U2             130      SCONN288_H44441003_PIP-SCONN,HA
M_J_DQ<56>               U2D1             AD25     SKX_EXT_B_BGA1-IC,TBD
M_J_DQ<57>               J1G3             130      SCONN288_H44441004_PIP-SCONN,HA
M_J_DQ<57>               J9U2             275      SCONN288_H44441003_PIP-SCONN,HA
M_J_DQ<57>               U2D1             AH25     SKX_EXT_B_BGA1-IC,TBD
M_J_DQ<58>               J1G3             282      SCONN288_H44441004_PIP-SCONN,HA
M_J_DQ<58>               J9U2             137      SCONN288_H44441003_PIP-SCONN,HA
M_J_DQ<58>               U2D1             AE22     SKX_EXT_B_BGA1-IC,TBD
M_J_DQ<59>               J1G3             137      SCONN288_H44441004_PIP-SCONN,HA
M_J_DQ<59>               J9U2             282      SCONN288_H44441003_PIP-SCONN,HA
M_J_DQ<59>               U2D1             AG22     SKX_EXT_B_BGA1-IC,TBD
M_J_DQ<60>               J1G3             273      SCONN288_H44441004_PIP-SCONN,HA
M_J_DQ<60>               J9U2             128      SCONN288_H44441003_PIP-SCONN,HA
M_J_DQ<60>               U2D1             AE26     SKX_EXT_B_BGA1-IC,TBD
M_J_DQ<61>               J1G3             128      SCONN288_H44441004_PIP-SCONN,HA
M_J_DQ<61>               J9U2             273      SCONN288_H44441003_PIP-SCONN,HA
M_J_DQ<61>               U2D1             AG26     SKX_EXT_B_BGA1-IC,TBD
M_J_DQ<62>               J1G3             280      SCONN288_H44441004_PIP-SCONN,HA
M_J_DQ<62>               J9U2             135      SCONN288_H44441003_PIP-SCONN,HA
M_J_DQ<62>               U2D1             AD23     SKX_EXT_B_BGA1-IC,TBD
M_J_DQ<63>               J1G3             135      SCONN288_H44441004_PIP-SCONN,HA
M_J_DQ<63>               J9U2             280      SCONN288_H44441003_PIP-SCONN,HA
M_J_DQ<63>               U2D1             AH23     SKX_EXT_B_BGA1-IC,TBD
M_J_DQS_DN<0>            J1G3             152      SCONN288_H44441004_PIP-SCONN,HA
M_J_DQS_DN<0>            J9U2             152      SCONN288_H44441003_PIP-SCONN,HA
M_J_DQS_DN<0>            U2D1             AL74     SKX_EXT_B_BGA1-IC,TBD
M_J_DQS_DN<1>            J1G3             163      SCONN288_H44441004_PIP-SCONN,HA
M_J_DQS_DN<1>            J9U2             163      SCONN288_H44441003_PIP-SCONN,HA
M_J_DQS_DN<1>            U2D1             AA74     SKX_EXT_B_BGA1-IC,TBD
M_J_DQS_DN<2>            J1G3             174      SCONN288_H44441004_PIP-SCONN,HA
M_J_DQS_DN<2>            J9U2             174      SCONN288_H44441003_PIP-SCONN,HA
M_J_DQS_DN<2>            U2D1             Y69      SKX_EXT_B_BGA1-IC,TBD
M_J_DQS_DN<3>            J1G3             185      SCONN288_H44441004_PIP-SCONN,HA
M_J_DQS_DN<3>            J9U2             185      SCONN288_H44441003_PIP-SCONN,HA
M_J_DQS_DN<3>            U2D1             AU66     SKX_EXT_B_BGA1-IC,TBD
M_J_DQS_DN<4>            J1G3             244      SCONN288_H44441004_PIP-SCONN,HA
M_J_DQS_DN<4>            J9U2             244      SCONN288_H44441003_PIP-SCONN,HA
M_J_DQS_DN<4>            U2D1             AB39     SKX_EXT_B_BGA1-IC,TBD
M_J_DQS_DN<5>            J1G3             255      SCONN288_H44441004_PIP-SCONN,HA
M_J_DQS_DN<5>            J9U2             255      SCONN288_H44441003_PIP-SCONN,HA
M_J_DQS_DN<5>            U2D1             AB33     SKX_EXT_B_BGA1-IC,TBD
M_J_DQS_DN<6>            J1G3             266      SCONN288_H44441004_PIP-SCONN,HA
M_J_DQS_DN<6>            J9U2             266      SCONN288_H44441003_PIP-SCONN,HA
M_J_DQS_DN<6>            U2D1             AJ30     SKX_EXT_B_BGA1-IC,TBD
M_J_DQS_DN<7>            J1G3             277      SCONN288_H44441004_PIP-SCONN,HA
M_J_DQS_DN<7>            J9U2             277      SCONN288_H44441003_PIP-SCONN,HA
M_J_DQS_DN<7>            U2D1             AJ24     SKX_EXT_B_BGA1-IC,TBD
M_J_DQS_DN<8>            J1G3             196      SCONN288_H44441004_PIP-SCONN,HA
M_J_DQS_DN<8>            J9U2             196      SCONN288_H44441003_PIP-SCONN,HA
M_J_DQS_DN<8>            U2D1             BB71     SKX_EXT_B_BGA1-IC,TBD
M_J_DQS_DN<9>            J1G3             8        SCONN288_H44441004_PIP-SCONN,HA
M_J_DQS_DN<9>            J9U2             8        SCONN288_H44441003_PIP-SCONN,HA
M_J_DQS_DN<9>            U2D1             AP77     SKX_EXT_B_BGA1-IC,TBD
M_J_DQS_DN<10>           J1G3             19       SCONN288_H44441004_PIP-SCONN,HA
M_J_DQS_DN<10>           J9U2             19       SCONN288_H44441003_PIP-SCONN,HA
M_J_DQS_DN<10>           U2D1             AD77     SKX_EXT_B_BGA1-IC,TBD
M_J_DQS_DN<11>           J1G3             30       SCONN288_H44441004_PIP-SCONN,HA
M_J_DQS_DN<11>           J9U2             30       SCONN288_H44441003_PIP-SCONN,HA
M_J_DQS_DN<11>           U2D1             U72      SKX_EXT_B_BGA1-IC,TBD
M_J_DQS_DN<12>           J1G3             41       SCONN288_H44441004_PIP-SCONN,HA
M_J_DQS_DN<12>           J9U2             41       SCONN288_H44441003_PIP-SCONN,HA
M_J_DQS_DN<12>           U2D1             AL66     SKX_EXT_B_BGA1-IC,TBD
M_J_DQS_DN<13>           J1G3             100      SCONN288_H44441004_PIP-SCONN,HA
M_J_DQS_DN<13>           J9U2             100      SCONN288_H44441003_PIP-SCONN,HA
M_J_DQS_DN<13>           U2D1             T39      SKX_EXT_B_BGA1-IC,TBD
M_J_DQS_DN<14>           J1G3             111      SCONN288_H44441004_PIP-SCONN,HA
M_J_DQS_DN<14>           J9U2             111      SCONN288_H44441003_PIP-SCONN,HA
M_J_DQS_DN<14>           U2D1             T33      SKX_EXT_B_BGA1-IC,TBD
M_J_DQS_DN<15>           J1G3             122      SCONN288_H44441004_PIP-SCONN,HA
M_J_DQS_DN<15>           J9U2             122      SCONN288_H44441003_PIP-SCONN,HA
M_J_DQS_DN<15>           U2D1             AC30     SKX_EXT_B_BGA1-IC,TBD
M_J_DQS_DN<16>           J1G3             133      SCONN288_H44441004_PIP-SCONN,HA
M_J_DQS_DN<16>           J9U2             133      SCONN288_H44441003_PIP-SCONN,HA
M_J_DQS_DN<16>           U2D1             AC24     SKX_EXT_B_BGA1-IC,TBD
M_J_DQS_DN<17>           J1G3             52       SCONN288_H44441004_PIP-SCONN,HA
M_J_DQS_DN<17>           J9U2             52       SCONN288_H44441003_PIP-SCONN,HA
M_J_DQS_DN<17>           U2D1             AT71     SKX_EXT_B_BGA1-IC,TBD
M_J_DQS_DP<0>            J1G3             153      SCONN288_H44441004_PIP-SCONN,HA
M_J_DQS_DP<0>            J9U2             153      SCONN288_H44441003_PIP-SCONN,HA
M_J_DQS_DP<0>            U2D1             AM75     SKX_EXT_B_BGA1-IC,TBD
M_J_DQS_DP<1>            J1G3             164      SCONN288_H44441004_PIP-SCONN,HA
M_J_DQS_DP<1>            J9U2             164      SCONN288_H44441003_PIP-SCONN,HA
M_J_DQS_DP<1>            U2D1             AB75     SKX_EXT_B_BGA1-IC,TBD
M_J_DQS_DP<2>            J1G3             175      SCONN288_H44441004_PIP-SCONN,HA
M_J_DQS_DP<2>            J9U2             175      SCONN288_H44441003_PIP-SCONN,HA
M_J_DQS_DP<2>            U2D1             W70      SKX_EXT_B_BGA1-IC,TBD
M_J_DQS_DP<3>            J1G3             186      SCONN288_H44441004_PIP-SCONN,HA
M_J_DQS_DP<3>            J9U2             186      SCONN288_H44441003_PIP-SCONN,HA
M_J_DQS_DP<3>            U2D1             AR66     SKX_EXT_B_BGA1-IC,TBD
M_J_DQS_DP<4>            J1G3             245      SCONN288_H44441004_PIP-SCONN,HA
M_J_DQS_DP<4>            J9U2             245      SCONN288_H44441003_PIP-SCONN,HA
M_J_DQS_DP<4>            U2D1             Y39      SKX_EXT_B_BGA1-IC,TBD
M_J_DQS_DP<5>            J1G3             256      SCONN288_H44441004_PIP-SCONN,HA
M_J_DQS_DP<5>            J9U2             256      SCONN288_H44441003_PIP-SCONN,HA
M_J_DQS_DP<5>            U2D1             Y33      SKX_EXT_B_BGA1-IC,TBD
M_J_DQS_DP<6>            J1G3             267      SCONN288_H44441004_PIP-SCONN,HA
M_J_DQS_DP<6>            J9U2             267      SCONN288_H44441003_PIP-SCONN,HA
M_J_DQS_DP<6>            U2D1             AG30     SKX_EXT_B_BGA1-IC,TBD
M_J_DQS_DP<7>            J1G3             278      SCONN288_H44441004_PIP-SCONN,HA
M_J_DQS_DP<7>            J9U2             278      SCONN288_H44441003_PIP-SCONN,HA
M_J_DQS_DP<7>            U2D1             AG24     SKX_EXT_B_BGA1-IC,TBD
M_J_DQS_DP<8>            J1G3             197      SCONN288_H44441004_PIP-SCONN,HA
M_J_DQS_DP<8>            J9U2             197      SCONN288_H44441003_PIP-SCONN,HA
M_J_DQS_DP<8>            U2D1             AY71     SKX_EXT_B_BGA1-IC,TBD
M_J_DQS_DP<9>            J1G3             7        SCONN288_H44441004_PIP-SCONN,HA
M_J_DQS_DP<9>            J9U2             7        SCONN288_H44441003_PIP-SCONN,HA
M_J_DQS_DP<9>            U2D1             AN76     SKX_EXT_B_BGA1-IC,TBD
M_J_DQS_DP<10>           J1G3             18       SCONN288_H44441004_PIP-SCONN,HA
M_J_DQS_DP<10>           J9U2             18       SCONN288_H44441003_PIP-SCONN,HA
M_J_DQS_DP<10>           U2D1             AC76     SKX_EXT_B_BGA1-IC,TBD
M_J_DQS_DP<11>           J1G3             29       SCONN288_H44441004_PIP-SCONN,HA
M_J_DQS_DP<11>           J9U2             29       SCONN288_H44441003_PIP-SCONN,HA
M_J_DQS_DP<11>           U2D1             V71      SKX_EXT_B_BGA1-IC,TBD
M_J_DQS_DP<12>           J1G3             40       SCONN288_H44441004_PIP-SCONN,HA
M_J_DQS_DP<12>           J9U2             40       SCONN288_H44441003_PIP-SCONN,HA
M_J_DQS_DP<12>           U2D1             AN66     SKX_EXT_B_BGA1-IC,TBD
M_J_DQS_DP<13>           J1G3             99       SCONN288_H44441004_PIP-SCONN,HA
M_J_DQS_DP<13>           J9U2             99       SCONN288_H44441003_PIP-SCONN,HA
M_J_DQS_DP<13>           U2D1             V39      SKX_EXT_B_BGA1-IC,TBD
M_J_DQS_DP<14>           J1G3             110      SCONN288_H44441004_PIP-SCONN,HA
M_J_DQS_DP<14>           J9U2             110      SCONN288_H44441003_PIP-SCONN,HA
M_J_DQS_DP<14>           U2D1             V33      SKX_EXT_B_BGA1-IC,TBD
M_J_DQS_DP<15>           J1G3             121      SCONN288_H44441004_PIP-SCONN,HA
M_J_DQS_DP<15>           J9U2             121      SCONN288_H44441003_PIP-SCONN,HA
M_J_DQS_DP<15>           U2D1             AE30     SKX_EXT_B_BGA1-IC,TBD
M_J_DQS_DP<16>           J1G3             132      SCONN288_H44441004_PIP-SCONN,HA
M_J_DQS_DP<16>           J9U2             132      SCONN288_H44441003_PIP-SCONN,HA
M_J_DQS_DP<16>           U2D1             AE24     SKX_EXT_B_BGA1-IC,TBD
M_J_DQS_DP<17>           J1G3             51       SCONN288_H44441004_PIP-SCONN,HA
M_J_DQS_DP<17>           J9U2             51       SCONN288_H44441003_PIP-SCONN,HA
M_J_DQS_DP<17>           U2D1             AV71     SKX_EXT_B_BGA1-IC,TBD
M_J_ECC<0>               J1G3             194      SCONN288_H44441004_PIP-SCONN,HA
M_J_ECC<0>               J9U2             49       SCONN288_H44441003_PIP-SCONN,HA
M_J_ECC<0>               U2D1             AU72     SKX_EXT_B_BGA1-IC,TBD
M_J_ECC<1>               J1G3             49       SCONN288_H44441004_PIP-SCONN,HA
M_J_ECC<1>               J9U2             194      SCONN288_H44441003_PIP-SCONN,HA
M_J_ECC<1>               U2D1             BA72     SKX_EXT_B_BGA1-IC,TBD
M_J_ECC<2>               J1G3             201      SCONN288_H44441004_PIP-SCONN,HA
M_J_ECC<2>               J9U2             56       SCONN288_H44441003_PIP-SCONN,HA
M_J_ECC<2>               U2D1             AV69     SKX_EXT_B_BGA1-IC,TBD
M_J_ECC<3>               J1G3             56       SCONN288_H44441004_PIP-SCONN,HA
M_J_ECC<3>               J9U2             201      SCONN288_H44441003_PIP-SCONN,HA
M_J_ECC<3>               U2D1             AY69     SKX_EXT_B_BGA1-IC,TBD
M_J_ECC<4>               J1G3             192      SCONN288_H44441004_PIP-SCONN,HA
M_J_ECC<4>               J9U2             47       SCONN288_H44441003_PIP-SCONN,HA
M_J_ECC<4>               U2D1             AV73     SKX_EXT_B_BGA1-IC,TBD
M_J_ECC<5>               J1G3             47       SCONN288_H44441004_PIP-SCONN,HA
M_J_ECC<5>               J9U2             192      SCONN288_H44441003_PIP-SCONN,HA
M_J_ECC<5>               U2D1             AY73     SKX_EXT_B_BGA1-IC,TBD
M_J_ECC<6>               J1G3             199      SCONN288_H44441004_PIP-SCONN,HA
M_J_ECC<6>               J9U2             54       SCONN288_H44441003_PIP-SCONN,HA
M_J_ECC<6>               U2D1             AU70     SKX_EXT_B_BGA1-IC,TBD
M_J_ECC<7>               J1G3             54       SCONN288_H44441004_PIP-SCONN,HA
M_J_ECC<7>               J9U2             199      SCONN288_H44441003_PIP-SCONN,HA
M_J_ECC<7>               U2D1             BA70     SKX_EXT_B_BGA1-IC,TBD
M_J_MA<0>                J1G3             79       SCONN288_H44441004_PIP-SCONN,HA
M_J_MA<0>                J9U2             79       SCONN288_H44441003_PIP-SCONN,HA
M_J_MA<0>                U2D1             AB53     SKX_EXT_B_BGA1-IC,TBD
M_J_MA<1>                J1G3             72       SCONN288_H44441004_PIP-SCONN,HA
M_J_MA<1>                J9U2             72       SCONN288_H44441003_PIP-SCONN,HA
M_J_MA<1>                U2D1             AE58     SKX_EXT_B_BGA1-IC,TBD
M_J_MA<2>                J1G3             216      SCONN288_H44441004_PIP-SCONN,HA
M_J_MA<2>                J9U2             216      SCONN288_H44441003_PIP-SCONN,HA
M_J_MA<2>                U2D1             AD57     SKX_EXT_B_BGA1-IC,TBD
M_J_MA<3>                J1G3             71       SCONN288_H44441004_PIP-SCONN,HA
M_J_MA<3>                J9U2             71       SCONN288_H44441003_PIP-SCONN,HA
M_J_MA<3>                U2D1             W58      SKX_EXT_B_BGA1-IC,TBD
M_J_MA<4>                J1G3             214      SCONN288_H44441004_PIP-SCONN,HA
M_J_MA<4>                J9U2             214      SCONN288_H44441003_PIP-SCONN,HA
M_J_MA<4>                U2D1             AA58     SKX_EXT_B_BGA1-IC,TBD
M_J_MA<5>                J1G3             213      SCONN288_H44441004_PIP-SCONN,HA
M_J_MA<5>                J9U2             213      SCONN288_H44441003_PIP-SCONN,HA
M_J_MA<5>                U2D1             V59      SKX_EXT_B_BGA1-IC,TBD
M_J_MA<6>                J1G3             69       SCONN288_H44441004_PIP-SCONN,HA
M_J_MA<6>                J9U2             69       SCONN288_H44441003_PIP-SCONN,HA
M_J_MA<6>                U2D1             AB59     SKX_EXT_B_BGA1-IC,TBD
M_J_MA<7>                J1G3             211      SCONN288_H44441004_PIP-SCONN,HA
M_J_MA<7>                J9U2             211      SCONN288_H44441003_PIP-SCONN,HA
M_J_MA<7>                U2D1             AE60     SKX_EXT_B_BGA1-IC,TBD
M_J_MA<8>                J1G3             68       SCONN288_H44441004_PIP-SCONN,HA
M_J_MA<8>                J9U2             68       SCONN288_H44441003_PIP-SCONN,HA
M_J_MA<8>                U2D1             AD59     SKX_EXT_B_BGA1-IC,TBD
M_J_MA<9>                J1G3             66       SCONN288_H44441004_PIP-SCONN,HA
M_J_MA<9>                J9U2             66       SCONN288_H44441003_PIP-SCONN,HA
M_J_MA<9>                U2D1             AG58     SKX_EXT_B_BGA1-IC,TBD
M_J_MA<10>               J1G3             225      SCONN288_H44441004_PIP-SCONN,HA
M_J_MA<10>               J9U2             225      SCONN288_H44441003_PIP-SCONN,HA
M_J_MA<10>               U2D1             AD55     SKX_EXT_B_BGA1-IC,TBD
M_J_MA<11>               J1G3             210      SCONN288_H44441004_PIP-SCONN,HA
M_J_MA<11>               J9U2             210      SCONN288_H44441003_PIP-SCONN,HA
M_J_MA<11>               U2D1             AG60     SKX_EXT_B_BGA1-IC,TBD
M_J_MA<12>               J1G3             65       SCONN288_H44441004_PIP-SCONN,HA
M_J_MA<12>               J9U2             65       SCONN288_H44441003_PIP-SCONN,HA
M_J_MA<12>               U2D1             AG62     SKX_EXT_B_BGA1-IC,TBD
M_J_MA<13>               J1G3             232      SCONN288_H44441004_PIP-SCONN,HA
M_J_MA<13>               J9U2             232      SCONN288_H44441003_PIP-SCONN,HA
M_J_MA<13>               U2D1             AD53     SKX_EXT_B_BGA1-IC,TBD
M_J_MA<14>               J1G3             228      SCONN288_H44441004_PIP-SCONN,HA
M_J_MA<14>               J9U2             228      SCONN288_H44441003_PIP-SCONN,HA
M_J_MA<14>               U2D1             W50      SKX_EXT_B_BGA1-IC,TBD
M_J_MA<15>               J1G3             86       SCONN288_H44441004_PIP-SCONN,HA
M_J_MA<15>               J9U2             86       SCONN288_H44441003_PIP-SCONN,HA
M_J_MA<15>               U2D1             AE54     SKX_EXT_B_BGA1-IC,TBD
M_J_MA<16>               J1G3             82       SCONN288_H44441004_PIP-SCONN,HA
M_J_MA<16>               J9U2             82       SCONN288_H44441003_PIP-SCONN,HA
M_J_MA<16>               U2D1             AA52     SKX_EXT_B_BGA1-IC,TBD
M_J_MA<17>               J1G3             234      SCONN288_H44441004_PIP-SCONN,HA
M_J_MA<17>               J9U2             234      SCONN288_H44441003_PIP-SCONN,HA
M_J_MA<17>               U2D1             AC46     SKX_EXT_B_BGA1-IC,TBD
M_J_ODT<0>               J1G3             87       SCONN288_H44441004_PIP-SCONN,HA
M_J_ODT<0>               U2D1             AA50     SKX_EXT_B_BGA1-IC,TBD
M_J_ODT<1>               J1G3             91       SCONN288_H44441004_PIP-SCONN,HA
M_J_ODT<1>               U2D1             AA48     SKX_EXT_B_BGA1-IC,TBD
M_J_ODT<2>               J9U2             87       SCONN288_H44441003_PIP-SCONN,HA
M_J_ODT<2>               U2D1             V49      SKX_EXT_B_BGA1-IC,TBD
M_J_ODT<3>               J9U2             91       SCONN288_H44441003_PIP-SCONN,HA
M_J_ODT<3>               U2D1             AB47     SKX_EXT_B_BGA1-IC,TBD
M_J_PAR                  J1G3             222      SCONN288_H44441004_PIP-SCONN,HA
M_J_PAR                  J9U2             222      SCONN288_H44441003_PIP-SCONN,HA
M_J_PAR                  U2D1             V53      SKX_EXT_B_BGA1-IC,TBD
M_J_VREF                 C1G19            1        CAP_A_0402V-0.01UF,25V,10%,X7RA
M_J_VREF                 C9U10            1        CAP_A_0402V-0.01UF,25V,10%,X7RA
M_J_VREF                 J1G3             146      SCONN288_H44441004_PIP-SCONN,HA
M_J_VREF                 J9U2             146      SCONN288_H44441003_PIP-SCONN,HA
M_J_VREF                 R1G14            2        RES_0402-2,1.0%,1/16W,CHIP,G21A
M_J_VREF                 R1G15            2        RES_0402-1.00K,1%,1/16W,CHIP,GA
M_J_VREF                 R1G17            1        RES_0402-1.00K,1%,1/16W,CHIP,GA
M_KLM_RST_N              J1A1             58       SCONN288_H44441004_PIP-SCONN,HA
M_KLM_RST_N              J1A2             58       SCONN288_H44441004_PIP-SCONN,HA
M_KLM_RST_N              J1B1             58       SCONN288_H44441004_PIP-SCONN,HA
M_KLM_RST_N              J9L1             58       SCONN288_H44441003_PIP-SCONN,HA
M_KLM_RST_N              J9L2             58       SCONN288_H44441003_PIP-SCONN,HA
M_KLM_RST_N              J9M1             58       SCONN288_H44441003_PIP-SCONN,HA
M_KLM_RST_N              U2D1             DV63     SKX_EXT_B_BGA1-IC,TBD
M_K_ACT_N                J1B1             62       SCONN288_H44441004_PIP-SCONN,HA
M_K_ACT_N                J9M1             62       SCONN288_H44441003_PIP-SCONN,HA
M_K_ACT_N                U2D1             DW60     SKX_EXT_B_BGA1-IC,TBD
M_K_ALERT_N              J1B1             208      SCONN288_H44441004_PIP-SCONN,HA
M_K_ALERT_N              J9M1             208      SCONN288_H44441003_PIP-SCONN,HA
M_K_ALERT_N              U2D1             ED63     SKX_EXT_B_BGA1-IC,TBD
M_K_BA<0>                J1B1             81       SCONN288_H44441004_PIP-SCONN,HA
M_K_BA<0>                J9M1             81       SCONN288_H44441003_PIP-SCONN,HA
M_K_BA<0>                U2D1             EE52     SKX_EXT_B_BGA1-IC,TBD
M_K_BA<1>                J1B1             224      SCONN288_H44441004_PIP-SCONN,HA
M_K_BA<1>                J9M1             224      SCONN288_H44441003_PIP-SCONN,HA
M_K_BA<1>                U2D1             EA54     SKX_EXT_B_BGA1-IC,TBD
M_K_BG<0>                J1B1             63       SCONN288_H44441004_PIP-SCONN,HA
M_K_BG<0>                J9M1             63       SCONN288_H44441003_PIP-SCONN,HA
M_K_BG<0>                U2D1             ED61     SKX_EXT_B_BGA1-IC,TBD
M_K_BG<1>                J1B1             207      SCONN288_H44441004_PIP-SCONN,HA
M_K_BG<1>                J9M1             207      SCONN288_H44441003_PIP-SCONN,HA
M_K_BG<1>                U2D1             DW62     SKX_EXT_B_BGA1-IC,TBD
M_K_C<2>                 J1B1             235      SCONN288_H44441004_PIP-SCONN,HA
M_K_C<2>                 J9M1             235      SCONN288_H44441003_PIP-SCONN,HA
M_K_C<2>                 U2D1             DV47     SKX_EXT_B_BGA1-IC,TBD
M_K_CKE<0>               J1B1             60       SCONN288_H44441004_PIP-SCONN,HA
M_K_CKE<0>               U2D1             EE62     SKX_EXT_B_BGA1-IC,TBD
M_K_CKE<1>               J1B1             203      SCONN288_H44441004_PIP-SCONN,HA
M_K_CKE<1>               U2D1             EF63     SKX_EXT_B_BGA1-IC,TBD
M_K_CKE<2>               J9M1             60       SCONN288_H44441003_PIP-SCONN,HA
M_K_CKE<2>               U2D1             EA62     SKX_EXT_B_BGA1-IC,TBD
M_K_CKE<3>               J9M1             203      SCONN288_H44441003_PIP-SCONN,HA
M_K_CKE<3>               U2D1             EB63     SKX_EXT_B_BGA1-IC,TBD
M_K_CLK_DN<0>            J1B1             75       SCONN288_H44441004_PIP-SCONN,HA
M_K_CLK_DN<0>            U2D1             ED55     SKX_EXT_B_BGA1-IC,TBD
M_K_CLK_DN<1>            J1B1             219      SCONN288_H44441004_PIP-SCONN,HA
M_K_CLK_DN<1>            U2D1             EF55     SKX_EXT_B_BGA1-IC,TBD
M_K_CLK_DN<2>            J9M1             75       SCONN288_H44441003_PIP-SCONN,HA
M_K_CLK_DN<2>            U2D1             DW56     SKX_EXT_B_BGA1-IC,TBD
M_K_CLK_DN<3>            J9M1             219      SCONN288_H44441003_PIP-SCONN,HA
M_K_CLK_DN<3>            U2D1             EF57     SKX_EXT_B_BGA1-IC,TBD
M_K_CLK_DP<0>            J1B1             74       SCONN288_H44441004_PIP-SCONN,HA
M_K_CLK_DP<0>            U2D1             EB55     SKX_EXT_B_BGA1-IC,TBD
M_K_CLK_DP<1>            J1B1             218      SCONN288_H44441004_PIP-SCONN,HA
M_K_CLK_DP<1>            U2D1             EE54     SKX_EXT_B_BGA1-IC,TBD
M_K_CLK_DP<2>            J9M1             74       SCONN288_H44441003_PIP-SCONN,HA
M_K_CLK_DP<2>            U2D1             EA56     SKX_EXT_B_BGA1-IC,TBD
M_K_CLK_DP<3>            J9M1             218      SCONN288_H44441003_PIP-SCONN,HA
M_K_CLK_DP<3>            U2D1             EE56     SKX_EXT_B_BGA1-IC,TBD
M_K_CPU_VREF             C9M2             1        CAP_A_0402V-0.01UF,25V,10%,X7RA
M_K_CPU_VREF             R9M2             1        RES_0402-2,1.0%,1/16W,CHIP,G21A
M_K_CPU_VREF             U2D1             CP61     SKX_EXT_B_BGA1-IC,TBD
M_K_CS_N<0>              J1B1             84       SCONN288_H44441004_PIP-SCONN,HA
M_K_CS_N<0>              U2D1             EF51     SKX_EXT_B_BGA1-IC,TBD
M_K_CS_N<1>              J1B1             89       SCONN288_H44441004_PIP-SCONN,HA
M_K_CS_N<1>              U2D1             ED49     SKX_EXT_B_BGA1-IC,TBD
M_K_CS_N<2>              J1B1             93       SCONN288_H44441004_PIP-SCONN,HA
M_K_CS_N<2>              U2D1             ED47     SKX_EXT_B_BGA1-IC,TBD
M_K_CS_N<3>              J1B1             237      SCONN288_H44441004_PIP-SCONN,HA
M_K_CS_N<3>              U2D1             EB47     SKX_EXT_B_BGA1-IC,TBD
M_K_CS_N<4>              J9M1             84       SCONN288_H44441003_PIP-SCONN,HA
M_K_CS_N<4>              U2D1             EB51     SKX_EXT_B_BGA1-IC,TBD
M_K_CS_N<5>              J9M1             89       SCONN288_H44441003_PIP-SCONN,HA
M_K_CS_N<5>              U2D1             EB49     SKX_EXT_B_BGA1-IC,TBD
M_K_CS_N<6>              J9M1             93       SCONN288_H44441003_PIP-SCONN,HA
M_K_CS_N<6>              U2D1             DV45     SKX_EXT_B_BGA1-IC,TBD
M_K_CS_N<7>              J9M1             237      SCONN288_H44441003_PIP-SCONN,HA
M_K_CS_N<7>              U2D1             EB45     SKX_EXT_B_BGA1-IC,TBD
M_K_DQ<0>                J1B1             150      SCONN288_H44441004_PIP-SCONN,HA
M_K_DQ<0>                J9M1             5        SCONN288_H44441003_PIP-SCONN,HA
M_K_DQ<0>                U2D1             CN84     SKX_EXT_B_BGA1-IC,TBD
M_K_DQ<1>                J1B1             5        SCONN288_H44441004_PIP-SCONN,HA
M_K_DQ<1>                J9M1             150      SCONN288_H44441003_PIP-SCONN,HA
M_K_DQ<1>                U2D1             CN86     SKX_EXT_B_BGA1-IC,TBD
M_K_DQ<2>                J1B1             157      SCONN288_H44441004_PIP-SCONN,HA
M_K_DQ<2>                J9M1             12       SCONN288_H44441003_PIP-SCONN,HA
M_K_DQ<2>                U2D1             DA86     SKX_EXT_B_BGA1-IC,TBD
M_K_DQ<3>                J1B1             12       SCONN288_H44441004_PIP-SCONN,HA
M_K_DQ<3>                J9M1             157      SCONN288_H44441003_PIP-SCONN,HA
M_K_DQ<3>                U2D1             DA84     SKX_EXT_B_BGA1-IC,TBD
M_K_DQ<4>                J1B1             148      SCONN288_H44441004_PIP-SCONN,HA
M_K_DQ<4>                J9M1             3        SCONN288_H44441003_PIP-SCONN,HA
M_K_DQ<4>                U2D1             CL84     SKX_EXT_B_BGA1-IC,TBD
M_K_DQ<5>                J1B1             3        SCONN288_H44441004_PIP-SCONN,HA
M_K_DQ<5>                J9M1             148      SCONN288_H44441003_PIP-SCONN,HA
M_K_DQ<5>                U2D1             CL86     SKX_EXT_B_BGA1-IC,TBD
M_K_DQ<6>                J1B1             155      SCONN288_H44441004_PIP-SCONN,HA
M_K_DQ<6>                J9M1             10       SCONN288_H44441003_PIP-SCONN,HA
M_K_DQ<6>                U2D1             CW86     SKX_EXT_B_BGA1-IC,TBD
M_K_DQ<7>                J1B1             10       SCONN288_H44441004_PIP-SCONN,HA
M_K_DQ<7>                J9M1             155      SCONN288_H44441003_PIP-SCONN,HA
M_K_DQ<7>                U2D1             CW84     SKX_EXT_B_BGA1-IC,TBD
M_K_DQ<8>                J1B1             161      SCONN288_H44441004_PIP-SCONN,HA
M_K_DQ<8>                J9M1             16       SCONN288_H44441003_PIP-SCONN,HA
M_K_DQ<8>                U2D1             DG84     SKX_EXT_B_BGA1-IC,TBD
M_K_DQ<9>                J1B1             16       SCONN288_H44441004_PIP-SCONN,HA
M_K_DQ<9>                J9M1             161      SCONN288_H44441003_PIP-SCONN,HA
M_K_DQ<9>                U2D1             DH85     SKX_EXT_B_BGA1-IC,TBD
M_K_DQ<10>               J1B1             168      SCONN288_H44441004_PIP-SCONN,HA
M_K_DQ<10>               J9M1             23       SCONN288_H44441003_PIP-SCONN,HA
M_K_DQ<10>               U2D1             DV83     SKX_EXT_B_BGA1-IC,TBD
M_K_DQ<11>               J1B1             23       SCONN288_H44441004_PIP-SCONN,HA
M_K_DQ<11>               J9M1             168      SCONN288_H44441003_PIP-SCONN,HA
M_K_DQ<11>               U2D1             DY83     SKX_EXT_B_BGA1-IC,TBD
M_K_DQ<12>               J1B1             159      SCONN288_H44441004_PIP-SCONN,HA
M_K_DQ<12>               J9M1             14       SCONN288_H44441003_PIP-SCONN,HA
M_K_DQ<12>               U2D1             DD85     SKX_EXT_B_BGA1-IC,TBD
M_K_DQ<13>               J1B1             14       SCONN288_H44441004_PIP-SCONN,HA
M_K_DQ<13>               J9M1             159      SCONN288_H44441003_PIP-SCONN,HA
M_K_DQ<13>               U2D1             DE84     SKX_EXT_B_BGA1-IC,TBD
M_K_DQ<14>               J1B1             166      SCONN288_H44441004_PIP-SCONN,HA
M_K_DQ<14>               J9M1             21       SCONN288_H44441003_PIP-SCONN,HA
M_K_DQ<14>               U2D1             DR84     SKX_EXT_B_BGA1-IC,TBD
M_K_DQ<15>               J1B1             21       SCONN288_H44441004_PIP-SCONN,HA
M_K_DQ<15>               J9M1             166      SCONN288_H44441003_PIP-SCONN,HA
M_K_DQ<15>               U2D1             DV85     SKX_EXT_B_BGA1-IC,TBD
M_K_DQ<16>               J1B1             172      SCONN288_H44441004_PIP-SCONN,HA
M_K_DQ<16>               J9M1             27       SCONN288_H44441003_PIP-SCONN,HA
M_K_DQ<16>               U2D1             DM79     SKX_EXT_B_BGA1-IC,TBD
M_K_DQ<17>               J1B1             27       SCONN288_H44441004_PIP-SCONN,HA
M_K_DQ<17>               J9M1             172      SCONN288_H44441003_PIP-SCONN,HA
M_K_DQ<17>               U2D1             DK81     SKX_EXT_B_BGA1-IC,TBD
M_K_DQ<18>               J1B1             179      SCONN288_H44441004_PIP-SCONN,HA
M_K_DQ<18>               J9M1             34       SCONN288_H44441003_PIP-SCONN,HA
M_K_DQ<18>               U2D1             DT81     SKX_EXT_B_BGA1-IC,TBD
M_K_DQ<19>               J1B1             34       SCONN288_H44441004_PIP-SCONN,HA
M_K_DQ<19>               J9M1             179      SCONN288_H44441003_PIP-SCONN,HA
M_K_DQ<19>               U2D1             DR82     SKX_EXT_B_BGA1-IC,TBD
M_K_DQ<20>               J1B1             170      SCONN288_H44441004_PIP-SCONN,HA
M_K_DQ<20>               J9M1             25       SCONN288_H44441003_PIP-SCONN,HA
M_K_DQ<20>               U2D1             DK79     SKX_EXT_B_BGA1-IC,TBD
M_K_DQ<21>               J1B1             25       SCONN288_H44441004_PIP-SCONN,HA
M_K_DQ<21>               J9M1             170      SCONN288_H44441003_PIP-SCONN,HA
M_K_DQ<21>               U2D1             DJ80     SKX_EXT_B_BGA1-IC,TBD
M_K_DQ<22>               J1B1             177      SCONN288_H44441004_PIP-SCONN,HA
M_K_DQ<22>               J9M1             32       SCONN288_H44441003_PIP-SCONN,HA
M_K_DQ<22>               U2D1             DR80     SKX_EXT_B_BGA1-IC,TBD
M_K_DQ<23>               J1B1             32       SCONN288_H44441004_PIP-SCONN,HA
M_K_DQ<23>               J9M1             177      SCONN288_H44441003_PIP-SCONN,HA
M_K_DQ<23>               U2D1             DN82     SKX_EXT_B_BGA1-IC,TBD
M_K_DQ<24>               J1B1             183      SCONN288_H44441004_PIP-SCONN,HA
M_K_DQ<24>               J9M1             38       SCONN288_H44441003_PIP-SCONN,HA
M_K_DQ<24>               U2D1             DN76     SKX_EXT_B_BGA1-IC,TBD
M_K_DQ<25>               J1B1             38       SCONN288_H44441004_PIP-SCONN,HA
M_K_DQ<25>               J9M1             183      SCONN288_H44441003_PIP-SCONN,HA
M_K_DQ<25>               U2D1             DU76     SKX_EXT_B_BGA1-IC,TBD
M_K_DQ<26>               J1B1             190      SCONN288_H44441004_PIP-SCONN,HA
M_K_DQ<26>               J9M1             45       SCONN288_H44441003_PIP-SCONN,HA
M_K_DQ<26>               U2D1             DP73     SKX_EXT_B_BGA1-IC,TBD
M_K_DQ<27>               J1B1             45       SCONN288_H44441004_PIP-SCONN,HA
M_K_DQ<27>               J9M1             190      SCONN288_H44441003_PIP-SCONN,HA
M_K_DQ<27>               U2D1             DT73     SKX_EXT_B_BGA1-IC,TBD
M_K_DQ<28>               J1B1             181      SCONN288_H44441004_PIP-SCONN,HA
M_K_DQ<28>               J9M1             36       SCONN288_H44441003_PIP-SCONN,HA
M_K_DQ<28>               U2D1             DP77     SKX_EXT_B_BGA1-IC,TBD
M_K_DQ<29>               J1B1             36       SCONN288_H44441004_PIP-SCONN,HA
M_K_DQ<29>               J9M1             181      SCONN288_H44441003_PIP-SCONN,HA
M_K_DQ<29>               U2D1             DT77     SKX_EXT_B_BGA1-IC,TBD
M_K_DQ<30>               J1B1             188      SCONN288_H44441004_PIP-SCONN,HA
M_K_DQ<30>               J9M1             43       SCONN288_H44441003_PIP-SCONN,HA
M_K_DQ<30>               U2D1             DN74     SKX_EXT_B_BGA1-IC,TBD
M_K_DQ<31>               J1B1             43       SCONN288_H44441004_PIP-SCONN,HA
M_K_DQ<31>               J9M1             188      SCONN288_H44441003_PIP-SCONN,HA
M_K_DQ<31>               U2D1             DU74     SKX_EXT_B_BGA1-IC,TBD
M_K_DQ<32>               J1B1             242      SCONN288_H44441004_PIP-SCONN,HA
M_K_DQ<32>               J9M1             97       SCONN288_H44441003_PIP-SCONN,HA
M_K_DQ<32>               U2D1             EC40     SKX_EXT_B_BGA1-IC,TBD
M_K_DQ<33>               J1B1             97       SCONN288_H44441004_PIP-SCONN,HA
M_K_DQ<33>               J9M1             242      SCONN288_H44441003_PIP-SCONN,HA
M_K_DQ<33>               U2D1             ED39     SKX_EXT_B_BGA1-IC,TBD
M_K_DQ<34>               J1B1             249      SCONN288_H44441004_PIP-SCONN,HA
M_K_DQ<34>               J9M1             104      SCONN288_H44441003_PIP-SCONN,HA
M_K_DQ<34>               U2D1             EA36     SKX_EXT_B_BGA1-IC,TBD
M_K_DQ<35>               J1B1             104      SCONN288_H44441004_PIP-SCONN,HA
M_K_DQ<35>               J9M1             249      SCONN288_H44441003_PIP-SCONN,HA
M_K_DQ<35>               U2D1             EC36     SKX_EXT_B_BGA1-IC,TBD
M_K_DQ<36>               J1B1             240      SCONN288_H44441004_PIP-SCONN,HA
M_K_DQ<36>               J9M1             95       SCONN288_H44441003_PIP-SCONN,HA
M_K_DQ<36>               U2D1             DY39     SKX_EXT_B_BGA1-IC,TBD
M_K_DQ<37>               J1B1             95       SCONN288_H44441004_PIP-SCONN,HA
M_K_DQ<37>               J9M1             240      SCONN288_H44441003_PIP-SCONN,HA
M_K_DQ<37>               U2D1             EA40     SKX_EXT_B_BGA1-IC,TBD
M_K_DQ<38>               J1B1             247      SCONN288_H44441004_PIP-SCONN,HA
M_K_DQ<38>               J9M1             102      SCONN288_H44441003_PIP-SCONN,HA
M_K_DQ<38>               U2D1             DY37     SKX_EXT_B_BGA1-IC,TBD
M_K_DQ<39>               J1B1             102      SCONN288_H44441004_PIP-SCONN,HA
M_K_DQ<39>               J9M1             247      SCONN288_H44441003_PIP-SCONN,HA
M_K_DQ<39>               U2D1             ED37     SKX_EXT_B_BGA1-IC,TBD
M_K_DQ<40>               J1B1             253      SCONN288_H44441004_PIP-SCONN,HA
M_K_DQ<40>               J9M1             108      SCONN288_H44441003_PIP-SCONN,HA
M_K_DQ<40>               U2D1             DN36     SKX_EXT_B_BGA1-IC,TBD
M_K_DQ<41>               J1B1             108      SCONN288_H44441004_PIP-SCONN,HA
M_K_DQ<41>               J9M1             253      SCONN288_H44441003_PIP-SCONN,HA
M_K_DQ<41>               U2D1             DU36     SKX_EXT_B_BGA1-IC,TBD
M_K_DQ<42>               J1B1             260      SCONN288_H44441004_PIP-SCONN,HA
M_K_DQ<42>               J9M1             115      SCONN288_H44441003_PIP-SCONN,HA
M_K_DQ<42>               U2D1             DP33     SKX_EXT_B_BGA1-IC,TBD
M_K_DQ<43>               J1B1             115      SCONN288_H44441004_PIP-SCONN,HA
M_K_DQ<43>               J9M1             260      SCONN288_H44441003_PIP-SCONN,HA
M_K_DQ<43>               U2D1             DT33     SKX_EXT_B_BGA1-IC,TBD
M_K_DQ<44>               J1B1             251      SCONN288_H44441004_PIP-SCONN,HA
M_K_DQ<44>               J9M1             106      SCONN288_H44441003_PIP-SCONN,HA
M_K_DQ<44>               U2D1             DP37     SKX_EXT_B_BGA1-IC,TBD
M_K_DQ<45>               J1B1             106      SCONN288_H44441004_PIP-SCONN,HA
M_K_DQ<45>               J9M1             251      SCONN288_H44441003_PIP-SCONN,HA
M_K_DQ<45>               U2D1             DT37     SKX_EXT_B_BGA1-IC,TBD
M_K_DQ<46>               J1B1             258      SCONN288_H44441004_PIP-SCONN,HA
M_K_DQ<46>               J9M1             113      SCONN288_H44441003_PIP-SCONN,HA
M_K_DQ<46>               U2D1             DN34     SKX_EXT_B_BGA1-IC,TBD
M_K_DQ<47>               J1B1             113      SCONN288_H44441004_PIP-SCONN,HA
M_K_DQ<47>               J9M1             258      SCONN288_H44441003_PIP-SCONN,HA
M_K_DQ<47>               U2D1             DU34     SKX_EXT_B_BGA1-IC,TBD
M_K_DQ<48>               J1B1             264      SCONN288_H44441004_PIP-SCONN,HA
M_K_DQ<48>               J9M1             119      SCONN288_H44441003_PIP-SCONN,HA
M_K_DQ<48>               U2D1             DN30     SKX_EXT_B_BGA1-IC,TBD
M_K_DQ<49>               J1B1             119      SCONN288_H44441004_PIP-SCONN,HA
M_K_DQ<49>               J9M1             264      SCONN288_H44441003_PIP-SCONN,HA
M_K_DQ<49>               U2D1             DU30     SKX_EXT_B_BGA1-IC,TBD
M_K_DQ<50>               J1B1             271      SCONN288_H44441004_PIP-SCONN,HA
M_K_DQ<50>               J9M1             126      SCONN288_H44441003_PIP-SCONN,HA
M_K_DQ<50>               U2D1             DP27     SKX_EXT_B_BGA1-IC,TBD
M_K_DQ<51>               J1B1             126      SCONN288_H44441004_PIP-SCONN,HA
M_K_DQ<51>               J9M1             271      SCONN288_H44441003_PIP-SCONN,HA
M_K_DQ<51>               U2D1             DT27     SKX_EXT_B_BGA1-IC,TBD
M_K_DQ<52>               J1B1             262      SCONN288_H44441004_PIP-SCONN,HA
M_K_DQ<52>               J9M1             117      SCONN288_H44441003_PIP-SCONN,HA
M_K_DQ<52>               U2D1             DP31     SKX_EXT_B_BGA1-IC,TBD
M_K_DQ<53>               J1B1             117      SCONN288_H44441004_PIP-SCONN,HA
M_K_DQ<53>               J9M1             262      SCONN288_H44441003_PIP-SCONN,HA
M_K_DQ<53>               U2D1             DT31     SKX_EXT_B_BGA1-IC,TBD
M_K_DQ<54>               J1B1             269      SCONN288_H44441004_PIP-SCONN,HA
M_K_DQ<54>               J9M1             124      SCONN288_H44441003_PIP-SCONN,HA
M_K_DQ<54>               U2D1             DN28     SKX_EXT_B_BGA1-IC,TBD
M_K_DQ<55>               J1B1             124      SCONN288_H44441004_PIP-SCONN,HA
M_K_DQ<55>               J9M1             269      SCONN288_H44441003_PIP-SCONN,HA
M_K_DQ<55>               U2D1             DU28     SKX_EXT_B_BGA1-IC,TBD
M_K_DQ<56>               J1B1             275      SCONN288_H44441004_PIP-SCONN,HA
M_K_DQ<56>               J9M1             130      SCONN288_H44441003_PIP-SCONN,HA
M_K_DQ<56>               U2D1             DN24     SKX_EXT_B_BGA1-IC,TBD
M_K_DQ<57>               J1B1             130      SCONN288_H44441004_PIP-SCONN,HA
M_K_DQ<57>               J9M1             275      SCONN288_H44441003_PIP-SCONN,HA
M_K_DQ<57>               U2D1             DU24     SKX_EXT_B_BGA1-IC,TBD
M_K_DQ<58>               J1B1             282      SCONN288_H44441004_PIP-SCONN,HA
M_K_DQ<58>               J9M1             137      SCONN288_H44441003_PIP-SCONN,HA
M_K_DQ<58>               U2D1             DY21     SKX_EXT_B_BGA1-IC,TBD
M_K_DQ<59>               J1B1             137      SCONN288_H44441004_PIP-SCONN,HA
M_K_DQ<59>               J9M1             282      SCONN288_H44441003_PIP-SCONN,HA
M_K_DQ<59>               U2D1             EB21     SKX_EXT_B_BGA1-IC,TBD
M_K_DQ<60>               J1B1             273      SCONN288_H44441004_PIP-SCONN,HA
M_K_DQ<60>               J9M1             128      SCONN288_H44441003_PIP-SCONN,HA
M_K_DQ<60>               U2D1             DP25     SKX_EXT_B_BGA1-IC,TBD
M_K_DQ<61>               J1B1             128      SCONN288_H44441004_PIP-SCONN,HA
M_K_DQ<61>               J9M1             273      SCONN288_H44441003_PIP-SCONN,HA
M_K_DQ<61>               U2D1             DT25     SKX_EXT_B_BGA1-IC,TBD
M_K_DQ<62>               J1B1             280      SCONN288_H44441004_PIP-SCONN,HA
M_K_DQ<62>               J9M1             135      SCONN288_H44441003_PIP-SCONN,HA
M_K_DQ<62>               U2D1             EC22     SKX_EXT_B_BGA1-IC,TBD
M_K_DQ<63>               J1B1             135      SCONN288_H44441004_PIP-SCONN,HA
M_K_DQ<63>               J9M1             280      SCONN288_H44441003_PIP-SCONN,HA
M_K_DQ<63>               U2D1             DW22     SKX_EXT_B_BGA1-IC,TBD
M_K_DQS_DN<0>            J1B1             152      SCONN288_H44441004_PIP-SCONN,HA
M_K_DQS_DN<0>            J9M1             152      SCONN288_H44441003_PIP-SCONN,HA
M_K_DQS_DN<0>            U2D1             CU84     SKX_EXT_B_BGA1-IC,TBD
M_K_DQS_DN<1>            J1B1             163      SCONN288_H44441004_PIP-SCONN,HA
M_K_DQS_DN<1>            J9M1             163      SCONN288_H44441003_PIP-SCONN,HA
M_K_DQS_DN<1>            U2D1             DN84     SKX_EXT_B_BGA1-IC,TBD
M_K_DQS_DN<2>            J1B1             174      SCONN288_H44441004_PIP-SCONN,HA
M_K_DQS_DN<2>            J9M1             174      SCONN288_H44441003_PIP-SCONN,HA
M_K_DQS_DN<2>            U2D1             DL82     SKX_EXT_B_BGA1-IC,TBD
M_K_DQS_DN<3>            J1B1             185      SCONN288_H44441004_PIP-SCONN,HA
M_K_DQS_DN<3>            J9M1             185      SCONN288_H44441003_PIP-SCONN,HA
M_K_DQS_DN<3>            U2D1             DV75     SKX_EXT_B_BGA1-IC,TBD
M_K_DQS_DN<4>            J1B1             244      SCONN288_H44441004_PIP-SCONN,HA
M_K_DQS_DN<4>            J9M1             244      SCONN288_H44441003_PIP-SCONN,HA
M_K_DQS_DN<4>            U2D1             EE38     SKX_EXT_B_BGA1-IC,TBD
M_K_DQS_DN<5>            J1B1             255      SCONN288_H44441004_PIP-SCONN,HA
M_K_DQS_DN<5>            J9M1             255      SCONN288_H44441003_PIP-SCONN,HA
M_K_DQS_DN<5>            U2D1             DV35     SKX_EXT_B_BGA1-IC,TBD
M_K_DQS_DN<6>            J1B1             266      SCONN288_H44441004_PIP-SCONN,HA
M_K_DQS_DN<6>            J9M1             266      SCONN288_H44441003_PIP-SCONN,HA
M_K_DQS_DN<6>            U2D1             DV29     SKX_EXT_B_BGA1-IC,TBD
M_K_DQS_DN<7>            J1B1             277      SCONN288_H44441004_PIP-SCONN,HA
M_K_DQS_DN<7>            J9M1             277      SCONN288_H44441003_PIP-SCONN,HA
M_K_DQS_DN<7>            U2D1             DV23     SKX_EXT_B_BGA1-IC,TBD
M_K_DQS_DN<8>            J1B1             196      SCONN288_H44441004_PIP-SCONN,HA
M_K_DQS_DN<8>            J9M1             196      SCONN288_H44441003_PIP-SCONN,HA
M_K_DQS_DN<8>            U2D1             DF67     SKX_EXT_B_BGA1-IC,TBD
M_K_DQS_DN<9>            J1B1             8        SCONN288_H44441004_PIP-SCONN,HA
M_K_DQS_DN<9>            J9M1             8        SCONN288_H44441003_PIP-SCONN,HA
M_K_DQS_DN<9>            U2D1             CR84     SKX_EXT_B_BGA1-IC,TBD
M_K_DQS_DN<10>           J1B1             19       SCONN288_H44441004_PIP-SCONN,HA
M_K_DQS_DN<10>           J9M1             19       SCONN288_H44441003_PIP-SCONN,HA
M_K_DQS_DN<10>           U2D1             DM85     SKX_EXT_B_BGA1-IC,TBD
M_K_DQS_DN<11>           J1B1             30       SCONN288_H44441004_PIP-SCONN,HA
M_K_DQS_DN<11>           J9M1             30       SCONN288_H44441003_PIP-SCONN,HA
M_K_DQS_DN<11>           U2D1             DN80     SKX_EXT_B_BGA1-IC,TBD
M_K_DQS_DN<12>           J1B1             41       SCONN288_H44441004_PIP-SCONN,HA
M_K_DQS_DN<12>           J9M1             41       SCONN288_H44441003_PIP-SCONN,HA
M_K_DQS_DN<12>           U2D1             DP75     SKX_EXT_B_BGA1-IC,TBD
M_K_DQS_DN<13>           J1B1             100      SCONN288_H44441004_PIP-SCONN,HA
M_K_DQS_DN<13>           J9M1             100      SCONN288_H44441003_PIP-SCONN,HA
M_K_DQS_DN<13>           U2D1             EA38     SKX_EXT_B_BGA1-IC,TBD
M_K_DQS_DN<14>           J1B1             111      SCONN288_H44441004_PIP-SCONN,HA
M_K_DQS_DN<14>           J9M1             111      SCONN288_H44441003_PIP-SCONN,HA
M_K_DQS_DN<14>           U2D1             DP35     SKX_EXT_B_BGA1-IC,TBD
M_K_DQS_DN<15>           J1B1             122      SCONN288_H44441004_PIP-SCONN,HA
M_K_DQS_DN<15>           J9M1             122      SCONN288_H44441003_PIP-SCONN,HA
M_K_DQS_DN<15>           U2D1             DM29     SKX_EXT_B_BGA1-IC,TBD
M_K_DQS_DN<16>           J1B1             133      SCONN288_H44441004_PIP-SCONN,HA
M_K_DQS_DN<16>           J9M1             133      SCONN288_H44441003_PIP-SCONN,HA
M_K_DQS_DN<16>           U2D1             DM23     SKX_EXT_B_BGA1-IC,TBD
M_K_DQS_DN<17>           J1B1             52       SCONN288_H44441004_PIP-SCONN,HA
M_K_DQS_DN<17>           J9M1             52       SCONN288_H44441003_PIP-SCONN,HA
M_K_DQS_DN<17>           U2D1             DB67     SKX_EXT_B_BGA1-IC,TBD
M_K_DQS_DP<0>            J1B1             153      SCONN288_H44441004_PIP-SCONN,HA
M_K_DQS_DP<0>            J9M1             153      SCONN288_H44441003_PIP-SCONN,HA
M_K_DQS_DP<0>            U2D1             CV85     SKX_EXT_B_BGA1-IC,TBD
M_K_DQS_DP<1>            J1B1             164      SCONN288_H44441004_PIP-SCONN,HA
M_K_DQS_DP<1>            J9M1             164      SCONN288_H44441003_PIP-SCONN,HA
M_K_DQS_DP<1>            U2D1             DP85     SKX_EXT_B_BGA1-IC,TBD
M_K_DQS_DP<2>            J1B1             175      SCONN288_H44441004_PIP-SCONN,HA
M_K_DQS_DP<2>            J9M1             175      SCONN288_H44441003_PIP-SCONN,HA
M_K_DQS_DP<2>            U2D1             DM81     SKX_EXT_B_BGA1-IC,TBD
M_K_DQS_DP<3>            J1B1             186      SCONN288_H44441004_PIP-SCONN,HA
M_K_DQS_DP<3>            J9M1             186      SCONN288_H44441003_PIP-SCONN,HA
M_K_DQS_DP<3>            U2D1             DT75     SKX_EXT_B_BGA1-IC,TBD
M_K_DQS_DP<4>            J1B1             245      SCONN288_H44441004_PIP-SCONN,HA
M_K_DQS_DP<4>            J9M1             245      SCONN288_H44441003_PIP-SCONN,HA
M_K_DQS_DP<4>            U2D1             EC38     SKX_EXT_B_BGA1-IC,TBD
M_K_DQS_DP<5>            J1B1             256      SCONN288_H44441004_PIP-SCONN,HA
M_K_DQS_DP<5>            J9M1             256      SCONN288_H44441003_PIP-SCONN,HA
M_K_DQS_DP<5>            U2D1             DT35     SKX_EXT_B_BGA1-IC,TBD
M_K_DQS_DP<6>            J1B1             267      SCONN288_H44441004_PIP-SCONN,HA
M_K_DQS_DP<6>            J9M1             267      SCONN288_H44441003_PIP-SCONN,HA
M_K_DQS_DP<6>            U2D1             DT29     SKX_EXT_B_BGA1-IC,TBD
M_K_DQS_DP<7>            J1B1             278      SCONN288_H44441004_PIP-SCONN,HA
M_K_DQS_DP<7>            J9M1             278      SCONN288_H44441003_PIP-SCONN,HA
M_K_DQS_DP<7>            U2D1             DT23     SKX_EXT_B_BGA1-IC,TBD
M_K_DQS_DP<8>            J1B1             197      SCONN288_H44441004_PIP-SCONN,HA
M_K_DQS_DP<8>            J9M1             197      SCONN288_H44441003_PIP-SCONN,HA
M_K_DQS_DP<8>            U2D1             DD67     SKX_EXT_B_BGA1-IC,TBD
M_K_DQS_DP<9>            J1B1             7        SCONN288_H44441004_PIP-SCONN,HA
M_K_DQS_DP<9>            J9M1             7        SCONN288_H44441003_PIP-SCONN,HA
M_K_DQS_DP<9>            U2D1             CP85     SKX_EXT_B_BGA1-IC,TBD
M_K_DQS_DP<10>           J1B1             18       SCONN288_H44441004_PIP-SCONN,HA
M_K_DQS_DP<10>           J9M1             18       SCONN288_H44441003_PIP-SCONN,HA
M_K_DQS_DP<10>           U2D1             DL84     SKX_EXT_B_BGA1-IC,TBD
M_K_DQS_DP<11>           J1B1             29       SCONN288_H44441004_PIP-SCONN,HA
M_K_DQS_DP<11>           J9M1             29       SCONN288_H44441003_PIP-SCONN,HA
M_K_DQS_DP<11>           U2D1             DP79     SKX_EXT_B_BGA1-IC,TBD
M_K_DQS_DP<12>           J1B1             40       SCONN288_H44441004_PIP-SCONN,HA
M_K_DQS_DP<12>           J9M1             40       SCONN288_H44441003_PIP-SCONN,HA
M_K_DQS_DP<12>           U2D1             DM75     SKX_EXT_B_BGA1-IC,TBD
M_K_DQS_DP<13>           J1B1             99       SCONN288_H44441004_PIP-SCONN,HA
M_K_DQS_DP<13>           J9M1             99       SCONN288_H44441003_PIP-SCONN,HA
M_K_DQS_DP<13>           U2D1             DW38     SKX_EXT_B_BGA1-IC,TBD
M_K_DQS_DP<14>           J1B1             110      SCONN288_H44441004_PIP-SCONN,HA
M_K_DQS_DP<14>           J9M1             110      SCONN288_H44441003_PIP-SCONN,HA
M_K_DQS_DP<14>           U2D1             DM35     SKX_EXT_B_BGA1-IC,TBD
M_K_DQS_DP<15>           J1B1             121      SCONN288_H44441004_PIP-SCONN,HA
M_K_DQS_DP<15>           J9M1             121      SCONN288_H44441003_PIP-SCONN,HA
M_K_DQS_DP<15>           U2D1             DP29     SKX_EXT_B_BGA1-IC,TBD
M_K_DQS_DP<16>           J1B1             132      SCONN288_H44441004_PIP-SCONN,HA
M_K_DQS_DP<16>           J9M1             132      SCONN288_H44441003_PIP-SCONN,HA
M_K_DQS_DP<16>           U2D1             DP23     SKX_EXT_B_BGA1-IC,TBD
M_K_DQS_DP<17>           J1B1             51       SCONN288_H44441004_PIP-SCONN,HA
M_K_DQS_DP<17>           J9M1             51       SCONN288_H44441003_PIP-SCONN,HA
M_K_DQS_DP<17>           U2D1             CY67     SKX_EXT_B_BGA1-IC,TBD
M_K_ECC<0>               J1B1             194      SCONN288_H44441004_PIP-SCONN,HA
M_K_ECC<0>               J9M1             49       SCONN288_H44441003_PIP-SCONN,HA
M_K_ECC<0>               U2D1             DA68     SKX_EXT_B_BGA1-IC,TBD
M_K_ECC<1>               J1B1             49       SCONN288_H44441004_PIP-SCONN,HA
M_K_ECC<1>               J9M1             194      SCONN288_H44441003_PIP-SCONN,HA
M_K_ECC<1>               U2D1             DE68     SKX_EXT_B_BGA1-IC,TBD
M_K_ECC<2>               J1B1             201      SCONN288_H44441004_PIP-SCONN,HA
M_K_ECC<2>               J9M1             56       SCONN288_H44441003_PIP-SCONN,HA
M_K_ECC<2>               U2D1             DB65     SKX_EXT_B_BGA1-IC,TBD
M_K_ECC<3>               J1B1             56       SCONN288_H44441004_PIP-SCONN,HA
M_K_ECC<3>               J9M1             201      SCONN288_H44441003_PIP-SCONN,HA
M_K_ECC<3>               U2D1             DD65     SKX_EXT_B_BGA1-IC,TBD
M_K_ECC<4>               J1B1             192      SCONN288_H44441004_PIP-SCONN,HA
M_K_ECC<4>               J9M1             47       SCONN288_H44441003_PIP-SCONN,HA
M_K_ECC<4>               U2D1             DB69     SKX_EXT_B_BGA1-IC,TBD
M_K_ECC<5>               J1B1             47       SCONN288_H44441004_PIP-SCONN,HA
M_K_ECC<5>               J9M1             192      SCONN288_H44441003_PIP-SCONN,HA
M_K_ECC<5>               U2D1             DD69     SKX_EXT_B_BGA1-IC,TBD
M_K_ECC<6>               J1B1             199      SCONN288_H44441004_PIP-SCONN,HA
M_K_ECC<6>               J9M1             54       SCONN288_H44441003_PIP-SCONN,HA
M_K_ECC<6>               U2D1             DA66     SKX_EXT_B_BGA1-IC,TBD
M_K_ECC<7>               J1B1             54       SCONN288_H44441004_PIP-SCONN,HA
M_K_ECC<7>               J9M1             199      SCONN288_H44441003_PIP-SCONN,HA
M_K_ECC<7>               U2D1             DE66     SKX_EXT_B_BGA1-IC,TBD
M_K_MA<0>                J1B1             79       SCONN288_H44441004_PIP-SCONN,HA
M_K_MA<0>                J9M1             79       SCONN288_H44441003_PIP-SCONN,HA
M_K_MA<0>                U2D1             EB53     SKX_EXT_B_BGA1-IC,TBD
M_K_MA<1>                J1B1             72       SCONN288_H44441004_PIP-SCONN,HA
M_K_MA<1>                J9M1             72       SCONN288_H44441003_PIP-SCONN,HA
M_K_MA<1>                U2D1             ED57     SKX_EXT_B_BGA1-IC,TBD
M_K_MA<2>                J1B1             216      SCONN288_H44441004_PIP-SCONN,HA
M_K_MA<2>                J9M1             216      SCONN288_H44441003_PIP-SCONN,HA
M_K_MA<2>                U2D1             EE58     SKX_EXT_B_BGA1-IC,TBD
M_K_MA<3>                J1B1             71       SCONN288_H44441004_PIP-SCONN,HA
M_K_MA<3>                J9M1             71       SCONN288_H44441003_PIP-SCONN,HA
M_K_MA<3>                U2D1             EB57     SKX_EXT_B_BGA1-IC,TBD
M_K_MA<4>                J1B1             214      SCONN288_H44441004_PIP-SCONN,HA
M_K_MA<4>                J9M1             214      SCONN288_H44441003_PIP-SCONN,HA
M_K_MA<4>                U2D1             ED59     SKX_EXT_B_BGA1-IC,TBD
M_K_MA<5>                J1B1             213      SCONN288_H44441004_PIP-SCONN,HA
M_K_MA<5>                J9M1             213      SCONN288_H44441003_PIP-SCONN,HA
M_K_MA<5>                U2D1             EA58     SKX_EXT_B_BGA1-IC,TBD
M_K_MA<6>                J1B1             69       SCONN288_H44441004_PIP-SCONN,HA
M_K_MA<6>                J9M1             69       SCONN288_H44441003_PIP-SCONN,HA
M_K_MA<6>                U2D1             EE60     SKX_EXT_B_BGA1-IC,TBD
M_K_MA<7>                J1B1             211      SCONN288_H44441004_PIP-SCONN,HA
M_K_MA<7>                J9M1             211      SCONN288_H44441003_PIP-SCONN,HA
M_K_MA<7>                U2D1             EA60     SKX_EXT_B_BGA1-IC,TBD
M_K_MA<8>                J1B1             68       SCONN288_H44441004_PIP-SCONN,HA
M_K_MA<8>                J9M1             68       SCONN288_H44441003_PIP-SCONN,HA
M_K_MA<8>                U2D1             EB59     SKX_EXT_B_BGA1-IC,TBD
M_K_MA<9>                J1B1             66       SCONN288_H44441004_PIP-SCONN,HA
M_K_MA<9>                J9M1             66       SCONN288_H44441003_PIP-SCONN,HA
M_K_MA<9>                U2D1             EF61     SKX_EXT_B_BGA1-IC,TBD
M_K_MA<10>               J1B1             225      SCONN288_H44441004_PIP-SCONN,HA
M_K_MA<10>               J9M1             225      SCONN288_H44441003_PIP-SCONN,HA
M_K_MA<10>               U2D1             DW54     SKX_EXT_B_BGA1-IC,TBD
M_K_MA<11>               J1B1             210      SCONN288_H44441004_PIP-SCONN,HA
M_K_MA<11>               J9M1             210      SCONN288_H44441003_PIP-SCONN,HA
M_K_MA<11>               U2D1             EB61     SKX_EXT_B_BGA1-IC,TBD
M_K_MA<12>               J1B1             65       SCONN288_H44441004_PIP-SCONN,HA
M_K_MA<12>               J9M1             65       SCONN288_H44441003_PIP-SCONN,HA
M_K_MA<12>               U2D1             DT63     SKX_EXT_B_BGA1-IC,TBD
M_K_MA<13>               J1B1             232      SCONN288_H44441004_PIP-SCONN,HA
M_K_MA<13>               J9M1             232      SCONN288_H44441003_PIP-SCONN,HA
M_K_MA<13>               U2D1             DW48     SKX_EXT_B_BGA1-IC,TBD
M_K_MA<14>               J1B1             228      SCONN288_H44441004_PIP-SCONN,HA
M_K_MA<14>               J9M1             228      SCONN288_H44441003_PIP-SCONN,HA
M_K_MA<14>               U2D1             ED51     SKX_EXT_B_BGA1-IC,TBD
M_K_MA<15>               J1B1             86       SCONN288_H44441004_PIP-SCONN,HA
M_K_MA<15>               J9M1             86       SCONN288_H44441003_PIP-SCONN,HA
M_K_MA<15>               U2D1             DV49     SKX_EXT_B_BGA1-IC,TBD
M_K_MA<16>               J1B1             82       SCONN288_H44441004_PIP-SCONN,HA
M_K_MA<16>               J9M1             82       SCONN288_H44441003_PIP-SCONN,HA
M_K_MA<16>               U2D1             EA52     SKX_EXT_B_BGA1-IC,TBD
M_K_MA<17>               J1B1             234      SCONN288_H44441004_PIP-SCONN,HA
M_K_MA<17>               J9M1             234      SCONN288_H44441003_PIP-SCONN,HA
M_K_MA<17>               U2D1             EA46     SKX_EXT_B_BGA1-IC,TBD
M_K_ODT<0>               J1B1             87       SCONN288_H44441004_PIP-SCONN,HA
M_K_ODT<0>               U2D1             EE50     SKX_EXT_B_BGA1-IC,TBD
M_K_ODT<1>               J1B1             91       SCONN288_H44441004_PIP-SCONN,HA
M_K_ODT<1>               U2D1             EE48     SKX_EXT_B_BGA1-IC,TBD
M_K_ODT<2>               J9M1             87       SCONN288_H44441003_PIP-SCONN,HA
M_K_ODT<2>               U2D1             EA50     SKX_EXT_B_BGA1-IC,TBD
M_K_ODT<3>               J9M1             91       SCONN288_H44441003_PIP-SCONN,HA
M_K_ODT<3>               U2D1             EA48     SKX_EXT_B_BGA1-IC,TBD
M_K_PAR                  J1B1             222      SCONN288_H44441004_PIP-SCONN,HA
M_K_PAR                  J9M1             222      SCONN288_H44441003_PIP-SCONN,HA
M_K_PAR                  U2D1             ED53     SKX_EXT_B_BGA1-IC,TBD
M_K_VREF                 C1B9             1        CAP_A_0402V-0.01UF,25V,10%,X7RA
M_K_VREF                 C9M1             1        CAP_A_0402V-0.01UF,25V,10%,X7RA
M_K_VREF                 J1B1             146      SCONN288_H44441004_PIP-SCONN,HA
M_K_VREF                 J9M1             146      SCONN288_H44441003_PIP-SCONN,HA
M_K_VREF                 R9L11            1        RES_0402-1.00K,1%,1/16W,CHIP,GA
M_K_VREF                 R9M1             2        RES_0402-1.00K,1%,1/16W,CHIP,GA
M_K_VREF                 R9M2             2        RES_0402-2,1.0%,1/16W,CHIP,G21A
M_L_ACT_N                J1A2             62       SCONN288_H44441004_PIP-SCONN,HA
M_L_ACT_N                J9L2             62       SCONN288_H44441003_PIP-SCONN,HA
M_L_ACT_N                U2D1             DR62     SKX_EXT_B_BGA1-IC,TBD
M_L_ALERT_N              J1A2             208      SCONN288_H44441004_PIP-SCONN,HA
M_L_ALERT_N              J9L2             208      SCONN288_H44441003_PIP-SCONN,HA
M_L_ALERT_N              U2D1             DT61     SKX_EXT_B_BGA1-IC,TBD
M_L_BA<0>                J1A2             81       SCONN288_H44441004_PIP-SCONN,HA
M_L_BA<0>                J9L2             81       SCONN288_H44441003_PIP-SCONN,HA
M_L_BA<0>                U2D1             DM53     SKX_EXT_B_BGA1-IC,TBD
M_L_BA<1>                J1A2             224      SCONN288_H44441004_PIP-SCONN,HA
M_L_BA<1>                J9L2             224      SCONN288_H44441003_PIP-SCONN,HA
M_L_BA<1>                U2D1             DV55     SKX_EXT_B_BGA1-IC,TBD
M_L_BG<0>                J1A2             63       SCONN288_H44441004_PIP-SCONN,HA
M_L_BG<0>                J9L2             63       SCONN288_H44441003_PIP-SCONN,HA
M_L_BG<0>                U2D1             DJ62     SKX_EXT_B_BGA1-IC,TBD
M_L_BG<1>                J1A2             207      SCONN288_H44441004_PIP-SCONN,HA
M_L_BG<1>                J9L2             207      SCONN288_H44441003_PIP-SCONN,HA
M_L_BG<1>                U2D1             DM61     SKX_EXT_B_BGA1-IC,TBD
M_L_C<2>                 J1A2             235      SCONN288_H44441004_PIP-SCONN,HA
M_L_C<2>                 J9L2             235      SCONN288_H44441003_PIP-SCONN,HA
M_L_C<2>                 U2D1             DT47     SKX_EXT_B_BGA1-IC,TBD
M_L_CKE<0>               J1A2             60       SCONN288_H44441004_PIP-SCONN,HA
M_L_CKE<0>               U2D1             DM63     SKX_EXT_B_BGA1-IC,TBD
M_L_CKE<1>               J1A2             203      SCONN288_H44441004_PIP-SCONN,HA
M_L_CKE<1>               U2D1             DN64     SKX_EXT_B_BGA1-IC,TBD
M_L_CKE<2>               J9L2             60       SCONN288_H44441003_PIP-SCONN,HA
M_L_CKE<2>               U2D1             DL64     SKX_EXT_B_BGA1-IC,TBD
M_L_CKE<3>               J9L2             203      SCONN288_H44441003_PIP-SCONN,HA
M_L_CKE<3>               U2D1             DR64     SKX_EXT_B_BGA1-IC,TBD
M_L_CLK_DN<0>            J1A2             75       SCONN288_H44441004_PIP-SCONN,HA
M_L_CLK_DN<0>            U2D1             DM55     SKX_EXT_B_BGA1-IC,TBD
M_L_CLK_DN<1>            J1A2             219      SCONN288_H44441004_PIP-SCONN,HA
M_L_CLK_DN<1>            U2D1             DR54     SKX_EXT_B_BGA1-IC,TBD
M_L_CLK_DN<2>            J9L2             75       SCONN288_H44441003_PIP-SCONN,HA
M_L_CLK_DN<2>            U2D1             DM57     SKX_EXT_B_BGA1-IC,TBD
M_L_CLK_DN<3>            J9L2             219      SCONN288_H44441003_PIP-SCONN,HA
M_L_CLK_DN<3>            U2D1             DT57     SKX_EXT_B_BGA1-IC,TBD
M_L_CLK_DP<0>            J1A2             74       SCONN288_H44441004_PIP-SCONN,HA
M_L_CLK_DP<0>            U2D1             DN54     SKX_EXT_B_BGA1-IC,TBD
M_L_CLK_DP<1>            J1A2             218      SCONN288_H44441004_PIP-SCONN,HA
M_L_CLK_DP<1>            U2D1             DT53     SKX_EXT_B_BGA1-IC,TBD
M_L_CLK_DP<2>            J9L2             74       SCONN288_H44441003_PIP-SCONN,HA
M_L_CLK_DP<2>            U2D1             DN56     SKX_EXT_B_BGA1-IC,TBD
M_L_CLK_DP<3>            J9L2             218      SCONN288_H44441003_PIP-SCONN,HA
M_L_CLK_DP<3>            U2D1             DR56     SKX_EXT_B_BGA1-IC,TBD
M_L_CPU_VREF             C9L8             1        CAP_A_0402V-0.01UF,25V,10%,X7RA
M_L_CPU_VREF             R9L8             1        RES_0402-2,1.0%,1/16W,CHIP,G21A
M_L_CPU_VREF             U2D1             CT61     SKX_EXT_B_BGA1-IC,TBD
M_L_CS_N<0>              J1A2             84       SCONN288_H44441004_PIP-SCONN,HA
M_L_CS_N<0>              U2D1             DV51     SKX_EXT_B_BGA1-IC,TBD
M_L_CS_N<1>              J1A2             89       SCONN288_H44441004_PIP-SCONN,HA
M_L_CS_N<1>              U2D1             DN50     SKX_EXT_B_BGA1-IC,TBD
M_L_CS_N<2>              J1A2             93       SCONN288_H44441004_PIP-SCONN,HA
M_L_CS_N<2>              U2D1             DR46     SKX_EXT_B_BGA1-IC,TBD
M_L_CS_N<3>              J1A2             237      SCONN288_H44441004_PIP-SCONN,HA
M_L_CS_N<3>              U2D1             DK47     SKX_EXT_B_BGA1-IC,TBD
M_L_CS_N<4>              J9L2             84       SCONN288_H44441003_PIP-SCONN,HA
M_L_CS_N<4>              U2D1             DW50     SKX_EXT_B_BGA1-IC,TBD
M_L_CS_N<5>              J9L2             89       SCONN288_H44441003_PIP-SCONN,HA
M_L_CS_N<5>              U2D1             DM49     SKX_EXT_B_BGA1-IC,TBD
M_L_CS_N<6>              J9L2             93       SCONN288_H44441003_PIP-SCONN,HA
M_L_CS_N<6>              U2D1             DT45     SKX_EXT_B_BGA1-IC,TBD
M_L_CS_N<7>              J9L2             237      SCONN288_H44441003_PIP-SCONN,HA
M_L_CS_N<7>              U2D1             DN46     SKX_EXT_B_BGA1-IC,TBD
M_L_DQ<0>                J1A2             150      SCONN288_H44441004_PIP-SCONN,HA
M_L_DQ<0>                J9L2             5        SCONN288_H44441003_PIP-SCONN,HA
M_L_DQ<0>                U2D1             CM79     SKX_EXT_B_BGA1-IC,TBD
M_L_DQ<1>                J1A2             5        SCONN288_H44441004_PIP-SCONN,HA
M_L_DQ<1>                J9L2             150      SCONN288_H44441003_PIP-SCONN,HA
M_L_DQ<1>                U2D1             CK81     SKX_EXT_B_BGA1-IC,TBD
M_L_DQ<2>                J1A2             157      SCONN288_H44441004_PIP-SCONN,HA
M_L_DQ<2>                J9L2             12       SCONN288_H44441003_PIP-SCONN,HA
M_L_DQ<2>                U2D1             CT81     SKX_EXT_B_BGA1-IC,TBD
M_L_DQ<3>                J1A2             12       SCONN288_H44441004_PIP-SCONN,HA
M_L_DQ<3>                J9L2             157      SCONN288_H44441003_PIP-SCONN,HA
M_L_DQ<3>                U2D1             CR82     SKX_EXT_B_BGA1-IC,TBD
M_L_DQ<4>                J1A2             148      SCONN288_H44441004_PIP-SCONN,HA
M_L_DQ<4>                J9L2             3        SCONN288_H44441003_PIP-SCONN,HA
M_L_DQ<4>                U2D1             CK79     SKX_EXT_B_BGA1-IC,TBD
M_L_DQ<5>                J1A2             3        SCONN288_H44441004_PIP-SCONN,HA
M_L_DQ<5>                J9L2             148      SCONN288_H44441003_PIP-SCONN,HA
M_L_DQ<5>                U2D1             CJ80     SKX_EXT_B_BGA1-IC,TBD
M_L_DQ<6>                J1A2             155      SCONN288_H44441004_PIP-SCONN,HA
M_L_DQ<6>                J9L2             10       SCONN288_H44441003_PIP-SCONN,HA
M_L_DQ<6>                U2D1             CR80     SKX_EXT_B_BGA1-IC,TBD
M_L_DQ<7>                J1A2             10       SCONN288_H44441004_PIP-SCONN,HA
M_L_DQ<7>                J9L2             155      SCONN288_H44441003_PIP-SCONN,HA
M_L_DQ<7>                U2D1             CN82     SKX_EXT_B_BGA1-IC,TBD
M_L_DQ<8>                J1A2             161      SCONN288_H44441004_PIP-SCONN,HA
M_L_DQ<8>                J9L2             16       SCONN288_H44441003_PIP-SCONN,HA
M_L_DQ<8>                U2D1             DB79     SKX_EXT_B_BGA1-IC,TBD
M_L_DQ<9>                J1A2             16       SCONN288_H44441004_PIP-SCONN,HA
M_L_DQ<9>                J9L2             161      SCONN288_H44441003_PIP-SCONN,HA
M_L_DQ<9>                U2D1             CY81     SKX_EXT_B_BGA1-IC,TBD
M_L_DQ<10>               J1A2             168      SCONN288_H44441004_PIP-SCONN,HA
M_L_DQ<10>               J9L2             23       SCONN288_H44441003_PIP-SCONN,HA
M_L_DQ<10>               U2D1             DE80     SKX_EXT_B_BGA1-IC,TBD
M_L_DQ<11>               J1A2             23       SCONN288_H44441004_PIP-SCONN,HA
M_L_DQ<11>               J9L2             168      SCONN288_H44441003_PIP-SCONN,HA
M_L_DQ<11>               U2D1             DF81     SKX_EXT_B_BGA1-IC,TBD
M_L_DQ<12>               J1A2             159      SCONN288_H44441004_PIP-SCONN,HA
M_L_DQ<12>               J9L2             14       SCONN288_H44441003_PIP-SCONN,HA
M_L_DQ<12>               U2D1             CY79     SKX_EXT_B_BGA1-IC,TBD
M_L_DQ<13>               J1A2             14       SCONN288_H44441004_PIP-SCONN,HA
M_L_DQ<13>               J9L2             159      SCONN288_H44441003_PIP-SCONN,HA
M_L_DQ<13>               U2D1             CW80     SKX_EXT_B_BGA1-IC,TBD
M_L_DQ<14>               J1A2             166      SCONN288_H44441004_PIP-SCONN,HA
M_L_DQ<14>               J9L2             21       SCONN288_H44441003_PIP-SCONN,HA
M_L_DQ<14>               U2D1             DC82     SKX_EXT_B_BGA1-IC,TBD
M_L_DQ<15>               J1A2             21       SCONN288_H44441004_PIP-SCONN,HA
M_L_DQ<15>               J9L2             166      SCONN288_H44441003_PIP-SCONN,HA
M_L_DQ<15>               U2D1             DE82     SKX_EXT_B_BGA1-IC,TBD
M_L_DQ<16>               J1A2             172      SCONN288_H44441004_PIP-SCONN,HA
M_L_DQ<16>               J9L2             27       SCONN288_H44441003_PIP-SCONN,HA
M_L_DQ<16>               U2D1             DW80     SKX_EXT_B_BGA1-IC,TBD
M_L_DQ<17>               J1A2             27       SCONN288_H44441004_PIP-SCONN,HA
M_L_DQ<17>               J9L2             172      SCONN288_H44441003_PIP-SCONN,HA
M_L_DQ<17>               U2D1             EC80     SKX_EXT_B_BGA1-IC,TBD
M_L_DQ<18>               J1A2             179      SCONN288_H44441004_PIP-SCONN,HA
M_L_DQ<18>               J9L2             34       SCONN288_H44441003_PIP-SCONN,HA
M_L_DQ<18>               U2D1             DY77     SKX_EXT_B_BGA1-IC,TBD
M_L_DQ<19>               J1A2             34       SCONN288_H44441004_PIP-SCONN,HA
M_L_DQ<19>               J9L2             179      SCONN288_H44441003_PIP-SCONN,HA
M_L_DQ<19>               U2D1             EB77     SKX_EXT_B_BGA1-IC,TBD
M_L_DQ<20>               J1A2             170      SCONN288_H44441004_PIP-SCONN,HA
M_L_DQ<20>               J9L2             25       SCONN288_H44441003_PIP-SCONN,HA
M_L_DQ<20>               U2D1             DY81     SKX_EXT_B_BGA1-IC,TBD
M_L_DQ<21>               J1A2             25       SCONN288_H44441004_PIP-SCONN,HA
M_L_DQ<21>               J9L2             170      SCONN288_H44441003_PIP-SCONN,HA
M_L_DQ<21>               U2D1             EB81     SKX_EXT_B_BGA1-IC,TBD
M_L_DQ<22>               J1A2             177      SCONN288_H44441004_PIP-SCONN,HA
M_L_DQ<22>               J9L2             32       SCONN288_H44441003_PIP-SCONN,HA
M_L_DQ<22>               U2D1             DW78     SKX_EXT_B_BGA1-IC,TBD
M_L_DQ<23>               J1A2             32       SCONN288_H44441004_PIP-SCONN,HA
M_L_DQ<23>               J9L2             177      SCONN288_H44441003_PIP-SCONN,HA
M_L_DQ<23>               U2D1             EC78     SKX_EXT_B_BGA1-IC,TBD
M_L_DQ<24>               J1A2             183      SCONN288_H44441004_PIP-SCONN,HA
M_L_DQ<24>               J9L2             38       SCONN288_H44441003_PIP-SCONN,HA
M_L_DQ<24>               U2D1             ED75     SKX_EXT_B_BGA1-IC,TBD
M_L_DQ<25>               J1A2             38       SCONN288_H44441004_PIP-SCONN,HA
M_L_DQ<25>               J9L2             183      SCONN288_H44441003_PIP-SCONN,HA
M_L_DQ<25>               U2D1             EE74     SKX_EXT_B_BGA1-IC,TBD
M_L_DQ<26>               J1A2             190      SCONN288_H44441004_PIP-SCONN,HA
M_L_DQ<26>               J9L2             45       SCONN288_H44441003_PIP-SCONN,HA
M_L_DQ<26>               U2D1             EB71     SKX_EXT_B_BGA1-IC,TBD
M_L_DQ<27>               J1A2             45       SCONN288_H44441004_PIP-SCONN,HA
M_L_DQ<27>               J9L2             190      SCONN288_H44441003_PIP-SCONN,HA
M_L_DQ<27>               U2D1             ED71     SKX_EXT_B_BGA1-IC,TBD
M_L_DQ<28>               J1A2             181      SCONN288_H44441004_PIP-SCONN,HA
M_L_DQ<28>               J9L2             36       SCONN288_H44441003_PIP-SCONN,HA
M_L_DQ<28>               U2D1             EA74     SKX_EXT_B_BGA1-IC,TBD
M_L_DQ<29>               J1A2             36       SCONN288_H44441004_PIP-SCONN,HA
M_L_DQ<29>               J9L2             181      SCONN288_H44441003_PIP-SCONN,HA
M_L_DQ<29>               U2D1             EB75     SKX_EXT_B_BGA1-IC,TBD
M_L_DQ<30>               J1A2             188      SCONN288_H44441004_PIP-SCONN,HA
M_L_DQ<30>               J9L2             43       SCONN288_H44441003_PIP-SCONN,HA
M_L_DQ<30>               U2D1             EA72     SKX_EXT_B_BGA1-IC,TBD
M_L_DQ<31>               J1A2             43       SCONN288_H44441004_PIP-SCONN,HA
M_L_DQ<31>               J9L2             188      SCONN288_H44441003_PIP-SCONN,HA
M_L_DQ<31>               U2D1             EE72     SKX_EXT_B_BGA1-IC,TBD
M_L_DQ<32>               J1A2             242      SCONN288_H44441004_PIP-SCONN,HA
M_L_DQ<32>               J9L2             97       SCONN288_H44441003_PIP-SCONN,HA
M_L_DQ<32>               U2D1             DU42     SKX_EXT_B_BGA1-IC,TBD
M_L_DQ<33>               J1A2             97       SCONN288_H44441004_PIP-SCONN,HA
M_L_DQ<33>               J9L2             242      SCONN288_H44441003_PIP-SCONN,HA
M_L_DQ<33>               U2D1             DW42     SKX_EXT_B_BGA1-IC,TBD
M_L_DQ<34>               J1A2             249      SCONN288_H44441004_PIP-SCONN,HA
M_L_DQ<34>               J9L2             104      SCONN288_H44441003_PIP-SCONN,HA
M_L_DQ<34>               U2D1             DP39     SKX_EXT_B_BGA1-IC,TBD
M_L_DQ<35>               J1A2             104      SCONN288_H44441004_PIP-SCONN,HA
M_L_DQ<35>               J9L2             249      SCONN288_H44441003_PIP-SCONN,HA
M_L_DQ<35>               U2D1             DT39     SKX_EXT_B_BGA1-IC,TBD
M_L_DQ<36>               J1A2             240      SCONN288_H44441004_PIP-SCONN,HA
M_L_DQ<36>               J9L2             95       SCONN288_H44441003_PIP-SCONN,HA
M_L_DQ<36>               U2D1             DL42     SKX_EXT_B_BGA1-IC,TBD
M_L_DQ<37>               J1A2             95       SCONN288_H44441004_PIP-SCONN,HA
M_L_DQ<37>               J9L2             240      SCONN288_H44441003_PIP-SCONN,HA
M_L_DQ<37>               U2D1             DN42     SKX_EXT_B_BGA1-IC,TBD
M_L_DQ<38>               J1A2             247      SCONN288_H44441004_PIP-SCONN,HA
M_L_DQ<38>               J9L2             102      SCONN288_H44441003_PIP-SCONN,HA
M_L_DQ<38>               U2D1             DN40     SKX_EXT_B_BGA1-IC,TBD
M_L_DQ<39>               J1A2             102      SCONN288_H44441004_PIP-SCONN,HA
M_L_DQ<39>               J9L2             247      SCONN288_H44441003_PIP-SCONN,HA
M_L_DQ<39>               U2D1             DU40     SKX_EXT_B_BGA1-IC,TBD
M_L_DQ<40>               J1A2             253      SCONN288_H44441004_PIP-SCONN,HA
M_L_DQ<40>               J9L2             108      SCONN288_H44441003_PIP-SCONN,HA
M_L_DQ<40>               U2D1             EC34     SKX_EXT_B_BGA1-IC,TBD
M_L_DQ<41>               J1A2             108      SCONN288_H44441004_PIP-SCONN,HA
M_L_DQ<41>               J9L2             253      SCONN288_H44441003_PIP-SCONN,HA
M_L_DQ<41>               U2D1             ED33     SKX_EXT_B_BGA1-IC,TBD
M_L_DQ<42>               J1A2             260      SCONN288_H44441004_PIP-SCONN,HA
M_L_DQ<42>               J9L2             115      SCONN288_H44441003_PIP-SCONN,HA
M_L_DQ<42>               U2D1             EA30     SKX_EXT_B_BGA1-IC,TBD
M_L_DQ<43>               J1A2             115      SCONN288_H44441004_PIP-SCONN,HA
M_L_DQ<43>               J9L2             260      SCONN288_H44441003_PIP-SCONN,HA
M_L_DQ<43>               U2D1             EC30     SKX_EXT_B_BGA1-IC,TBD
M_L_DQ<44>               J1A2             251      SCONN288_H44441004_PIP-SCONN,HA
M_L_DQ<44>               J9L2             106      SCONN288_H44441003_PIP-SCONN,HA
M_L_DQ<44>               U2D1             DY33     SKX_EXT_B_BGA1-IC,TBD
M_L_DQ<45>               J1A2             106      SCONN288_H44441004_PIP-SCONN,HA
M_L_DQ<45>               J9L2             251      SCONN288_H44441003_PIP-SCONN,HA
M_L_DQ<45>               U2D1             EA34     SKX_EXT_B_BGA1-IC,TBD
M_L_DQ<46>               J1A2             258      SCONN288_H44441004_PIP-SCONN,HA
M_L_DQ<46>               J9L2             113      SCONN288_H44441003_PIP-SCONN,HA
M_L_DQ<46>               U2D1             DY31     SKX_EXT_B_BGA1-IC,TBD
M_L_DQ<47>               J1A2             113      SCONN288_H44441004_PIP-SCONN,HA
M_L_DQ<47>               J9L2             258      SCONN288_H44441003_PIP-SCONN,HA
M_L_DQ<47>               U2D1             ED31     SKX_EXT_B_BGA1-IC,TBD
M_L_DQ<48>               J1A2             264      SCONN288_H44441004_PIP-SCONN,HA
M_L_DQ<48>               J9L2             119      SCONN288_H44441003_PIP-SCONN,HA
M_L_DQ<48>               U2D1             EC28     SKX_EXT_B_BGA1-IC,TBD
M_L_DQ<49>               J1A2             119      SCONN288_H44441004_PIP-SCONN,HA
M_L_DQ<49>               J9L2             264      SCONN288_H44441003_PIP-SCONN,HA
M_L_DQ<49>               U2D1             ED27     SKX_EXT_B_BGA1-IC,TBD
M_L_DQ<50>               J1A2             271      SCONN288_H44441004_PIP-SCONN,HA
M_L_DQ<50>               J9L2             126      SCONN288_H44441003_PIP-SCONN,HA
M_L_DQ<50>               U2D1             EA24     SKX_EXT_B_BGA1-IC,TBD
M_L_DQ<51>               J1A2             126      SCONN288_H44441004_PIP-SCONN,HA
M_L_DQ<51>               J9L2             271      SCONN288_H44441003_PIP-SCONN,HA
M_L_DQ<51>               U2D1             EC24     SKX_EXT_B_BGA1-IC,TBD
M_L_DQ<52>               J1A2             262      SCONN288_H44441004_PIP-SCONN,HA
M_L_DQ<52>               J9L2             117      SCONN288_H44441003_PIP-SCONN,HA
M_L_DQ<52>               U2D1             DY27     SKX_EXT_B_BGA1-IC,TBD
M_L_DQ<53>               J1A2             117      SCONN288_H44441004_PIP-SCONN,HA
M_L_DQ<53>               J9L2             262      SCONN288_H44441003_PIP-SCONN,HA
M_L_DQ<53>               U2D1             EA28     SKX_EXT_B_BGA1-IC,TBD
M_L_DQ<54>               J1A2             269      SCONN288_H44441004_PIP-SCONN,HA
M_L_DQ<54>               J9L2             124      SCONN288_H44441003_PIP-SCONN,HA
M_L_DQ<54>               U2D1             DY25     SKX_EXT_B_BGA1-IC,TBD
M_L_DQ<55>               J1A2             124      SCONN288_H44441004_PIP-SCONN,HA
M_L_DQ<55>               J9L2             269      SCONN288_H44441003_PIP-SCONN,HA
M_L_DQ<55>               U2D1             ED25     SKX_EXT_B_BGA1-IC,TBD
M_L_DQ<56>               J1A2             275      SCONN288_H44441004_PIP-SCONN,HA
M_L_DQ<56>               J9L2             130      SCONN288_H44441003_PIP-SCONN,HA
M_L_DQ<56>               U2D1             DF27     SKX_EXT_B_BGA1-IC,TBD
M_L_DQ<57>               J1A2             130      SCONN288_H44441004_PIP-SCONN,HA
M_L_DQ<57>               J9L2             275      SCONN288_H44441003_PIP-SCONN,HA
M_L_DQ<57>               U2D1             DK27     SKX_EXT_B_BGA1-IC,TBD
M_L_DQ<58>               J1A2             282      SCONN288_H44441004_PIP-SCONN,HA
M_L_DQ<58>               J9L2             137      SCONN288_H44441003_PIP-SCONN,HA
M_L_DQ<58>               U2D1             DD25     SKX_EXT_B_BGA1-IC,TBD
M_L_DQ<59>               J1A2             137      SCONN288_H44441004_PIP-SCONN,HA
M_L_DQ<59>               J9L2             282      SCONN288_H44441003_PIP-SCONN,HA
M_L_DQ<59>               U2D1             DJ24     SKX_EXT_B_BGA1-IC,TBD
M_L_DQ<60>               J1A2             273      SCONN288_H44441004_PIP-SCONN,HA
M_L_DQ<60>               J9L2             128      SCONN288_H44441003_PIP-SCONN,HA
M_L_DQ<60>               U2D1             DG28     SKX_EXT_B_BGA1-IC,TBD
M_L_DQ<61>               J1A2             128      SCONN288_H44441004_PIP-SCONN,HA
M_L_DQ<61>               J9L2             273      SCONN288_H44441003_PIP-SCONN,HA
M_L_DQ<61>               U2D1             DJ28     SKX_EXT_B_BGA1-IC,TBD
M_L_DQ<62>               J1A2             280      SCONN288_H44441004_PIP-SCONN,HA
M_L_DQ<62>               J9L2             135      SCONN288_H44441003_PIP-SCONN,HA
M_L_DQ<62>               U2D1             DF25     SKX_EXT_B_BGA1-IC,TBD
M_L_DQ<63>               J1A2             135      SCONN288_H44441004_PIP-SCONN,HA
M_L_DQ<63>               J9L2             280      SCONN288_H44441003_PIP-SCONN,HA
M_L_DQ<63>               U2D1             DK25     SKX_EXT_B_BGA1-IC,TBD
M_L_DQS_DN<0>            J1A2             152      SCONN288_H44441004_PIP-SCONN,HA
M_L_DQS_DN<0>            J9L2             152      SCONN288_H44441003_PIP-SCONN,HA
M_L_DQS_DN<0>            U2D1             CL82     SKX_EXT_B_BGA1-IC,TBD
M_L_DQS_DN<1>            J1A2             163      SCONN288_H44441004_PIP-SCONN,HA
M_L_DQS_DN<1>            J9L2             163      SCONN288_H44441003_PIP-SCONN,HA
M_L_DQS_DN<1>            U2D1             DA82     SKX_EXT_B_BGA1-IC,TBD
M_L_DQS_DN<2>            J1A2             174      SCONN288_H44441004_PIP-SCONN,HA
M_L_DQS_DN<2>            J9L2             174      SCONN288_H44441003_PIP-SCONN,HA
M_L_DQS_DN<2>            U2D1             ED79     SKX_EXT_B_BGA1-IC,TBD
M_L_DQS_DN<3>            J1A2             185      SCONN288_H44441004_PIP-SCONN,HA
M_L_DQS_DN<3>            J9L2             185      SCONN288_H44441003_PIP-SCONN,HA
M_L_DQS_DN<3>            U2D1             EF73     SKX_EXT_B_BGA1-IC,TBD
M_L_DQS_DN<4>            J1A2             244      SCONN288_H44441004_PIP-SCONN,HA
M_L_DQS_DN<4>            J9L2             244      SCONN288_H44441003_PIP-SCONN,HA
M_L_DQS_DN<4>            U2D1             DV41     SKX_EXT_B_BGA1-IC,TBD
M_L_DQS_DN<5>            J1A2             255      SCONN288_H44441004_PIP-SCONN,HA
M_L_DQS_DN<5>            J9L2             255      SCONN288_H44441003_PIP-SCONN,HA
M_L_DQS_DN<5>            U2D1             EE32     SKX_EXT_B_BGA1-IC,TBD
M_L_DQS_DN<6>            J1A2             266      SCONN288_H44441004_PIP-SCONN,HA
M_L_DQS_DN<6>            J9L2             266      SCONN288_H44441003_PIP-SCONN,HA
M_L_DQS_DN<6>            U2D1             EE26     SKX_EXT_B_BGA1-IC,TBD
M_L_DQS_DN<7>            J1A2             277      SCONN288_H44441004_PIP-SCONN,HA
M_L_DQS_DN<7>            J9L2             277      SCONN288_H44441003_PIP-SCONN,HA
M_L_DQS_DN<7>            U2D1             DL26     SKX_EXT_B_BGA1-IC,TBD
M_L_DQS_DN<8>            J1A2             196      SCONN288_H44441004_PIP-SCONN,HA
M_L_DQS_DN<8>            J9L2             196      SCONN288_H44441003_PIP-SCONN,HA
M_L_DQS_DN<8>            U2D1             EB67     SKX_EXT_B_BGA1-IC,TBD
M_L_DQS_DN<9>            J1A2             8        SCONN288_H44441004_PIP-SCONN,HA
M_L_DQS_DN<9>            J9L2             8        SCONN288_H44441003_PIP-SCONN,HA
M_L_DQS_DN<9>            U2D1             CN80     SKX_EXT_B_BGA1-IC,TBD
M_L_DQS_DN<10>           J1A2             19       SCONN288_H44441004_PIP-SCONN,HA
M_L_DQS_DN<10>           J9L2             19       SCONN288_H44441003_PIP-SCONN,HA
M_L_DQS_DN<10>           U2D1             DC80     SKX_EXT_B_BGA1-IC,TBD
M_L_DQS_DN<11>           J1A2             30       SCONN288_H44441004_PIP-SCONN,HA
M_L_DQS_DN<11>           J9L2             30       SCONN288_H44441003_PIP-SCONN,HA
M_L_DQS_DN<11>           U2D1             DY79     SKX_EXT_B_BGA1-IC,TBD
M_L_DQS_DN<12>           J1A2             41       SCONN288_H44441004_PIP-SCONN,HA
M_L_DQS_DN<12>           J9L2             41       SCONN288_H44441003_PIP-SCONN,HA
M_L_DQS_DN<12>           U2D1             EB73     SKX_EXT_B_BGA1-IC,TBD
M_L_DQS_DN<13>           J1A2             100      SCONN288_H44441004_PIP-SCONN,HA
M_L_DQS_DN<13>           J9L2             100      SCONN288_H44441003_PIP-SCONN,HA
M_L_DQS_DN<13>           U2D1             DP41     SKX_EXT_B_BGA1-IC,TBD
M_L_DQS_DN<14>           J1A2             111      SCONN288_H44441004_PIP-SCONN,HA
M_L_DQS_DN<14>           J9L2             111      SCONN288_H44441003_PIP-SCONN,HA
M_L_DQS_DN<14>           U2D1             EA32     SKX_EXT_B_BGA1-IC,TBD
M_L_DQS_DN<15>           J1A2             122      SCONN288_H44441004_PIP-SCONN,HA
M_L_DQS_DN<15>           J9L2             122      SCONN288_H44441003_PIP-SCONN,HA
M_L_DQS_DN<15>           U2D1             EA26     SKX_EXT_B_BGA1-IC,TBD
M_L_DQS_DN<16>           J1A2             133      SCONN288_H44441004_PIP-SCONN,HA
M_L_DQS_DN<16>           J9L2             133      SCONN288_H44441003_PIP-SCONN,HA
M_L_DQS_DN<16>           U2D1             DG26     SKX_EXT_B_BGA1-IC,TBD
M_L_DQS_DN<17>           J1A2             52       SCONN288_H44441004_PIP-SCONN,HA
M_L_DQS_DN<17>           J9L2             52       SCONN288_H44441003_PIP-SCONN,HA
M_L_DQS_DN<17>           U2D1             DV67     SKX_EXT_B_BGA1-IC,TBD
M_L_DQS_DP<0>            J1A2             153      SCONN288_H44441004_PIP-SCONN,HA
M_L_DQS_DP<0>            J9L2             153      SCONN288_H44441003_PIP-SCONN,HA
M_L_DQS_DP<0>            U2D1             CM81     SKX_EXT_B_BGA1-IC,TBD
M_L_DQS_DP<1>            J1A2             164      SCONN288_H44441004_PIP-SCONN,HA
M_L_DQS_DP<1>            J9L2             164      SCONN288_H44441003_PIP-SCONN,HA
M_L_DQS_DP<1>            U2D1             DB81     SKX_EXT_B_BGA1-IC,TBD
M_L_DQS_DP<2>            J1A2             175      SCONN288_H44441004_PIP-SCONN,HA
M_L_DQS_DP<2>            J9L2             175      SCONN288_H44441003_PIP-SCONN,HA
M_L_DQS_DP<2>            U2D1             EB79     SKX_EXT_B_BGA1-IC,TBD
M_L_DQS_DP<3>            J1A2             186      SCONN288_H44441004_PIP-SCONN,HA
M_L_DQS_DP<3>            J9L2             186      SCONN288_H44441003_PIP-SCONN,HA
M_L_DQS_DP<3>            U2D1             ED73     SKX_EXT_B_BGA1-IC,TBD
M_L_DQS_DP<4>            J1A2             245      SCONN288_H44441004_PIP-SCONN,HA
M_L_DQS_DP<4>            J9L2             245      SCONN288_H44441003_PIP-SCONN,HA
M_L_DQS_DP<4>            U2D1             DT41     SKX_EXT_B_BGA1-IC,TBD
M_L_DQS_DP<5>            J1A2             256      SCONN288_H44441004_PIP-SCONN,HA
M_L_DQS_DP<5>            J9L2             256      SCONN288_H44441003_PIP-SCONN,HA
M_L_DQS_DP<5>            U2D1             EC32     SKX_EXT_B_BGA1-IC,TBD
M_L_DQS_DP<6>            J1A2             267      SCONN288_H44441004_PIP-SCONN,HA
M_L_DQS_DP<6>            J9L2             267      SCONN288_H44441003_PIP-SCONN,HA
M_L_DQS_DP<6>            U2D1             EC26     SKX_EXT_B_BGA1-IC,TBD
M_L_DQS_DP<7>            J1A2             278      SCONN288_H44441004_PIP-SCONN,HA
M_L_DQS_DP<7>            J9L2             278      SCONN288_H44441003_PIP-SCONN,HA
M_L_DQS_DP<7>            U2D1             DJ26     SKX_EXT_B_BGA1-IC,TBD
M_L_DQS_DP<8>            J1A2             197      SCONN288_H44441004_PIP-SCONN,HA
M_L_DQS_DP<8>            J9L2             197      SCONN288_H44441003_PIP-SCONN,HA
M_L_DQS_DP<8>            U2D1             DY67     SKX_EXT_B_BGA1-IC,TBD
M_L_DQS_DP<9>            J1A2             7        SCONN288_H44441004_PIP-SCONN,HA
M_L_DQS_DP<9>            J9L2             7        SCONN288_H44441003_PIP-SCONN,HA
M_L_DQS_DP<9>            U2D1             CP79     SKX_EXT_B_BGA1-IC,TBD
M_L_DQS_DP<10>           J1A2             18       SCONN288_H44441004_PIP-SCONN,HA
M_L_DQS_DP<10>           J9L2             18       SCONN288_H44441003_PIP-SCONN,HA
M_L_DQS_DP<10>           U2D1             DD79     SKX_EXT_B_BGA1-IC,TBD
M_L_DQS_DP<11>           J1A2             29       SCONN288_H44441004_PIP-SCONN,HA
M_L_DQS_DP<11>           J9L2             29       SCONN288_H44441003_PIP-SCONN,HA
M_L_DQS_DP<11>           U2D1             DV79     SKX_EXT_B_BGA1-IC,TBD
M_L_DQS_DP<12>           J1A2             40       SCONN288_H44441004_PIP-SCONN,HA
M_L_DQS_DP<12>           J9L2             40       SCONN288_H44441003_PIP-SCONN,HA
M_L_DQS_DP<12>           U2D1             DY73     SKX_EXT_B_BGA1-IC,TBD
M_L_DQS_DP<13>           J1A2             99       SCONN288_H44441004_PIP-SCONN,HA
M_L_DQS_DP<13>           J9L2             99       SCONN288_H44441003_PIP-SCONN,HA
M_L_DQS_DP<13>           U2D1             DM41     SKX_EXT_B_BGA1-IC,TBD
M_L_DQS_DP<14>           J1A2             110      SCONN288_H44441004_PIP-SCONN,HA
M_L_DQS_DP<14>           J9L2             110      SCONN288_H44441003_PIP-SCONN,HA
M_L_DQS_DP<14>           U2D1             DW32     SKX_EXT_B_BGA1-IC,TBD
M_L_DQS_DP<15>           J1A2             121      SCONN288_H44441004_PIP-SCONN,HA
M_L_DQS_DP<15>           J9L2             121      SCONN288_H44441003_PIP-SCONN,HA
M_L_DQS_DP<15>           U2D1             DW26     SKX_EXT_B_BGA1-IC,TBD
M_L_DQS_DP<16>           J1A2             132      SCONN288_H44441004_PIP-SCONN,HA
M_L_DQS_DP<16>           J9L2             132      SCONN288_H44441003_PIP-SCONN,HA
M_L_DQS_DP<16>           U2D1             DE26     SKX_EXT_B_BGA1-IC,TBD
M_L_DQS_DP<17>           J1A2             51       SCONN288_H44441004_PIP-SCONN,HA
M_L_DQS_DP<17>           J9L2             51       SCONN288_H44441003_PIP-SCONN,HA
M_L_DQS_DP<17>           U2D1             DT67     SKX_EXT_B_BGA1-IC,TBD
M_L_ECC<0>               J1A2             194      SCONN288_H44441004_PIP-SCONN,HA
M_L_ECC<0>               J9L2             49       SCONN288_H44441003_PIP-SCONN,HA
M_L_ECC<0>               U2D1             DY69     SKX_EXT_B_BGA1-IC,TBD
M_L_ECC<1>               J1A2             49       SCONN288_H44441004_PIP-SCONN,HA
M_L_ECC<1>               J9L2             194      SCONN288_H44441003_PIP-SCONN,HA
M_L_ECC<1>               U2D1             EA68     SKX_EXT_B_BGA1-IC,TBD
M_L_ECC<2>               J1A2             201      SCONN288_H44441004_PIP-SCONN,HA
M_L_ECC<2>               J9L2             56       SCONN288_H44441003_PIP-SCONN,HA
M_L_ECC<2>               U2D1             DV65     SKX_EXT_B_BGA1-IC,TBD
M_L_ECC<3>               J1A2             56       SCONN288_H44441004_PIP-SCONN,HA
M_L_ECC<3>               J9L2             201      SCONN288_H44441003_PIP-SCONN,HA
M_L_ECC<3>               U2D1             DY65     SKX_EXT_B_BGA1-IC,TBD
M_L_ECC<4>               J1A2             192      SCONN288_H44441004_PIP-SCONN,HA
M_L_ECC<4>               J9L2             47       SCONN288_H44441003_PIP-SCONN,HA
M_L_ECC<4>               U2D1             DU68     SKX_EXT_B_BGA1-IC,TBD
M_L_ECC<5>               J1A2             47       SCONN288_H44441004_PIP-SCONN,HA
M_L_ECC<5>               J9L2             192      SCONN288_H44441003_PIP-SCONN,HA
M_L_ECC<5>               U2D1             DV69     SKX_EXT_B_BGA1-IC,TBD
M_L_ECC<6>               J1A2             199      SCONN288_H44441004_PIP-SCONN,HA
M_L_ECC<6>               J9L2             54       SCONN288_H44441003_PIP-SCONN,HA
M_L_ECC<6>               U2D1             DU66     SKX_EXT_B_BGA1-IC,TBD
M_L_ECC<7>               J1A2             54       SCONN288_H44441004_PIP-SCONN,HA
M_L_ECC<7>               J9L2             199      SCONN288_H44441003_PIP-SCONN,HA
M_L_ECC<7>               U2D1             EA66     SKX_EXT_B_BGA1-IC,TBD
M_L_MA<0>                J1A2             79       SCONN288_H44441004_PIP-SCONN,HA
M_L_MA<0>                J9L2             79       SCONN288_H44441003_PIP-SCONN,HA
M_L_MA<0>                U2D1             DW52     SKX_EXT_B_BGA1-IC,TBD
M_L_MA<1>                J1A2             72       SCONN288_H44441004_PIP-SCONN,HA
M_L_MA<1>                J9L2             72       SCONN288_H44441003_PIP-SCONN,HA
M_L_MA<1>                U2D1             DW58     SKX_EXT_B_BGA1-IC,TBD
M_L_MA<2>                J1A2             216      SCONN288_H44441004_PIP-SCONN,HA
M_L_MA<2>                J9L2             216      SCONN288_H44441003_PIP-SCONN,HA
M_L_MA<2>                U2D1             DV57     SKX_EXT_B_BGA1-IC,TBD
M_L_MA<3>                J1A2             71       SCONN288_H44441004_PIP-SCONN,HA
M_L_MA<3>                J9L2             71       SCONN288_H44441003_PIP-SCONN,HA
M_L_MA<3>                U2D1             DR58     SKX_EXT_B_BGA1-IC,TBD
M_L_MA<4>                J1A2             214      SCONN288_H44441004_PIP-SCONN,HA
M_L_MA<4>                J9L2             214      SCONN288_H44441003_PIP-SCONN,HA
M_L_MA<4>                U2D1             DT59     SKX_EXT_B_BGA1-IC,TBD
M_L_MA<5>                J1A2             213      SCONN288_H44441004_PIP-SCONN,HA
M_L_MA<5>                J9L2             213      SCONN288_H44441003_PIP-SCONN,HA
M_L_MA<5>                U2D1             DN58     SKX_EXT_B_BGA1-IC,TBD
M_L_MA<6>                J1A2             69       SCONN288_H44441004_PIP-SCONN,HA
M_L_MA<6>                J9L2             69       SCONN288_H44441003_PIP-SCONN,HA
M_L_MA<6>                U2D1             DM59     SKX_EXT_B_BGA1-IC,TBD
M_L_MA<7>                J1A2             211      SCONN288_H44441004_PIP-SCONN,HA
M_L_MA<7>                J9L2             211      SCONN288_H44441003_PIP-SCONN,HA
M_L_MA<7>                U2D1             DK61     SKX_EXT_B_BGA1-IC,TBD
M_L_MA<8>                J1A2             68       SCONN288_H44441004_PIP-SCONN,HA
M_L_MA<8>                J9L2             68       SCONN288_H44441003_PIP-SCONN,HA
M_L_MA<8>                U2D1             DJ60     SKX_EXT_B_BGA1-IC,TBD
M_L_MA<9>                J1A2             66       SCONN288_H44441004_PIP-SCONN,HA
M_L_MA<9>                J9L2             66       SCONN288_H44441003_PIP-SCONN,HA
M_L_MA<9>                U2D1             DV59     SKX_EXT_B_BGA1-IC,TBD
M_L_MA<10>               J1A2             225      SCONN288_H44441004_PIP-SCONN,HA
M_L_MA<10>               J9L2             225      SCONN288_H44441003_PIP-SCONN,HA
M_L_MA<10>               U2D1             DT55     SKX_EXT_B_BGA1-IC,TBD
M_L_MA<11>               J1A2             210      SCONN288_H44441004_PIP-SCONN,HA
M_L_MA<11>               J9L2             210      SCONN288_H44441003_PIP-SCONN,HA
M_L_MA<11>               U2D1             DR60     SKX_EXT_B_BGA1-IC,TBD
M_L_MA<12>               J1A2             65       SCONN288_H44441004_PIP-SCONN,HA
M_L_MA<12>               J9L2             65       SCONN288_H44441003_PIP-SCONN,HA
M_L_MA<12>               U2D1             DN60     SKX_EXT_B_BGA1-IC,TBD
M_L_MA<13>               J1A2             232      SCONN288_H44441004_PIP-SCONN,HA
M_L_MA<13>               J9L2             232      SCONN288_H44441003_PIP-SCONN,HA
M_L_MA<13>               U2D1             DT51     SKX_EXT_B_BGA1-IC,TBD
M_L_MA<14>               J1A2             228      SCONN288_H44441004_PIP-SCONN,HA
M_L_MA<14>               J9L2             228      SCONN288_H44441003_PIP-SCONN,HA
M_L_MA<14>               U2D1             DM51     SKX_EXT_B_BGA1-IC,TBD
M_L_MA<15>               J1A2             86       SCONN288_H44441004_PIP-SCONN,HA
M_L_MA<15>               J9L2             86       SCONN288_H44441003_PIP-SCONN,HA
M_L_MA<15>               U2D1             DR52     SKX_EXT_B_BGA1-IC,TBD
M_L_MA<16>               J1A2             82       SCONN288_H44441004_PIP-SCONN,HA
M_L_MA<16>               J9L2             82       SCONN288_H44441003_PIP-SCONN,HA
M_L_MA<16>               U2D1             DN52     SKX_EXT_B_BGA1-IC,TBD
M_L_MA<17>               J1A2             234      SCONN288_H44441004_PIP-SCONN,HA
M_L_MA<17>               J9L2             234      SCONN288_H44441003_PIP-SCONN,HA
M_L_MA<17>               U2D1             DR48     SKX_EXT_B_BGA1-IC,TBD
M_L_ODT<0>               J1A2             87       SCONN288_H44441004_PIP-SCONN,HA
M_L_ODT<0>               U2D1             DR50     SKX_EXT_B_BGA1-IC,TBD
M_L_ODT<1>               J1A2             91       SCONN288_H44441004_PIP-SCONN,HA
M_L_ODT<1>               U2D1             DN48     SKX_EXT_B_BGA1-IC,TBD
M_L_ODT<2>               J9L2             87       SCONN288_H44441003_PIP-SCONN,HA
M_L_ODT<2>               U2D1             DT49     SKX_EXT_B_BGA1-IC,TBD
M_L_ODT<3>               J9L2             91       SCONN288_H44441003_PIP-SCONN,HA
M_L_ODT<3>               U2D1             DM47     SKX_EXT_B_BGA1-IC,TBD
M_L_PAR                  J1A2             222      SCONN288_H44441004_PIP-SCONN,HA
M_L_PAR                  J9L2             222      SCONN288_H44441003_PIP-SCONN,HA
M_L_PAR                  U2D1             DV53     SKX_EXT_B_BGA1-IC,TBD
M_L_VREF                 C1A17            1        CAP_A_0402V-0.01UF,25V,10%,X7RA
M_L_VREF                 C9L7             1        CAP_A_0402V-0.01UF,25V,10%,X7RA
M_L_VREF                 J1A2             146      SCONN288_H44441004_PIP-SCONN,HA
M_L_VREF                 J9L2             146      SCONN288_H44441003_PIP-SCONN,HA
M_L_VREF                 R9L6             1        RES_0402-1.00K,1%,1/16W,CHIP,GA
M_L_VREF                 R9L7             2        RES_0402-1.00K,1%,1/16W,CHIP,GA
M_L_VREF                 R9L8             2        RES_0402-2,1.0%,1/16W,CHIP,G21A
M_M_ACT_N                J1A1             62       SCONN288_H44441004_PIP-SCONN,HA
M_M_ACT_N                J9L1             62       SCONN288_H44441003_PIP-SCONN,HA
M_M_ACT_N                U2D1             DC62     SKX_EXT_B_BGA1-IC,TBD
M_M_ALERT_N              J1A1             208      SCONN288_H44441004_PIP-SCONN,HA
M_M_ALERT_N              J9L1             208      SCONN288_H44441003_PIP-SCONN,HA
M_M_ALERT_N              U2D1             DD61     SKX_EXT_B_BGA1-IC,TBD
M_M_BA<0>                J1A1             81       SCONN288_H44441004_PIP-SCONN,HA
M_M_BA<0>                J9L1             81       SCONN288_H44441003_PIP-SCONN,HA
M_M_BA<0>                U2D1             DJ52     SKX_EXT_B_BGA1-IC,TBD
M_M_BA<1>                J1A1             224      SCONN288_H44441004_PIP-SCONN,HA
M_M_BA<1>                J9L1             224      SCONN288_H44441003_PIP-SCONN,HA
M_M_BA<1>                U2D1             DC56     SKX_EXT_B_BGA1-IC,TBD
M_M_BG<0>                J1A1             63       SCONN288_H44441004_PIP-SCONN,HA
M_M_BG<0>                J9L1             63       SCONN288_H44441003_PIP-SCONN,HA
M_M_BG<0>                U2D1             DA62     SKX_EXT_B_BGA1-IC,TBD
M_M_BG<1>                J1A1             207      SCONN288_H44441004_PIP-SCONN,HA
M_M_BG<1>                J9L1             207      SCONN288_H44441003_PIP-SCONN,HA
M_M_BG<1>                U2D1             DF61     SKX_EXT_B_BGA1-IC,TBD
M_M_C<2>                 J1A1             235      SCONN288_H44441004_PIP-SCONN,HA
M_M_C<2>                 J9L1             235      SCONN288_H44441003_PIP-SCONN,HA
M_M_C<2>                 U2D1             DF45     SKX_EXT_B_BGA1-IC,TBD
M_M_CKE<0>               J1A1             60       SCONN288_H44441004_PIP-SCONN,HA
M_M_CKE<0>               U2D1             DG62     SKX_EXT_B_BGA1-IC,TBD
M_M_CKE<1>               J1A1             203      SCONN288_H44441004_PIP-SCONN,HA
M_M_CKE<1>               U2D1             DD63     SKX_EXT_B_BGA1-IC,TBD
M_M_CKE<2>               J9L1             60       SCONN288_H44441003_PIP-SCONN,HA
M_M_CKE<2>               U2D1             DK63     SKX_EXT_B_BGA1-IC,TBD
M_M_CKE<3>               J9L1             203      SCONN288_H44441003_PIP-SCONN,HA
M_M_CKE<3>               U2D1             DF63     SKX_EXT_B_BGA1-IC,TBD
M_M_CLK_DN<0>            J1A1             75       SCONN288_H44441004_PIP-SCONN,HA
M_M_CLK_DN<0>            U2D1             DK55     SKX_EXT_B_BGA1-IC,TBD
M_M_CLK_DN<1>            J1A1             219      SCONN288_H44441004_PIP-SCONN,HA
M_M_CLK_DN<1>            U2D1             DF55     SKX_EXT_B_BGA1-IC,TBD
M_M_CLK_DN<2>            J9L1             75       SCONN288_H44441003_PIP-SCONN,HA
M_M_CLK_DN<2>            U2D1             DK57     SKX_EXT_B_BGA1-IC,TBD
M_M_CLK_DN<3>            J9L1             219      SCONN288_H44441003_PIP-SCONN,HA
M_M_CLK_DN<3>            U2D1             DF57     SKX_EXT_B_BGA1-IC,TBD
M_M_CLK_DP<0>            J1A1             74       SCONN288_H44441004_PIP-SCONN,HA
M_M_CLK_DP<0>            U2D1             DJ54     SKX_EXT_B_BGA1-IC,TBD
M_M_CLK_DP<1>            J1A1             218      SCONN288_H44441004_PIP-SCONN,HA
M_M_CLK_DP<1>            U2D1             DG54     SKX_EXT_B_BGA1-IC,TBD
M_M_CLK_DP<2>            J9L1             74       SCONN288_H44441003_PIP-SCONN,HA
M_M_CLK_DP<2>            U2D1             DJ56     SKX_EXT_B_BGA1-IC,TBD
M_M_CLK_DP<3>            J9L1             218      SCONN288_H44441003_PIP-SCONN,HA
M_M_CLK_DP<3>            U2D1             DG56     SKX_EXT_B_BGA1-IC,TBD
M_M_CPU_VREF             C9L3             1        CAP_A_0402V-0.01UF,25V,10%,X7RA
M_M_CPU_VREF             R9L3             1        RES_0402-2,1.0%,1/16W,CHIP,G21A
M_M_CPU_VREF             U2D1             CV61     SKX_EXT_B_BGA1-IC,TBD
M_M_CS_N<0>              J1A1             84       SCONN288_H44441004_PIP-SCONN,HA
M_M_CS_N<0>              U2D1             DK51     SKX_EXT_B_BGA1-IC,TBD
M_M_CS_N<1>              J1A1             89       SCONN288_H44441004_PIP-SCONN,HA
M_M_CS_N<1>              U2D1             DF49     SKX_EXT_B_BGA1-IC,TBD
M_M_CS_N<2>              J1A1             93       SCONN288_H44441004_PIP-SCONN,HA
M_M_CS_N<2>              U2D1             DJ46     SKX_EXT_B_BGA1-IC,TBD
M_M_CS_N<3>              J1A1             237      SCONN288_H44441004_PIP-SCONN,HA
M_M_CS_N<3>              U2D1             DG46     SKX_EXT_B_BGA1-IC,TBD
M_M_CS_N<4>              J9L1             84       SCONN288_H44441003_PIP-SCONN,HA
M_M_CS_N<4>              U2D1             DF51     SKX_EXT_B_BGA1-IC,TBD
M_M_CS_N<5>              J9L1             89       SCONN288_H44441003_PIP-SCONN,HA
M_M_CS_N<5>              U2D1             DJ48     SKX_EXT_B_BGA1-IC,TBD
M_M_CS_N<6>              J9L1             93       SCONN288_H44441003_PIP-SCONN,HA
M_M_CS_N<6>              U2D1             DM45     SKX_EXT_B_BGA1-IC,TBD
M_M_CS_N<7>              J9L1             237      SCONN288_H44441003_PIP-SCONN,HA
M_M_CS_N<7>              U2D1             DK45     SKX_EXT_B_BGA1-IC,TBD
M_M_DQ<0>                J1A1             150      SCONN288_H44441004_PIP-SCONN,HA
M_M_DQ<0>                J9L1             5        SCONN288_H44441003_PIP-SCONN,HA
M_M_DQ<0>                U2D1             CR74     SKX_EXT_B_BGA1-IC,TBD
M_M_DQ<1>                J1A1             5        SCONN288_H44441004_PIP-SCONN,HA
M_M_DQ<1>                J9L1             150      SCONN288_H44441003_PIP-SCONN,HA
M_M_DQ<1>                U2D1             CN76     SKX_EXT_B_BGA1-IC,TBD
M_M_DQ<2>                J1A1             157      SCONN288_H44441004_PIP-SCONN,HA
M_M_DQ<2>                J9L1             12       SCONN288_H44441003_PIP-SCONN,HA
M_M_DQ<2>                U2D1             CW76     SKX_EXT_B_BGA1-IC,TBD
M_M_DQ<3>                J1A1             12       SCONN288_H44441004_PIP-SCONN,HA
M_M_DQ<3>                J9L1             157      SCONN288_H44441003_PIP-SCONN,HA
M_M_DQ<3>                U2D1             CV77     SKX_EXT_B_BGA1-IC,TBD
M_M_DQ<4>                J1A1             148      SCONN288_H44441004_PIP-SCONN,HA
M_M_DQ<4>                J9L1             3        SCONN288_H44441003_PIP-SCONN,HA
M_M_DQ<4>                U2D1             CN74     SKX_EXT_B_BGA1-IC,TBD
M_M_DQ<5>                J1A1             3        SCONN288_H44441004_PIP-SCONN,HA
M_M_DQ<5>                J9L1             148      SCONN288_H44441003_PIP-SCONN,HA
M_M_DQ<5>                U2D1             CM75     SKX_EXT_B_BGA1-IC,TBD
M_M_DQ<6>                J1A1             155      SCONN288_H44441004_PIP-SCONN,HA
M_M_DQ<6>                J9L1             10       SCONN288_H44441003_PIP-SCONN,HA
M_M_DQ<6>                U2D1             CV75     SKX_EXT_B_BGA1-IC,TBD
M_M_DQ<7>                J1A1             10       SCONN288_H44441004_PIP-SCONN,HA
M_M_DQ<7>                J9L1             155      SCONN288_H44441003_PIP-SCONN,HA
M_M_DQ<7>                U2D1             CT77     SKX_EXT_B_BGA1-IC,TBD
M_M_DQ<8>                J1A1             161      SCONN288_H44441004_PIP-SCONN,HA
M_M_DQ<8>                J9L1             16       SCONN288_H44441003_PIP-SCONN,HA
M_M_DQ<8>                U2D1             DE74     SKX_EXT_B_BGA1-IC,TBD
M_M_DQ<9>                J1A1             16       SCONN288_H44441004_PIP-SCONN,HA
M_M_DQ<9>                J9L1             161      SCONN288_H44441003_PIP-SCONN,HA
M_M_DQ<9>                U2D1             DC76     SKX_EXT_B_BGA1-IC,TBD
M_M_DQ<10>               J1A1             168      SCONN288_H44441004_PIP-SCONN,HA
M_M_DQ<10>               J9L1             23       SCONN288_H44441003_PIP-SCONN,HA
M_M_DQ<10>               U2D1             DH75     SKX_EXT_B_BGA1-IC,TBD
M_M_DQ<11>               J1A1             23       SCONN288_H44441004_PIP-SCONN,HA
M_M_DQ<11>               J9L1             168      SCONN288_H44441003_PIP-SCONN,HA
M_M_DQ<11>               U2D1             DJ76     SKX_EXT_B_BGA1-IC,TBD
M_M_DQ<12>               J1A1             159      SCONN288_H44441004_PIP-SCONN,HA
M_M_DQ<12>               J9L1             14       SCONN288_H44441003_PIP-SCONN,HA
M_M_DQ<12>               U2D1             DC74     SKX_EXT_B_BGA1-IC,TBD
M_M_DQ<13>               J1A1             14       SCONN288_H44441004_PIP-SCONN,HA
M_M_DQ<13>               J9L1             159      SCONN288_H44441003_PIP-SCONN,HA
M_M_DQ<13>               U2D1             DB75     SKX_EXT_B_BGA1-IC,TBD
M_M_DQ<14>               J1A1             166      SCONN288_H44441004_PIP-SCONN,HA
M_M_DQ<14>               J9L1             21       SCONN288_H44441003_PIP-SCONN,HA
M_M_DQ<14>               U2D1             DF77     SKX_EXT_B_BGA1-IC,TBD
M_M_DQ<15>               J1A1             21       SCONN288_H44441004_PIP-SCONN,HA
M_M_DQ<15>               J9L1             166      SCONN288_H44441003_PIP-SCONN,HA
M_M_DQ<15>               U2D1             DH77     SKX_EXT_B_BGA1-IC,TBD
M_M_DQ<16>               J1A1             172      SCONN288_H44441004_PIP-SCONN,HA
M_M_DQ<16>               J9L1             27       SCONN288_H44441003_PIP-SCONN,HA
M_M_DQ<16>               U2D1             DG70     SKX_EXT_B_BGA1-IC,TBD
M_M_DQ<17>               J1A1             27       SCONN288_H44441004_PIP-SCONN,HA
M_M_DQ<17>               J9L1             172      SCONN288_H44441003_PIP-SCONN,HA
M_M_DQ<17>               U2D1             DJ72     SKX_EXT_B_BGA1-IC,TBD
M_M_DQ<18>               J1A1             179      SCONN288_H44441004_PIP-SCONN,HA
M_M_DQ<18>               J9L1             34       SCONN288_H44441003_PIP-SCONN,HA
M_M_DQ<18>               U2D1             DM69     SKX_EXT_B_BGA1-IC,TBD
M_M_DQ<19>               J1A1             34       SCONN288_H44441004_PIP-SCONN,HA
M_M_DQ<19>               J9L1             179      SCONN288_H44441003_PIP-SCONN,HA
M_M_DQ<19>               U2D1             DN70     SKX_EXT_B_BGA1-IC,TBD
M_M_DQ<20>               J1A1             170      SCONN288_H44441004_PIP-SCONN,HA
M_M_DQ<20>               J9L1             25       SCONN288_H44441003_PIP-SCONN,HA
M_M_DQ<20>               U2D1             DF71     SKX_EXT_B_BGA1-IC,TBD
M_M_DQ<21>               J1A1             25       SCONN288_H44441004_PIP-SCONN,HA
M_M_DQ<21>               J9L1             170      SCONN288_H44441003_PIP-SCONN,HA
M_M_DQ<21>               U2D1             DG72     SKX_EXT_B_BGA1-IC,TBD
M_M_DQ<22>               J1A1             177      SCONN288_H44441004_PIP-SCONN,HA
M_M_DQ<22>               J9L1             32       SCONN288_H44441003_PIP-SCONN,HA
M_M_DQ<22>               U2D1             DK69     SKX_EXT_B_BGA1-IC,TBD
M_M_DQ<23>               J1A1             32       SCONN288_H44441004_PIP-SCONN,HA
M_M_DQ<23>               J9L1             177      SCONN288_H44441003_PIP-SCONN,HA
M_M_DQ<23>               U2D1             DM71     SKX_EXT_B_BGA1-IC,TBD
M_M_DQ<24>               J1A1             183      SCONN288_H44441004_PIP-SCONN,HA
M_M_DQ<24>               J9L1             38       SCONN288_H44441003_PIP-SCONN,HA
M_M_DQ<24>               U2D1             CN66     SKX_EXT_B_BGA1-IC,TBD
M_M_DQ<25>               J1A1             38       SCONN288_H44441004_PIP-SCONN,HA
M_M_DQ<25>               J9L1             183      SCONN288_H44441003_PIP-SCONN,HA
M_M_DQ<25>               U2D1             CU66     SKX_EXT_B_BGA1-IC,TBD
M_M_DQ<26>               J1A1             190      SCONN288_H44441004_PIP-SCONN,HA
M_M_DQ<26>               J9L1             45       SCONN288_H44441003_PIP-SCONN,HA
M_M_DQ<26>               U2D1             CP63     SKX_EXT_B_BGA1-IC,TBD
M_M_DQ<27>               J1A1             45       SCONN288_H44441004_PIP-SCONN,HA
M_M_DQ<27>               J9L1             190      SCONN288_H44441003_PIP-SCONN,HA
M_M_DQ<27>               U2D1             CT63     SKX_EXT_B_BGA1-IC,TBD
M_M_DQ<28>               J1A1             181      SCONN288_H44441004_PIP-SCONN,HA
M_M_DQ<28>               J9L1             36       SCONN288_H44441003_PIP-SCONN,HA
M_M_DQ<28>               U2D1             CP67     SKX_EXT_B_BGA1-IC,TBD
M_M_DQ<29>               J1A1             36       SCONN288_H44441004_PIP-SCONN,HA
M_M_DQ<29>               J9L1             181      SCONN288_H44441003_PIP-SCONN,HA
M_M_DQ<29>               U2D1             CT67     SKX_EXT_B_BGA1-IC,TBD
M_M_DQ<30>               J1A1             188      SCONN288_H44441004_PIP-SCONN,HA
M_M_DQ<30>               J9L1             43       SCONN288_H44441003_PIP-SCONN,HA
M_M_DQ<30>               U2D1             CN64     SKX_EXT_B_BGA1-IC,TBD
M_M_DQ<31>               J1A1             43       SCONN288_H44441004_PIP-SCONN,HA
M_M_DQ<31>               J9L1             188      SCONN288_H44441003_PIP-SCONN,HA
M_M_DQ<31>               U2D1             CU64     SKX_EXT_B_BGA1-IC,TBD
M_M_DQ<32>               J1A1             242      SCONN288_H44441004_PIP-SCONN,HA
M_M_DQ<32>               J9L1             97       SCONN288_H44441003_PIP-SCONN,HA
M_M_DQ<32>               U2D1             DD41     SKX_EXT_B_BGA1-IC,TBD
M_M_DQ<33>               J1A1             97       SCONN288_H44441004_PIP-SCONN,HA
M_M_DQ<33>               J9L1             242      SCONN288_H44441003_PIP-SCONN,HA
M_M_DQ<33>               U2D1             DG42     SKX_EXT_B_BGA1-IC,TBD
M_M_DQ<34>               J1A1             249      SCONN288_H44441004_PIP-SCONN,HA
M_M_DQ<34>               J9L1             104      SCONN288_H44441003_PIP-SCONN,HA
M_M_DQ<34>               U2D1             DE38     SKX_EXT_B_BGA1-IC,TBD
M_M_DQ<35>               J1A1             104      SCONN288_H44441004_PIP-SCONN,HA
M_M_DQ<35>               J9L1             249      SCONN288_H44441003_PIP-SCONN,HA
M_M_DQ<35>               U2D1             DG38     SKX_EXT_B_BGA1-IC,TBD
M_M_DQ<36>               J1A1             240      SCONN288_H44441004_PIP-SCONN,HA
M_M_DQ<36>               J9L1             95       SCONN288_H44441003_PIP-SCONN,HA
M_M_DQ<36>               U2D1             DA42     SKX_EXT_B_BGA1-IC,TBD
M_M_DQ<37>               J1A1             95       SCONN288_H44441004_PIP-SCONN,HA
M_M_DQ<37>               J9L1             240      SCONN288_H44441003_PIP-SCONN,HA
M_M_DQ<37>               U2D1             DE42     SKX_EXT_B_BGA1-IC,TBD
M_M_DQ<38>               J1A1             247      SCONN288_H44441004_PIP-SCONN,HA
M_M_DQ<38>               J9L1             102      SCONN288_H44441003_PIP-SCONN,HA
M_M_DQ<38>               U2D1             DD39     SKX_EXT_B_BGA1-IC,TBD
M_M_DQ<39>               J1A1             102      SCONN288_H44441004_PIP-SCONN,HA
M_M_DQ<39>               J9L1             247      SCONN288_H44441003_PIP-SCONN,HA
M_M_DQ<39>               U2D1             DH39     SKX_EXT_B_BGA1-IC,TBD
M_M_DQ<40>               J1A1             253      SCONN288_H44441004_PIP-SCONN,HA
M_M_DQ<40>               J9L1             108      SCONN288_H44441003_PIP-SCONN,HA
M_M_DQ<40>               U2D1             DF33     SKX_EXT_B_BGA1-IC,TBD
M_M_DQ<41>               J1A1             108      SCONN288_H44441004_PIP-SCONN,HA
M_M_DQ<41>               J9L1             253      SCONN288_H44441003_PIP-SCONN,HA
M_M_DQ<41>               U2D1             DK33     SKX_EXT_B_BGA1-IC,TBD
M_M_DQ<42>               J1A1             260      SCONN288_H44441004_PIP-SCONN,HA
M_M_DQ<42>               J9L1             115      SCONN288_H44441003_PIP-SCONN,HA
M_M_DQ<42>               U2D1             DG30     SKX_EXT_B_BGA1-IC,TBD
M_M_DQ<43>               J1A1             115      SCONN288_H44441004_PIP-SCONN,HA
M_M_DQ<43>               J9L1             260      SCONN288_H44441003_PIP-SCONN,HA
M_M_DQ<43>               U2D1             DJ30     SKX_EXT_B_BGA1-IC,TBD
M_M_DQ<44>               J1A1             251      SCONN288_H44441004_PIP-SCONN,HA
M_M_DQ<44>               J9L1             106      SCONN288_H44441003_PIP-SCONN,HA
M_M_DQ<44>               U2D1             DG34     SKX_EXT_B_BGA1-IC,TBD
M_M_DQ<45>               J1A1             106      SCONN288_H44441004_PIP-SCONN,HA
M_M_DQ<45>               J9L1             251      SCONN288_H44441003_PIP-SCONN,HA
M_M_DQ<45>               U2D1             DJ34     SKX_EXT_B_BGA1-IC,TBD
M_M_DQ<46>               J1A1             258      SCONN288_H44441004_PIP-SCONN,HA
M_M_DQ<46>               J9L1             113      SCONN288_H44441003_PIP-SCONN,HA
M_M_DQ<46>               U2D1             DF31     SKX_EXT_B_BGA1-IC,TBD
M_M_DQ<47>               J1A1             113      SCONN288_H44441004_PIP-SCONN,HA
M_M_DQ<47>               J9L1             258      SCONN288_H44441003_PIP-SCONN,HA
M_M_DQ<47>               U2D1             DK31     SKX_EXT_B_BGA1-IC,TBD
M_M_DQ<48>               J1A1             264      SCONN288_H44441004_PIP-SCONN,HA
M_M_DQ<48>               J9L1             119      SCONN288_H44441003_PIP-SCONN,HA
M_M_DQ<48>               U2D1             CW36     SKX_EXT_B_BGA1-IC,TBD
M_M_DQ<49>               J1A1             119      SCONN288_H44441004_PIP-SCONN,HA
M_M_DQ<49>               J9L1             264      SCONN288_H44441003_PIP-SCONN,HA
M_M_DQ<49>               U2D1             DC36     SKX_EXT_B_BGA1-IC,TBD
M_M_DQ<50>               J1A1             271      SCONN288_H44441004_PIP-SCONN,HA
M_M_DQ<50>               J9L1             126      SCONN288_H44441003_PIP-SCONN,HA
M_M_DQ<50>               U2D1             CY33     SKX_EXT_B_BGA1-IC,TBD
M_M_DQ<51>               J1A1             126      SCONN288_H44441004_PIP-SCONN,HA
M_M_DQ<51>               J9L1             271      SCONN288_H44441003_PIP-SCONN,HA
M_M_DQ<51>               U2D1             DB33     SKX_EXT_B_BGA1-IC,TBD
M_M_DQ<52>               J1A1             262      SCONN288_H44441004_PIP-SCONN,HA
M_M_DQ<52>               J9L1             117      SCONN288_H44441003_PIP-SCONN,HA
M_M_DQ<52>               U2D1             CY37     SKX_EXT_B_BGA1-IC,TBD
M_M_DQ<53>               J1A1             117      SCONN288_H44441004_PIP-SCONN,HA
M_M_DQ<53>               J9L1             262      SCONN288_H44441003_PIP-SCONN,HA
M_M_DQ<53>               U2D1             DB37     SKX_EXT_B_BGA1-IC,TBD
M_M_DQ<54>               J1A1             269      SCONN288_H44441004_PIP-SCONN,HA
M_M_DQ<54>               J9L1             124      SCONN288_H44441003_PIP-SCONN,HA
M_M_DQ<54>               U2D1             CW34     SKX_EXT_B_BGA1-IC,TBD
M_M_DQ<55>               J1A1             124      SCONN288_H44441004_PIP-SCONN,HA
M_M_DQ<55>               J9L1             269      SCONN288_H44441003_PIP-SCONN,HA
M_M_DQ<55>               U2D1             DC34     SKX_EXT_B_BGA1-IC,TBD
M_M_DQ<56>               J1A1             275      SCONN288_H44441004_PIP-SCONN,HA
M_M_DQ<56>               J9L1             130      SCONN288_H44441003_PIP-SCONN,HA
M_M_DQ<56>               U2D1             CW30     SKX_EXT_B_BGA1-IC,TBD
M_M_DQ<57>               J1A1             130      SCONN288_H44441004_PIP-SCONN,HA
M_M_DQ<57>               J9L1             275      SCONN288_H44441003_PIP-SCONN,HA
M_M_DQ<57>               U2D1             DC30     SKX_EXT_B_BGA1-IC,TBD
M_M_DQ<58>               J1A1             282      SCONN288_H44441004_PIP-SCONN,HA
M_M_DQ<58>               J9L1             137      SCONN288_H44441003_PIP-SCONN,HA
M_M_DQ<58>               U2D1             CY27     SKX_EXT_B_BGA1-IC,TBD
M_M_DQ<59>               J1A1             137      SCONN288_H44441004_PIP-SCONN,HA
M_M_DQ<59>               J9L1             282      SCONN288_H44441003_PIP-SCONN,HA
M_M_DQ<59>               U2D1             DB27     SKX_EXT_B_BGA1-IC,TBD
M_M_DQ<60>               J1A1             273      SCONN288_H44441004_PIP-SCONN,HA
M_M_DQ<60>               J9L1             128      SCONN288_H44441003_PIP-SCONN,HA
M_M_DQ<60>               U2D1             CY31     SKX_EXT_B_BGA1-IC,TBD
M_M_DQ<61>               J1A1             128      SCONN288_H44441004_PIP-SCONN,HA
M_M_DQ<61>               J9L1             273      SCONN288_H44441003_PIP-SCONN,HA
M_M_DQ<61>               U2D1             DB31     SKX_EXT_B_BGA1-IC,TBD
M_M_DQ<62>               J1A1             280      SCONN288_H44441004_PIP-SCONN,HA
M_M_DQ<62>               J9L1             135      SCONN288_H44441003_PIP-SCONN,HA
M_M_DQ<62>               U2D1             CW28     SKX_EXT_B_BGA1-IC,TBD
M_M_DQ<63>               J1A1             135      SCONN288_H44441004_PIP-SCONN,HA
M_M_DQ<63>               J9L1             280      SCONN288_H44441003_PIP-SCONN,HA
M_M_DQ<63>               U2D1             DC28     SKX_EXT_B_BGA1-IC,TBD
M_M_DQS_DN<0>            J1A1             152      SCONN288_H44441004_PIP-SCONN,HA
M_M_DQS_DN<0>            J9L1             152      SCONN288_H44441003_PIP-SCONN,HA
M_M_DQS_DN<0>            U2D1             CP77     SKX_EXT_B_BGA1-IC,TBD
M_M_DQS_DN<1>            J1A1             163      SCONN288_H44441004_PIP-SCONN,HA
M_M_DQS_DN<1>            J9L1             163      SCONN288_H44441003_PIP-SCONN,HA
M_M_DQS_DN<1>            U2D1             DD77     SKX_EXT_B_BGA1-IC,TBD
M_M_DQS_DN<2>            J1A1             174      SCONN288_H44441004_PIP-SCONN,HA
M_M_DQS_DN<2>            J9L1             174      SCONN288_H44441003_PIP-SCONN,HA
M_M_DQS_DN<2>            U2D1             DL72     SKX_EXT_B_BGA1-IC,TBD
M_M_DQS_DN<3>            J1A1             185      SCONN288_H44441004_PIP-SCONN,HA
M_M_DQS_DN<3>            J9L1             185      SCONN288_H44441003_PIP-SCONN,HA
M_M_DQS_DN<3>            U2D1             CV65     SKX_EXT_B_BGA1-IC,TBD
M_M_DQS_DN<4>            J1A1             244      SCONN288_H44441004_PIP-SCONN,HA
M_M_DQS_DN<4>            J9L1             244      SCONN288_H44441003_PIP-SCONN,HA
M_M_DQS_DN<4>            U2D1             DG40     SKX_EXT_B_BGA1-IC,TBD
M_M_DQS_DN<5>            J1A1             255      SCONN288_H44441004_PIP-SCONN,HA
M_M_DQS_DN<5>            J9L1             255      SCONN288_H44441003_PIP-SCONN,HA
M_M_DQS_DN<5>            U2D1             DL32     SKX_EXT_B_BGA1-IC,TBD
M_M_DQS_DN<6>            J1A1             266      SCONN288_H44441004_PIP-SCONN,HA
M_M_DQS_DN<6>            J9L1             266      SCONN288_H44441003_PIP-SCONN,HA
M_M_DQS_DN<6>            U2D1             DD35     SKX_EXT_B_BGA1-IC,TBD
M_M_DQS_DN<7>            J1A1             277      SCONN288_H44441004_PIP-SCONN,HA
M_M_DQS_DN<7>            J9L1             277      SCONN288_H44441003_PIP-SCONN,HA
M_M_DQS_DN<7>            U2D1             DD29     SKX_EXT_B_BGA1-IC,TBD
M_M_DQS_DN<8>            J1A1             196      SCONN288_H44441004_PIP-SCONN,HA
M_M_DQS_DN<8>            J9L1             196      SCONN288_H44441003_PIP-SCONN,HA
M_M_DQS_DN<8>            U2D1             CN70     SKX_EXT_B_BGA1-IC,TBD
M_M_DQS_DN<9>            J1A1             8        SCONN288_H44441004_PIP-SCONN,HA
M_M_DQS_DN<9>            J9L1             8        SCONN288_H44441003_PIP-SCONN,HA
M_M_DQS_DN<9>            U2D1             CT75     SKX_EXT_B_BGA1-IC,TBD
M_M_DQS_DN<10>           J1A1             19       SCONN288_H44441004_PIP-SCONN,HA
M_M_DQS_DN<10>           J9L1             19       SCONN288_H44441003_PIP-SCONN,HA
M_M_DQS_DN<10>           U2D1             DF75     SKX_EXT_B_BGA1-IC,TBD
M_M_DQS_DN<11>           J1A1             30       SCONN288_H44441004_PIP-SCONN,HA
M_M_DQS_DN<11>           J9L1             30       SCONN288_H44441003_PIP-SCONN,HA
M_M_DQS_DN<11>           U2D1             DJ70     SKX_EXT_B_BGA1-IC,TBD
M_M_DQS_DN<12>           J1A1             41       SCONN288_H44441004_PIP-SCONN,HA
M_M_DQS_DN<12>           J9L1             41       SCONN288_H44441003_PIP-SCONN,HA
M_M_DQS_DN<12>           U2D1             CP65     SKX_EXT_B_BGA1-IC,TBD
M_M_DQS_DN<13>           J1A1             100      SCONN288_H44441004_PIP-SCONN,HA
M_M_DQS_DN<13>           J9L1             100      SCONN288_H44441003_PIP-SCONN,HA
M_M_DQS_DN<13>           U2D1             DE40     SKX_EXT_B_BGA1-IC,TBD
M_M_DQS_DN<14>           J1A1             111      SCONN288_H44441004_PIP-SCONN,HA
M_M_DQS_DN<14>           J9L1             111      SCONN288_H44441003_PIP-SCONN,HA
M_M_DQS_DN<14>           U2D1             DG32     SKX_EXT_B_BGA1-IC,TBD
M_M_DQS_DN<15>           J1A1             122      SCONN288_H44441004_PIP-SCONN,HA
M_M_DQS_DN<15>           J9L1             122      SCONN288_H44441003_PIP-SCONN,HA
M_M_DQS_DN<15>           U2D1             CY35     SKX_EXT_B_BGA1-IC,TBD
M_M_DQS_DN<16>           J1A1             133      SCONN288_H44441004_PIP-SCONN,HA
M_M_DQS_DN<16>           J9L1             133      SCONN288_H44441003_PIP-SCONN,HA
M_M_DQS_DN<16>           U2D1             CY29     SKX_EXT_B_BGA1-IC,TBD
M_M_DQS_DN<17>           J1A1             52       SCONN288_H44441004_PIP-SCONN,HA
M_M_DQS_DN<17>           J9L1             52       SCONN288_H44441003_PIP-SCONN,HA
M_M_DQS_DN<17>           U2D1             CJ70     SKX_EXT_B_BGA1-IC,TBD
M_M_DQS_DP<0>            J1A1             153      SCONN288_H44441004_PIP-SCONN,HA
M_M_DQS_DP<0>            J9L1             153      SCONN288_H44441003_PIP-SCONN,HA
M_M_DQS_DP<0>            U2D1             CR76     SKX_EXT_B_BGA1-IC,TBD
M_M_DQS_DP<1>            J1A1             164      SCONN288_H44441004_PIP-SCONN,HA
M_M_DQS_DP<1>            J9L1             164      SCONN288_H44441003_PIP-SCONN,HA
M_M_DQS_DP<1>            U2D1             DE76     SKX_EXT_B_BGA1-IC,TBD
M_M_DQS_DP<2>            J1A1             175      SCONN288_H44441004_PIP-SCONN,HA
M_M_DQS_DP<2>            J9L1             175      SCONN288_H44441003_PIP-SCONN,HA
M_M_DQS_DP<2>            U2D1             DK71     SKX_EXT_B_BGA1-IC,TBD
M_M_DQS_DP<3>            J1A1             186      SCONN288_H44441004_PIP-SCONN,HA
M_M_DQS_DP<3>            J9L1             186      SCONN288_H44441003_PIP-SCONN,HA
M_M_DQS_DP<3>            U2D1             CT65     SKX_EXT_B_BGA1-IC,TBD
M_M_DQS_DP<4>            J1A1             245      SCONN288_H44441004_PIP-SCONN,HA
M_M_DQS_DP<4>            J9L1             245      SCONN288_H44441003_PIP-SCONN,HA
M_M_DQS_DP<4>            U2D1             DJ40     SKX_EXT_B_BGA1-IC,TBD
M_M_DQS_DP<5>            J1A1             256      SCONN288_H44441004_PIP-SCONN,HA
M_M_DQS_DP<5>            J9L1             256      SCONN288_H44441003_PIP-SCONN,HA
M_M_DQS_DP<5>            U2D1             DJ32     SKX_EXT_B_BGA1-IC,TBD
M_M_DQS_DP<6>            J1A1             267      SCONN288_H44441004_PIP-SCONN,HA
M_M_DQS_DP<6>            J9L1             267      SCONN288_H44441003_PIP-SCONN,HA
M_M_DQS_DP<6>            U2D1             DB35     SKX_EXT_B_BGA1-IC,TBD
M_M_DQS_DP<7>            J1A1             278      SCONN288_H44441004_PIP-SCONN,HA
M_M_DQS_DP<7>            J9L1             278      SCONN288_H44441003_PIP-SCONN,HA
M_M_DQS_DP<7>            U2D1             DB29     SKX_EXT_B_BGA1-IC,TBD
M_M_DQS_DP<8>            J1A1             197      SCONN288_H44441004_PIP-SCONN,HA
M_M_DQS_DP<8>            J9L1             197      SCONN288_H44441003_PIP-SCONN,HA
M_M_DQS_DP<8>            U2D1             CL70     SKX_EXT_B_BGA1-IC,TBD
M_M_DQS_DP<9>            J1A1             7        SCONN288_H44441004_PIP-SCONN,HA
M_M_DQS_DP<9>            J9L1             7        SCONN288_H44441003_PIP-SCONN,HA
M_M_DQS_DP<9>            U2D1             CU74     SKX_EXT_B_BGA1-IC,TBD
M_M_DQS_DP<10>           J1A1             18       SCONN288_H44441004_PIP-SCONN,HA
M_M_DQS_DP<10>           J9L1             18       SCONN288_H44441003_PIP-SCONN,HA
M_M_DQS_DP<10>           U2D1             DG74     SKX_EXT_B_BGA1-IC,TBD
M_M_DQS_DP<11>           J1A1             29       SCONN288_H44441004_PIP-SCONN,HA
M_M_DQS_DP<11>           J9L1             29       SCONN288_H44441003_PIP-SCONN,HA
M_M_DQS_DP<11>           U2D1             DH69     SKX_EXT_B_BGA1-IC,TBD
M_M_DQS_DP<12>           J1A1             40       SCONN288_H44441004_PIP-SCONN,HA
M_M_DQS_DP<12>           J9L1             40       SCONN288_H44441003_PIP-SCONN,HA
M_M_DQS_DP<12>           U2D1             CM65     SKX_EXT_B_BGA1-IC,TBD
M_M_DQS_DP<13>           J1A1             99       SCONN288_H44441004_PIP-SCONN,HA
M_M_DQS_DP<13>           J9L1             99       SCONN288_H44441003_PIP-SCONN,HA
M_M_DQS_DP<13>           U2D1             DC40     SKX_EXT_B_BGA1-IC,TBD
M_M_DQS_DP<14>           J1A1             110      SCONN288_H44441004_PIP-SCONN,HA
M_M_DQS_DP<14>           J9L1             110      SCONN288_H44441003_PIP-SCONN,HA
M_M_DQS_DP<14>           U2D1             DE32     SKX_EXT_B_BGA1-IC,TBD
M_M_DQS_DP<15>           J1A1             121      SCONN288_H44441004_PIP-SCONN,HA
M_M_DQS_DP<15>           J9L1             121      SCONN288_H44441003_PIP-SCONN,HA
M_M_DQS_DP<15>           U2D1             CV35     SKX_EXT_B_BGA1-IC,TBD
M_M_DQS_DP<16>           J1A1             132      SCONN288_H44441004_PIP-SCONN,HA
M_M_DQS_DP<16>           J9L1             132      SCONN288_H44441003_PIP-SCONN,HA
M_M_DQS_DP<16>           U2D1             CV29     SKX_EXT_B_BGA1-IC,TBD
M_M_DQS_DP<17>           J1A1             51       SCONN288_H44441004_PIP-SCONN,HA
M_M_DQS_DP<17>           J9L1             51       SCONN288_H44441003_PIP-SCONN,HA
M_M_DQS_DP<17>           U2D1             CG70     SKX_EXT_B_BGA1-IC,TBD
M_M_ECC<0>               J1A1             194      SCONN288_H44441004_PIP-SCONN,HA
M_M_ECC<0>               J9L1             49       SCONN288_H44441003_PIP-SCONN,HA
M_M_ECC<0>               U2D1             CH71     SKX_EXT_B_BGA1-IC,TBD
M_M_ECC<1>               J1A1             49       SCONN288_H44441004_PIP-SCONN,HA
M_M_ECC<1>               J9L1             194      SCONN288_H44441003_PIP-SCONN,HA
M_M_ECC<1>               U2D1             CM71     SKX_EXT_B_BGA1-IC,TBD
M_M_ECC<2>               J1A1             201      SCONN288_H44441004_PIP-SCONN,HA
M_M_ECC<2>               J9L1             56       SCONN288_H44441003_PIP-SCONN,HA
M_M_ECC<2>               U2D1             CJ68     SKX_EXT_B_BGA1-IC,TBD
M_M_ECC<3>               J1A1             56       SCONN288_H44441004_PIP-SCONN,HA
M_M_ECC<3>               J9L1             201      SCONN288_H44441003_PIP-SCONN,HA
M_M_ECC<3>               U2D1             CL68     SKX_EXT_B_BGA1-IC,TBD
M_M_ECC<4>               J1A1             192      SCONN288_H44441004_PIP-SCONN,HA
M_M_ECC<4>               J9L1             47       SCONN288_H44441003_PIP-SCONN,HA
M_M_ECC<4>               U2D1             CJ72     SKX_EXT_B_BGA1-IC,TBD
M_M_ECC<5>               J1A1             47       SCONN288_H44441004_PIP-SCONN,HA
M_M_ECC<5>               J9L1             192      SCONN288_H44441003_PIP-SCONN,HA
M_M_ECC<5>               U2D1             CL72     SKX_EXT_B_BGA1-IC,TBD
M_M_ECC<6>               J1A1             199      SCONN288_H44441004_PIP-SCONN,HA
M_M_ECC<6>               J9L1             54       SCONN288_H44441003_PIP-SCONN,HA
M_M_ECC<6>               U2D1             CH69     SKX_EXT_B_BGA1-IC,TBD
M_M_ECC<7>               J1A1             54       SCONN288_H44441004_PIP-SCONN,HA
M_M_ECC<7>               J9L1             199      SCONN288_H44441003_PIP-SCONN,HA
M_M_ECC<7>               U2D1             CM69     SKX_EXT_B_BGA1-IC,TBD
M_M_MA<0>                J1A1             79       SCONN288_H44441004_PIP-SCONN,HA
M_M_MA<0>                J9L1             79       SCONN288_H44441003_PIP-SCONN,HA
M_M_MA<0>                U2D1             DF53     SKX_EXT_B_BGA1-IC,TBD
M_M_MA<1>                J1A1             72       SCONN288_H44441004_PIP-SCONN,HA
M_M_MA<1>                J9L1             72       SCONN288_H44441003_PIP-SCONN,HA
M_M_MA<1>                U2D1             DC58     SKX_EXT_B_BGA1-IC,TBD
M_M_MA<2>                J1A1             216      SCONN288_H44441004_PIP-SCONN,HA
M_M_MA<2>                J9L1             216      SCONN288_H44441003_PIP-SCONN,HA
M_M_MA<2>                U2D1             DD57     SKX_EXT_B_BGA1-IC,TBD
M_M_MA<3>                J1A1             71       SCONN288_H44441004_PIP-SCONN,HA
M_M_MA<3>                J9L1             71       SCONN288_H44441003_PIP-SCONN,HA
M_M_MA<3>                U2D1             DG58     SKX_EXT_B_BGA1-IC,TBD
M_M_MA<4>                J1A1             214      SCONN288_H44441004_PIP-SCONN,HA
M_M_MA<4>                J9L1             214      SCONN288_H44441003_PIP-SCONN,HA
M_M_MA<4>                U2D1             DJ58     SKX_EXT_B_BGA1-IC,TBD
M_M_MA<5>                J1A1             213      SCONN288_H44441004_PIP-SCONN,HA
M_M_MA<5>                J9L1             213      SCONN288_H44441003_PIP-SCONN,HA
M_M_MA<5>                U2D1             DF59     SKX_EXT_B_BGA1-IC,TBD
M_M_MA<6>                J1A1             69       SCONN288_H44441004_PIP-SCONN,HA
M_M_MA<6>                J9L1             69       SCONN288_H44441003_PIP-SCONN,HA
M_M_MA<6>                U2D1             DK59     SKX_EXT_B_BGA1-IC,TBD
M_M_MA<7>                J1A1             211      SCONN288_H44441004_PIP-SCONN,HA
M_M_MA<7>                J9L1             211      SCONN288_H44441003_PIP-SCONN,HA
M_M_MA<7>                U2D1             DC60     SKX_EXT_B_BGA1-IC,TBD
M_M_MA<8>                J1A1             68       SCONN288_H44441004_PIP-SCONN,HA
M_M_MA<8>                J9L1             68       SCONN288_H44441003_PIP-SCONN,HA
M_M_MA<8>                U2D1             DD59     SKX_EXT_B_BGA1-IC,TBD
M_M_MA<9>                J1A1             66       SCONN288_H44441004_PIP-SCONN,HA
M_M_MA<9>                J9L1             66       SCONN288_H44441003_PIP-SCONN,HA
M_M_MA<9>                U2D1             DA58     SKX_EXT_B_BGA1-IC,TBD
M_M_MA<10>               J1A1             225      SCONN288_H44441004_PIP-SCONN,HA
M_M_MA<10>               J9L1             225      SCONN288_H44441003_PIP-SCONN,HA
M_M_MA<10>               U2D1             DD55     SKX_EXT_B_BGA1-IC,TBD
M_M_MA<11>               J1A1             210      SCONN288_H44441004_PIP-SCONN,HA
M_M_MA<11>               J9L1             210      SCONN288_H44441003_PIP-SCONN,HA
M_M_MA<11>               U2D1             DA60     SKX_EXT_B_BGA1-IC,TBD
M_M_MA<12>               J1A1             65       SCONN288_H44441004_PIP-SCONN,HA
M_M_MA<12>               J9L1             65       SCONN288_H44441003_PIP-SCONN,HA
M_M_MA<12>               U2D1             DG60     SKX_EXT_B_BGA1-IC,TBD
M_M_MA<13>               J1A1             232      SCONN288_H44441004_PIP-SCONN,HA
M_M_MA<13>               J9L1             232      SCONN288_H44441003_PIP-SCONN,HA
M_M_MA<13>               U2D1             DD53     SKX_EXT_B_BGA1-IC,TBD
M_M_MA<14>               J1A1             228      SCONN288_H44441004_PIP-SCONN,HA
M_M_MA<14>               J9L1             228      SCONN288_H44441003_PIP-SCONN,HA
M_M_MA<14>               U2D1             DJ50     SKX_EXT_B_BGA1-IC,TBD
M_M_MA<15>               J1A1             86       SCONN288_H44441004_PIP-SCONN,HA
M_M_MA<15>               J9L1             86       SCONN288_H44441003_PIP-SCONN,HA
M_M_MA<15>               U2D1             DC54     SKX_EXT_B_BGA1-IC,TBD
M_M_MA<16>               J1A1             82       SCONN288_H44441004_PIP-SCONN,HA
M_M_MA<16>               J9L1             82       SCONN288_H44441003_PIP-SCONN,HA
M_M_MA<16>               U2D1             DG52     SKX_EXT_B_BGA1-IC,TBD
M_M_MA<17>               J1A1             234      SCONN288_H44441004_PIP-SCONN,HA
M_M_MA<17>               J9L1             234      SCONN288_H44441003_PIP-SCONN,HA
M_M_MA<17>               U2D1             DE46     SKX_EXT_B_BGA1-IC,TBD
M_M_ODT<0>               J1A1             87       SCONN288_H44441004_PIP-SCONN,HA
M_M_ODT<0>               U2D1             DG50     SKX_EXT_B_BGA1-IC,TBD
M_M_ODT<1>               J1A1             91       SCONN288_H44441004_PIP-SCONN,HA
M_M_ODT<1>               U2D1             DG48     SKX_EXT_B_BGA1-IC,TBD
M_M_ODT<2>               J9L1             87       SCONN288_H44441003_PIP-SCONN,HA
M_M_ODT<2>               U2D1             DK49     SKX_EXT_B_BGA1-IC,TBD
M_M_ODT<3>               J9L1             91       SCONN288_H44441003_PIP-SCONN,HA
M_M_ODT<3>               U2D1             DF47     SKX_EXT_B_BGA1-IC,TBD
M_M_PAR                  J1A1             222      SCONN288_H44441004_PIP-SCONN,HA
M_M_PAR                  J9L1             222      SCONN288_H44441003_PIP-SCONN,HA
M_M_PAR                  U2D1             DK53     SKX_EXT_B_BGA1-IC,TBD
M_M_VREF                 C1A5             1        CAP_A_0402V-0.01UF,25V,10%,X7RA
M_M_VREF                 C9L1             1        CAP_A_0402V-0.01UF,25V,10%,X7RA
M_M_VREF                 J1A1             146      SCONN288_H44441004_PIP-SCONN,HA
M_M_VREF                 J9L1             146      SCONN288_H44441003_PIP-SCONN,HA
M_M_VREF                 R9L1             1        RES_0402-1.00K,1%,1/16W,CHIP,GA
M_M_VREF                 R9L2             2        RES_0402-1.00K,1%,1/16W,CHIP,GA
M_M_VREF                 R9L3             2        RES_0402-2,1.0%,1/16W,CHIP,G21A
NC_CLK_156M_CPU0_OSC     Y6F1             2        OSC_C_6P10-156.25MHZ,OSC,G6383A
NC_CLK_156M_CPU1_OSC     Y3F1             2        OSC_C_6P10-156.25MHZ,OSC,G6383A
NC_CPLD1                 U8D7             A2       LCMXO2_A_256BGA-IC,H63395-001
NC_DB1200ZL<0>           EU4D2            3        NB3W1200L_LCC-IC,H13585-001
NC_DB1200ZL<1>           EU4D2            16       NB3W1200L_LCC-IC,H13585-001
NC_DB1200ZL<2>           EU4D2            15       NB3W1200L_LCC-IC,H13585-001
NC_M2<0>                 J8F1             6        SCONN75K_H17033002_SMT1-SCONN,A
NC_M2<1>                 J8F1             8        SCONN75K_H17033002_SMT1-SCONN,A
NC_M2<2>                 J8F1             20       SCONN75K_H17033002_SMT1-SCONN,A
NC_M2<3>                 J8F1             22       SCONN75K_H17033002_SMT1-SCONN,A
NC_M2<4>                 J8F1             24       SCONN75K_H17033002_SMT1-SCONN,A
NC_M2<5>                 J8F1             26       SCONN75K_H17033002_SMT1-SCONN,A
NC_M2<6>                 J8F1             28       SCONN75K_H17033002_SMT1-SCONN,A
NC_M2<7>                 J8F1             30       SCONN75K_H17033002_SMT1-SCONN,A
NC_M2<8>                 J8F1             32       SCONN75K_H17033002_SMT1-SCONN,A
NC_M2<9>                 J8F1             34       SCONN75K_H17033002_SMT1-SCONN,A
NC_M2<10>                J8F1             36       SCONN75K_H17033002_SMT1-SCONN,A
NC_M2<11>                J8F1             40       SCONN75K_H17033002_SMT1-SCONN,A
NC_M2<12>                J8F1             42       SCONN75K_H17033002_SMT1-SCONN,A
NC_M2<13>                J8F1             44       SCONN75K_H17033002_SMT1-SCONN,A
NC_M2<14>                J8F1             46       SCONN75K_H17033002_SMT1-SCONN,A
NC_M2<15>                J8F1             48       SCONN75K_H17033002_SMT1-SCONN,A
NC_M2<16>                J8F1             56       SCONN75K_H17033002_SMT1-SCONN,A
NC_M2<17>                J8F1             58       SCONN75K_H17033002_SMT1-SCONN,A
NC_M2<18>                J8F1             67       SCONN75K_H17033002_SMT1-SCONN,A
NC_P1V05_PCH_STBY_PH1_P31 EU7A2            31       IR354XX_SM-IR35412,IC,H73684-0A
NC_PI7C9X1172_1          EU9F3            1        PI7C9X1172_QFN-IC,H66899-001
NC_PI7C9X1172_8          EU9F3            8        PI7C9X1172_QFN-IC,H66899-001
NC_PVCCIN_CPU0_PH1_P31   EU4E1            31       IR354XX_SM-IR35411,IC,H73688-0A
NC_PVCCIN_CPU0_PH2_P31   EU4D6            31       IR354XX_SM-IR35411,IC,H73688-0A
NC_PVCCIN_CPU0_PH3_P31   EU4D3            31       IR354XX_SM-IR35411,IC,H73688-0A
NC_PVCCIN_CPU0_PH4_P31   EU4D1            31       IR354XX_SM-IR35411,IC,H73688-0A
NC_PVCCIN_CPU0_PH5_P31   EU4C2            31       IR354XX_SM-IR35411,IC,H73688-0A
NC_PVCCIN_CPU1_PH1_P31   EU1E2            31       IR354XX_SM-IR35411,IC,H73688-0A
NC_PVCCIN_CPU1_PH2_P31   EU1D4            31       IR354XX_SM-IR35411,IC,H73688-0A
NC_PVCCIN_CPU1_PH3_P31   EU1D3            31       IR354XX_SM-IR35411,IC,H73688-0A
NC_PVCCIN_CPU1_PH4_P31   EU1D1            31       IR354XX_SM-IR35411,IC,H73688-0A
NC_PVCCIN_CPU1_PH5_P31   EU1C3            31       IR354XX_SM-IR35411,IC,H73688-0A
NC_PVCCIO_CPU0_DNC0      EU3P1            1        PXE1110B_QFN-IC,H89187-001
NC_PVCCIO_CPU0_DNC1      EU3P1            2        PXE1110B_QFN-IC,H89187-001
NC_PVCCIO_CPU0_DNC2      EU3P1            4        PXE1110B_QFN-IC,H89187-001
NC_PVCCIO_CPU0_DNC3      EU3P1            24       PXE1110B_QFN-IC,H89187-001
NC_PVCCIO_CPU0_DNC4      EU3P1            28       PXE1110B_QFN-IC,H89187-001
NC_PVCCIO_CPU0_PH1_P31   EU7C1            31       IR354XX_SM-IR35412,IC,H73684-0A
NC_PVCCIO_CPU1_DNC0      EU4D5            1        PXE1110B_QFN-IC,H89187-001
NC_PVCCIO_CPU1_DNC1      EU4D5            2        PXE1110B_QFN-IC,H89187-001
NC_PVCCIO_CPU1_DNC2      EU4D5            4        PXE1110B_QFN-IC,H89187-001
NC_PVCCIO_CPU1_DNC3      EU4D5            24       PXE1110B_QFN-IC,H89187-001
NC_PVCCIO_CPU1_DNC4      EU4D5            28       PXE1110B_QFN-IC,H89187-001
NC_PVCCIO_CPU1_PH1_P31   EU4E2            31       IR354XX_SM-IR35412,IC,H73684-0A
NC_PVDDQ_ABC_DNC0        EU7G1            2        PXM1310B_QFN-IC,H89186-001
NC_PVDDQ_ABC_DNC1        EU7G1            28       PXM1310B_QFN-IC,H89186-001
NC_PVDDQ_ABC_PH1_P31     EU7G2            31       IR354XX_SM-IR35411,IC,H73688-0A
NC_PVDDQ_ABC_PH2_P31     EU7G3            31       IR354XX_SM-IR35411,IC,H73688-0A
NC_PVDDQ_DEF_DNC0        EU7A5            2        PXM1310B_QFN-IC,H89186-001
NC_PVDDQ_DEF_DNC1        EU7A5            28       PXM1310B_QFN-IC,H89186-001
NC_PVDDQ_DEF_PH1_P31     EU7A1            31       IR354XX_SM-IR35411,IC,H73688-0A
NC_PVDDQ_DEF_PH2_P31     EU7A4            31       IR354XX_SM-IR35411,IC,H73688-0A
NC_PVDDQ_GHJ_DNC0        EU1G2            2        PXM1310B_QFN-IC,H89186-001
NC_PVDDQ_GHJ_DNC1        EU1G2            28       PXM1310B_QFN-IC,H89186-001
NC_PVDDQ_GHJ_PH1_P31     EU1G1            31       IR354XX_SM-IR35411,IC,H73688-0A
NC_PVDDQ_GHJ_PH2_P31     EU1F1            31       IR354XX_SM-IR35411,IC,H73688-0A
NC_PVDDQ_GHJ_PINALRT_N   EU1G2            12       PXM1310B_QFN-IC,H89186-001
NC_PVDDQ_KLM_DNC0        EU1B1            2        PXM1310B_QFN-IC,H89186-001
NC_PVDDQ_KLM_DNC1        EU1B1            28       PXM1310B_QFN-IC,H89186-001
NC_PVDDQ_KLM_GP0         EU1B1            18       PXM1310B_QFN-IC,H89186-001
NC_PVDDQ_KLM_GP1         EU1B1            14       PXM1310B_QFN-IC,H89186-001
NC_PVDDQ_KLM_PH1_P31     EU1A2            31       IR354XX_SM-IR35411,IC,H73688-0A
NC_PVDDQ_KLM_PH2_P31     EU1A1            31       IR354XX_SM-IR35411,IC,H73688-0A
NC_PVDDQ_KLM_PINALRT_N   EU1B1            12       PXM1310B_QFN-IC,H89186-001
NC_PVDDQ_KLM_PWM3        EU1B1            3        PXM1310B_QFN-IC,H89186-001
NC_PVNN_PCH_DNC0         EU8A1            1        PXE1110B_QFN-IC,H89187-001
NC_PVNN_PCH_DNC1         EU8A1            2        PXE1110B_QFN-IC,H89187-001
NC_PVNN_PCH_DNC2         EU8A1            4        PXE1110B_QFN-IC,H89187-001
NC_PVNN_PCH_DNC3         EU8A1            24       PXE1110B_QFN-IC,H89187-001
NC_PVNN_PCH_DNC4         EU8A1            28       PXE1110B_QFN-IC,H89187-001
NC_PVNN_PCH_PH1_P31      EU7A3            31       IR354XX_SM-IR35412,IC,H73684-0A
NC_PVSA_CPU0_P31         EU4C1            31       IR354XX_SM-IR35412,IC,H73684-0A
NC_PVSA_CPU1_P31         EU1C1            31       IR354XX_SM-IR35412,IC,H73684-0A
NC_SPRNGVLLE_22          EU9E1            22       SPRINGVILLE_SM1-IC,G47144-004
NIC_LED_ACT_ANODE_R      JA9G1            L4       CONN17_H71061002_PIP1-CONN,H71A
NIC_LED_ACT_ANODE_R      R9G4             1        RES_0402-0.0,5%,1/16W,CHIP,G21A
NIC_MDI_MNG_RX_DN        C9G12            2        CAP_0402LF-4700PF,50V,10%,EMPTA
NIC_MDI_MNG_RX_DN        J1F1             E5       CONN76_H22707001_THMT1-CONN,H2A
NIC_MDI_MNG_RX_DP        C9G9             2        CAP_0402LF-4700PF,50V,10%,EMPTA
NIC_MDI_MNG_RX_DP        J1F1             D5       CONN76_H22707001_THMT1-CONN,H2A
NIC_MDI_MNG_TX_DN        C9G13            2        CAP_0402LF-4700PF,50V,10%,EMPTA
NIC_MDI_MNG_TX_DN        J1F1             B5       CONN76_H22707001_THMT1-CONN,H2A
NIC_MDI_MNG_TX_DP        C9G16            2        CAP_0402LF-4700PF,50V,10%,EMPTA
NIC_MDI_MNG_TX_DP        J1F1             A5       CONN76_H22707001_THMT1-CONN,H2A
NIC_MDI_SPRV_RJ45_0_DN   EU9E1            57       SPRINGVILLE_SM1-IC,G47144-004
NIC_MDI_SPRV_RJ45_0_DN   R9G22            1        RES_0402-0.0,5%,1/16W,CHIP,G21A
NIC_MDI_SPRV_RJ45_0_DP   EU9E1            58       SPRINGVILLE_SM1-IC,G47144-004
NIC_MDI_SPRV_RJ45_0_DP   R9G24            1        RES_0402-0.0,5%,1/16W,CHIP,G21A
NIC_MDI_SPRV_RJ45_0_R_DN JA9G1            R10      CONN17_H71061002_PIP1-CONN,H71A
NIC_MDI_SPRV_RJ45_0_R_DN R9G22            2        RES_0402-0.0,5%,1/16W,CHIP,G21A
NIC_MDI_SPRV_RJ45_0_R_DP JA9G1            R11      CONN17_H71061002_PIP1-CONN,H71A
NIC_MDI_SPRV_RJ45_0_R_DP R9G24            2        RES_0402-0.0,5%,1/16W,CHIP,G21A
NIC_MDI_SPRV_RJ45_1_DN   EU9E1            54       SPRINGVILLE_SM1-IC,G47144-004
NIC_MDI_SPRV_RJ45_1_DN   R9G20            1        RES_0402-0.0,5%,1/16W,CHIP,G21A
NIC_MDI_SPRV_RJ45_1_DP   EU9E1            55       SPRINGVILLE_SM1-IC,G47144-004
NIC_MDI_SPRV_RJ45_1_DP   R9G19            1        RES_0402-0.0,5%,1/16W,CHIP,G21A
NIC_MDI_SPRV_RJ45_1_R_DN JA9G1            R5       CONN17_H71061002_PIP1-CONN,H71A
NIC_MDI_SPRV_RJ45_1_R_DN R9G20            2        RES_0402-0.0,5%,1/16W,CHIP,G21A
NIC_MDI_SPRV_RJ45_1_R_DP JA9G1            R4       CONN17_H71061002_PIP1-CONN,H71A
NIC_MDI_SPRV_RJ45_1_R_DP R9G19            2        RES_0402-0.0,5%,1/16W,CHIP,G21A
NIC_MDI_SPRV_RJ45_2_R_DN JA9G1            R2       CONN17_H71061002_PIP1-CONN,H71A
NIC_MDI_SPRV_RJ45_2_R_DN R9G17            2        RES_0402-0.0,5%,1/16W,CHIP,G21A
NIC_MDI_SPRV_RJ45_2_R_DP JA9G1            R3       CONN17_H71061002_PIP1-CONN,H71A
NIC_MDI_SPRV_RJ45_2_R_DP R9G18            2        RES_0402-0.0,5%,1/16W,CHIP,G21A
NIC_MDI_SPRV_RJ45_3_R_DN JA9G1            R9       CONN17_H71061002_PIP1-CONN,H71A
NIC_MDI_SPRV_RJ45_3_R_DN R9G11            2        RES_0402-0.0,5%,1/16W,CHIP,G21A
NIC_MDI_SPRV_RJ45_3_R_DP JA9G1            R8       CONN17_H71061002_PIP1-CONN,H71A
NIC_MDI_SPRV_RJ45_3_R_DP R9G9             2        RES_0402-0.0,5%,1/16W,CHIP,G21A
NIC_SER_N_MDI_3_DN       C9G12            1        CAP_0402LF-4700PF,50V,10%,EMPTA
NIC_SER_N_MDI_3_DN       EU9E1            49       SPRINGVILLE_SM1-IC,G47144-004
NIC_SER_N_MDI_3_DN       R9G11            1        RES_0402-0.0,5%,1/16W,CHIP,G21A
NIC_SER_P_MDI_3_DP       C9G9             1        CAP_0402LF-4700PF,50V,10%,EMPTA
NIC_SER_P_MDI_3_DP       EU9E1            50       SPRINGVILLE_SM1-IC,G47144-004
NIC_SER_P_MDI_3_DP       R9G9             1        RES_0402-0.0,5%,1/16W,CHIP,G21A
NIC_SET_N_MDI_2_DN       C9G13            1        CAP_0402LF-4700PF,50V,10%,EMPTA
NIC_SET_N_MDI_2_DN       EU9E1            52       SPRINGVILLE_SM1-IC,G47144-004
NIC_SET_N_MDI_2_DN       R9G17            1        RES_0402-0.0,5%,1/16W,CHIP,G21A
NIC_SET_P_MDI_2_DP       C9G16            1        CAP_0402LF-4700PF,50V,10%,EMPTA
NIC_SET_P_MDI_2_DP       EU9E1            53       SPRINGVILLE_SM1-IC,G47144-004
NIC_SET_P_MDI_2_DP       R9G18            1        RES_0402-0.0,5%,1/16W,CHIP,G21A
P0V7_GTL2014_2           C1U22            1        CAP_A_0402V-0.1UF,16V,10%,X7R,A
P0V7_GTL2014_2           R1U37            1        RES_0402-100.0,1%,1/16W,CHIP,GA
P0V7_GTL2014_2           R1U43            2        RES_0402-49.9,1%,1/16W,CHIP,G2A
P0V7_GTL2014_2           U9G1             4        GTL2014_SM-IC,D66151-001
P0V7_GTL2104_5_VREF      C2T32            1        CAP_A_0402V-0.1UF,16V,10%,X7R,A
P0V7_GTL2104_5_VREF      R2T36            2        RES_0402-49.9,1%,1/16W,CHIP,G2A
P0V7_GTL2104_5_VREF      R2T39            1        RES_0402-100.0,1%,1/16W,CHIP,GA
P0V7_GTL2104_5_VREF      U2T4             4        GTL2014_SM-IC,D66151-001
P0V7_GTL2104_VREF_0      C7D5             1        CAP_A_0402V-0.1UF,16V,10%,X7R,A
P0V7_GTL2104_VREF_0      R7D32            1        RES_0402-100.0,1%,1/16W,CHIP,GA
P0V7_GTL2104_VREF_0      R7D33            2        RES_0402-49.9,1%,1/16W,CHIP,G2A
P0V7_GTL2104_VREF_0      U7D2             4        GTL2014_SM-IC,D66151-001
P0V7_GTL2104_VREF_1      C3P49            1        CAP_A_0402V-0.1UF,16V,10%,X7R,A
P0V7_GTL2104_VREF_1      R3P45            2        RES_0402-49.9,1%,1/16W,CHIP,G2A
P0V7_GTL2104_VREF_1      R3P49            1        RES_0402-100.0,1%,1/16W,CHIP,GA
P0V7_GTL2104_VREF_1      U3P2             4        GTL2014_SM-IC,D66151-001
P0V9_LAN                 C1R15            1        CAP_A_0402V-0.1UF,16V,10%,X7R,A
P0V9_LAN                 C1R16            1        CAP_0603-10UF,6.3V,20%,X6S,E15A
P0V9_LAN                 C1R18            1        CAP_A_0402V-0.1UF,16V,10%,X7R,A
P0V9_LAN                 C1R24            1        CAP_A_0402V-0.1UF,16V,10%,X7R,A
P0V9_LAN                 C1T4             1        CAP_0603-10UF,6.3V,20%,X6S,E15A
P0V9_LAN                 C1T5             1        CAP_A_0402V-0.1UF,16V,10%,X7R,A
P0V9_LAN                 C9E1             1        CAP_A_0603V-22.0UF,4V,20%,EMPTA
P0V9_LAN                 C9E12            1        CAP_A_0603V-22.0UF,4V,20%,EMPTA
P0V9_LAN                 EU9E1            11       SPRINGVILLE_SM1-IC,G47144-004
P0V9_LAN                 EU9E1            32       SPRINGVILLE_SM1-IC,G47144-004
P0V9_LAN                 EU9E1            42       SPRINGVILLE_SM1-IC,G47144-004
P0V9_LAN                 EU9E1            59       SPRINGVILLE_SM1-IC,G47144-004
P0V9_LAN                 R1R15            1        RES_0603-0,5.0%,1/10W,CHIP,G22A
P0V9_LAN_I210            EU9E1            38       SPRINGVILLE_SM1-IC,G47144-004
P0V9_LAN_I210            R1R15            2        RES_0603-0,5.0%,1/10W,CHIP,G22A
P12V                     C2U20            1        CAP_A_0402V-0.1UF,16V,10%,X7R,A
P12V                     C2U24            1        CAP_A_0402V-0.1UF,16V,10%,X7R,A
P12V                     C7E8             1        CAP_0805-10UF,16V,10%,X6S,C953A
P12V                     C7E9             1        CAP_A_0402V-0.1UF,16V,10%,X7R,A
P12V                     EU7E1            6        SLG55021_SM-IC,G56246-001
P12V                     F9B1             1        FUSE_SM-IC,C94311-016
P12V                     J8G1             1        SCONN200_H68296001_SM-CONN,H68A
P12V                     J8G1             2        SCONN200_H68296001_SM-CONN,H68A
P12V                     J8G1             3        SCONN200_H68296001_SM-CONN,H68A
P12V                     J8G1             4        SCONN200_H68296001_SM-CONN,H68A
P12V                     J8G1             5        SCONN200_H68296001_SM-CONN,H68A
P12V                     J8G1             6        SCONN200_H68296001_SM-CONN,H68A
P12V                     J8G1             7        SCONN200_H68296001_SM-CONN,H68A
P12V                     J8G1             8        SCONN200_H68296001_SM-CONN,H68A
P12V                     J8G1             9        SCONN200_H68296001_SM-CONN,H68A
P12V                     J8G1             10       SCONN200_H68296001_SM-CONN,H68A
P12V                     J8G1             11       SCONN200_H68296001_SM-CONN,H68A
P12V                     J8G1             12       SCONN200_H68296001_SM-CONN,H68A
P12V                     Q7E7             1        MOSFET_N_LCC3-BSZ019N03LS,NFETA
P12V                     R8D38            1        RES_0402-100.0K,1%,1/16W,CHIP,A
P12V_FAN                 C1B18            1        CAP_0805-10UF,16V,10%,X6S,C953A
P12V_FAN                 C1B19            1        CAP_A_0402V-0.1UF,16V,10%,X7R,A
P12V_FAN                 C1E20            1        CAP_A_0402V-0.1UF,16V,10%,X7R,A
P12V_FAN                 C1E21            1        CAP_0805-10UF,16V,10%,X6S,C953A
P12V_FAN                 C9M4             1        CAP_0805-10UF,16V,10%,X6S,C953A
P12V_FAN                 C9M5             1        CAP_A_0402V-0.1UF,16V,10%,X7R,A
P12V_FAN                 EU9M1            6        SLG55021_SM-IC,G56246-001
P12V_FAN                 J1B2             2        CONN6_C74770005_PIP-HDR,C74770A
P12V_FAN                 J1F2             2        CONN6_C74770005_PIP-HDR,C74770A
P12V_FAN                 Q1B1             1        MOSFET_N_LCC3-BSZ019N03LS,NFETA
P12V_FAN_SWITCH_G        EU9M1            7        SLG55021_SM-IC,G56246-001
P12V_FAN_SWITCH_G        Q1B1             4        MOSFET_N_LCC3-BSZ019N03LS,NFETA
P12V_HDD_SATA            C9B2             1        CAP_0805-10UF,16V,10%,X6S,C953A
P12V_HDD_SATA            F9B1             2        FUSE_SM-IC,C94311-016
P12V_HDD_SATA            J2L1             4        CONN4_H73295001_PIP-CONN,H7329A
P12V_HDD_SATA            J8A4             4        CONN4_H73295001_PIP-EMPTY,H732A
P12V_HSC_SENN0           R1D47            1        RES_0402-10.0,1%,1/16W,CHIP,G2A
P12V_HSC_SENN0           R1D49            4        RES_PWR_6PAD-0.001,1%,3W,CHIP,A
P12V_HSC_SENN1           R9P26            1        RES_0402-10.0,1%,1/16W,CHIP,G2A
P12V_HSC_SENN1           R9R1             4        RES_PWR_6PAD-0.001,1%,3W,CHIP,A
P12V_HSC_SENP0           R1D46            1        RES_0402-10.0,1%,1/16W,CHIP,G2A
P12V_HSC_SENP0           R1D49            3        RES_PWR_6PAD-0.001,1%,3W,CHIP,A
P12V_HSC_SENP1           R9P27            1        RES_0402-10.0,1%,1/16W,CHIP,G2A
P12V_HSC_SENP1           R9R1             3        RES_PWR_6PAD-0.001,1%,3W,CHIP,A
P12V_HSC_VCC             C1D25            1        CAP_0402-1.0UF,16V,10%,X6S,D97A
P12V_HSC_VCC             EU1D2            30       ADM1278_SM-IC,G99251-001
P12V_HSC_VCC             R9P30            2        RES_0603-10.0,1%,1/10W,CHIP,G2A
P12V_MB0_SW              EU1E1            5        MOSFETN_1D3S_SOT5-IC,G68777-001
P12V_MB0_SW              EU1E3            5        MOSFETN_1D3S_SOT5-IC,G68777-001
P12V_MB0_SW              EU9R1            5        MOSFETN_1D3S_SOT5-IC,G68777-001
P12V_MB0_SW              R1D49            2        RES_PWR_6PAD-0.001,1%,3W,CHIP,A
P12V_MB0_SW              R1D49            6        RES_PWR_6PAD-0.001,1%,3W,CHIP,A
P12V_MB0_SW              R9R1             2        RES_PWR_6PAD-0.001,1%,3W,CHIP,A
P12V_MB0_SW              R9R1             6        RES_PWR_6PAD-0.001,1%,3W,CHIP,A
P12V_NVDIMM_ABC          C6T2             1        CAP_0805-10UF,16V,10%,X7R,G106A
P12V_NVDIMM_ABC          C6U10            1        CAP_0805-10UF,16V,10%,X7R,G106A
P12V_NVDIMM_ABC          C6U18            1        CAP_0805-10UF,16V,10%,X7R,G106A
P12V_NVDIMM_ABC          J4G1             1        SCONN288_H44441004_PIP-SCONN,HA
P12V_NVDIMM_ABC          J4G1             145      SCONN288_H44441004_PIP-SCONN,HA
P12V_NVDIMM_ABC          J4G2             1        SCONN288_H44441004_PIP-SCONN,HA
P12V_NVDIMM_ABC          J4G2             145      SCONN288_H44441004_PIP-SCONN,HA
P12V_NVDIMM_ABC          J4G3             1        SCONN288_H44441004_PIP-SCONN,HA
P12V_NVDIMM_ABC          J4G3             145      SCONN288_H44441004_PIP-SCONN,HA
P12V_NVDIMM_ABC          J6T1             1        SCONN288_H44441003_PIP-SCONN,HA
P12V_NVDIMM_ABC          J6T1             145      SCONN288_H44441003_PIP-SCONN,HA
P12V_NVDIMM_ABC          J6U1             1        SCONN288_H44441003_PIP-SCONN,HA
P12V_NVDIMM_ABC          J6U1             145      SCONN288_H44441003_PIP-SCONN,HA
P12V_NVDIMM_ABC          J6U2             1        SCONN288_H44441003_PIP-SCONN,HA
P12V_NVDIMM_ABC          J6U2             145      SCONN288_H44441003_PIP-SCONN,HA
P12V_NVDIMM_ABC          R4F2             1        RES_1206-0.002,1%,1W,CHIP,G521A
P12V_NVDIMM_ABC          U4F1             4        MAX9634_SOT-IC,H35789-001
P12V_NVDIMM_DEF          C4A4             1        CAP_0805-10UF,16V,10%,X7R,G106A
P12V_NVDIMM_DEF          C4A17            1        CAP_0805-10UF,16V,10%,X7R,G106A
P12V_NVDIMM_DEF          C4B11            1        CAP_0805-10UF,16V,10%,X7R,G106A
P12V_NVDIMM_DEF          J4A1             1        SCONN288_H44441004_PIP-SCONN,HA
P12V_NVDIMM_DEF          J4A1             145      SCONN288_H44441004_PIP-SCONN,HA
P12V_NVDIMM_DEF          J4A2             1        SCONN288_H44441004_PIP-SCONN,HA
P12V_NVDIMM_DEF          J4A2             145      SCONN288_H44441004_PIP-SCONN,HA
P12V_NVDIMM_DEF          J4B1             1        SCONN288_H44441004_PIP-SCONN,HA
P12V_NVDIMM_DEF          J4B1             145      SCONN288_H44441004_PIP-SCONN,HA
P12V_NVDIMM_DEF          J6L1             1        SCONN288_H44441003_PIP-SCONN,HA
P12V_NVDIMM_DEF          J6L1             145      SCONN288_H44441003_PIP-SCONN,HA
P12V_NVDIMM_DEF          J6L2             1        SCONN288_H44441003_PIP-SCONN,HA
P12V_NVDIMM_DEF          J6L2             145      SCONN288_H44441003_PIP-SCONN,HA
P12V_NVDIMM_DEF          J6M1             1        SCONN288_H44441003_PIP-SCONN,HA
P12V_NVDIMM_DEF          J6M1             145      SCONN288_H44441003_PIP-SCONN,HA
P12V_NVDIMM_DEF          R4B12            1        RES_1206-0.002,1%,1W,CHIP,G521A
P12V_NVDIMM_DEF          U4B1             4        MAX9634_SOT-IC,H35789-001
P12V_NVDIMM_GHJ          C9T8             1        CAP_0805-10UF,16V,10%,X7R,G106A
P12V_NVDIMM_GHJ          C9U8             1        CAP_0805-10UF,16V,10%,X7R,G106A
P12V_NVDIMM_GHJ          C9U11            1        CAP_0805-10UF,16V,10%,X7R,G106A
P12V_NVDIMM_GHJ          J1G1             1        SCONN288_H44441004_PIP-SCONN,HA
P12V_NVDIMM_GHJ          J1G1             145      SCONN288_H44441004_PIP-SCONN,HA
P12V_NVDIMM_GHJ          J1G2             1        SCONN288_H44441004_PIP-SCONN,HA
P12V_NVDIMM_GHJ          J1G2             145      SCONN288_H44441004_PIP-SCONN,HA
P12V_NVDIMM_GHJ          J1G3             1        SCONN288_H44441004_PIP-SCONN,HA
P12V_NVDIMM_GHJ          J1G3             145      SCONN288_H44441004_PIP-SCONN,HA
P12V_NVDIMM_GHJ          J9T1             1        SCONN288_H44441003_PIP-SCONN,HA
P12V_NVDIMM_GHJ          J9T1             145      SCONN288_H44441003_PIP-SCONN,HA
P12V_NVDIMM_GHJ          J9U1             1        SCONN288_H44441003_PIP-SCONN,HA
P12V_NVDIMM_GHJ          J9U1             145      SCONN288_H44441003_PIP-SCONN,HA
P12V_NVDIMM_GHJ          J9U2             1        SCONN288_H44441003_PIP-SCONN,HA
P12V_NVDIMM_GHJ          J9U2             145      SCONN288_H44441003_PIP-SCONN,HA
P12V_NVDIMM_GHJ          R1F3             1        RES_1206-0.002,1%,1W,CHIP,G521A
P12V_NVDIMM_GHJ          U1F1             4        MAX9634_SOT-IC,H35789-001
P12V_NVDIMM_KLM          C1A4             1        CAP_0805-10UF,16V,10%,X7R,G106A
P12V_NVDIMM_KLM          C1A16            1        CAP_0805-10UF,16V,10%,X7R,G106A
P12V_NVDIMM_KLM          C1B7             1        CAP_0805-10UF,16V,10%,X7R,G106A
P12V_NVDIMM_KLM          J1A1             1        SCONN288_H44441004_PIP-SCONN,HA
P12V_NVDIMM_KLM          J1A1             145      SCONN288_H44441004_PIP-SCONN,HA
P12V_NVDIMM_KLM          J1A2             1        SCONN288_H44441004_PIP-SCONN,HA
P12V_NVDIMM_KLM          J1A2             145      SCONN288_H44441004_PIP-SCONN,HA
P12V_NVDIMM_KLM          J1B1             1        SCONN288_H44441004_PIP-SCONN,HA
P12V_NVDIMM_KLM          J1B1             145      SCONN288_H44441004_PIP-SCONN,HA
P12V_NVDIMM_KLM          J9L1             1        SCONN288_H44441003_PIP-SCONN,HA
P12V_NVDIMM_KLM          J9L1             145      SCONN288_H44441003_PIP-SCONN,HA
P12V_NVDIMM_KLM          J9L2             1        SCONN288_H44441003_PIP-SCONN,HA
P12V_NVDIMM_KLM          J9L2             145      SCONN288_H44441003_PIP-SCONN,HA
P12V_NVDIMM_KLM          J9M1             1        SCONN288_H44441003_PIP-SCONN,HA
P12V_NVDIMM_KLM          J9M1             145      SCONN288_H44441003_PIP-SCONN,HA
P12V_NVDIMM_KLM          R9M4             1        RES_1206-0.002,1%,1W,CHIP,G521A
P12V_NVDIMM_KLM          U1B1             4        MAX9634_SOT-IC,H35789-001
P12V_PSU                 C1E12            1        CAP_0805-10UF,16V,10%,X6S,C953A
P12V_PSU                 C1E15            1        CAP_0805-10UF,16V,10%,X6S,C953A
P12V_PSU                 C1E16            1        CAP_A_0402V-0.1UF,16V,10%,X7R,A
P12V_PSU                 C1E17            1        CAP_A_0402V-0.1UF,16V,10%,X7R,A
P12V_PSU                 C9R5             1        CAP_0805-10UF,16V,10%,X6S,C953A
P12V_PSU                 C9R6             1        CAP_A_0402V-0.1UF,16V,10%,X7R,A
P12V_PSU                 C9R12            1        CAP_A_0402V-0.1UF,16V,10%,X7R,A
P12V_PSU                 J1D1             A1       CONN12_G98257001_THMT-CONN,G98A
P12V_PSU                 J1D1             A2       CONN12_G98257001_THMT-CONN,G98A
P12V_PSU                 J1D1             A3       CONN12_G98257001_THMT-CONN,G98A
P12V_PSU                 J1D1             B1       CONN12_G98257001_THMT-CONN,G98A
P12V_PSU                 J1D1             B2       CONN12_G98257001_THMT-CONN,G98A
P12V_PSU                 J1D1             B3       CONN12_G98257001_THMT-CONN,G98A
P12V_PSU                 J1E1             A1       CONN12_G98257001_THMT-CONN,G98A
P12V_PSU                 J1E1             A2       CONN12_G98257001_THMT-CONN,G98A
P12V_PSU                 J1E1             A3       CONN12_G98257001_THMT-CONN,G98A
P12V_PSU                 J1E1             B1       CONN12_G98257001_THMT-CONN,G98A
P12V_PSU                 J1E1             B2       CONN12_G98257001_THMT-CONN,G98A
P12V_PSU                 J1E1             B3       CONN12_G98257001_THMT-CONN,G98A
P12V_PSU                 R1D15            1        RES_0402-100.0K,1%,1/16W,CHIP,A
P12V_PSU                 R1D49            1        RES_PWR_6PAD-0.001,1%,3W,CHIP,A
P12V_PSU                 R1D49            5        RES_PWR_6PAD-0.001,1%,3W,CHIP,A
P12V_PSU                 R9P28            1        RES_0402-100.0K,1%,1/16W,CHIP,A
P12V_PSU                 R9P29            1        RES_0402-100.0K,1%,1/16W,CHIP,A
P12V_PSU                 R9P30            1        RES_0603-10.0,1%,1/10W,CHIP,G2A
P12V_PSU                 R9R1             1        RES_PWR_6PAD-0.001,1%,3W,CHIP,A
P12V_PSU                 R9R1             5        RES_PWR_6PAD-0.001,1%,3W,CHIP,A
P12V_PSU                 R9T6             1        RES_0402-15.0K,1%,1/16W,CHIP,GA
P12V_PSU                 R9T9             1        RES_0402-4.75K,1%,1/16W,CHIP,GA
P12V_PSU                 VR1D1            1        ZENER_SM-13V,IC,H69095-001
P12V_STBY                C1B14            1        CAPP_4040LF-470UF,16V,20%,ALUMA
P12V_STBY                C1D9             1        CAP_A_0402V-0.1UF,16V,10%,X7R,A
P12V_STBY                C1F7             1        CAPP_4040LF-470UF,16V,20%,ALUMA
P12V_STBY                C1M5             1        CAPP_3018-68UF,16V,20%,TANT,72A
P12V_STBY                C1M22            1        CAP_A_0402V-0.1UF,16V,10%,X7R,A
P12V_STBY                C1M23            1        CAP_A_0402V-0.1UF,16V,10%,X7R,A
P12V_STBY                C1M26            1        CAP_0805-10UF,16V,10%,X6S,C953A
P12V_STBY                C1M27            1        CAP_0805-10UF,16V,10%,X6S,C953A
P12V_STBY                C1R23            1        CAPP_3018-68UF,16V,20%,TANT,72A
P12V_STBY                C2P10            1        CAP_1206LF-22UF,16V,10%,X6S,D3A
P12V_STBY                C2P11            1        CAP_A_0402V-0.1UF,16V,10%,X7R,A
P12V_STBY                C2P12            1        CAP_A_0402V-0.1UF,16V,10%,X7R,A
P12V_STBY                C2P13            1        CAP_A_0402V-0.1UF,16V,10%,X7R,A
P12V_STBY                C2P14            1        CAP_A_0402V-0.1UF,16V,10%,X7R,A
P12V_STBY                C2P15            1        CAP_A_0402V-0.1UF,16V,10%,X7R,A
P12V_STBY                C2P16            1        CAP_A_0402V-0.1UF,16V,10%,X7R,A
P12V_STBY                C2R15            1        CAP_A_0402V-0.1UF,16V,10%,X7R,A
P12V_STBY                C2R16            1        CAP_A_0402V-0.1UF,16V,10%,X7R,A
P12V_STBY                C2R17            1        CAP_A_0402V-0.1UF,16V,10%,X7R,A
P12V_STBY                C2R18            1        CAP_A_0402V-0.1UF,16V,10%,X7R,A
P12V_STBY                C3B6             1        CAPP_3018-68UF,16V,20%,TANT,72A
P12V_STBY                C3T3             1        CAPP_3018-68UF,16V,20%,TANT,72A
P12V_STBY                C3T6             1        CAPP_3018-68UF,16V,20%,TANT,72A
P12V_STBY                C3T13            1        CAPP_3018-68UF,16V,20%,TANT,72A
P12V_STBY                C3T15            1        CAPP_3018-68UF,16V,20%,TANT,72A
P12V_STBY                C4B13            1        CAPP_4040LF-470UF,16V,20%,ALUMA
P12V_STBY                C4B14            1        CAPP_3018-68UF,16V,20%,TANT,72A
P12V_STBY                C4F4             1        CAPP_3018-68UF,16V,20%,TANT,72A
P12V_STBY                C4F5             1        CAPP_3018-68UF,16V,20%,TANT,72A
P12V_STBY                C4F6             1        CAPP_4040LF-470UF,16V,20%,ALUMA
P12V_STBY                C4M6             1        CAPP_3018-68UF,16V,20%,TANT,72A
P12V_STBY                C4M7             1        CAPP_3018-68UF,16V,20%,TANT,72A
P12V_STBY                C6N5             1        CAPP_3018-68UF,16V,20%,TANT,72A
P12V_STBY                C7E5             1        CAP_A_0402V-0.1UF,16V,10%,X7R,A
P12V_STBY                C7E6             1        CAP_0805-10UF,16V,10%,X6S,C953A
P12V_STBY                C7M6             1        CAPP_3018-68UF,16V,20%,TANT,72A
P12V_STBY                C9M3             1        CAPP_3018-68UF,16V,20%,TANT,72A
P12V_STBY                C9M9             1        CAP_A_0402V-0.1UF,16V,10%,X7R,A
P12V_STBY                C9M10            1        CAP_0805-10UF,16V,10%,X6S,C953A
P12V_STBY                C9P6             1        CAP_A_0402V-0.1UF,16V,10%,X7R,A
P12V_STBY                C9T3             1        CAPP_3018-68UF,16V,20%,TANT,72A
P12V_STBY                CR1F5            1        DIODE_SM-MBRS340T3G,EMPTY,C819A
P12V_STBY                EU1E1            1        MOSFETN_1D3S_SOT5-IC,G68777-001
P12V_STBY                EU1E1            2        MOSFETN_1D3S_SOT5-IC,G68777-001
P12V_STBY                EU1E1            3        MOSFETN_1D3S_SOT5-IC,G68777-001
P12V_STBY                EU1E3            1        MOSFETN_1D3S_SOT5-IC,G68777-001
P12V_STBY                EU1E3            2        MOSFETN_1D3S_SOT5-IC,G68777-001
P12V_STBY                EU1E3            3        MOSFETN_1D3S_SOT5-IC,G68777-001
P12V_STBY                EU7E1            5        SLG55021_SM-IC,G56246-001
P12V_STBY                EU9M1            5        SLG55021_SM-IC,G56246-001
P12V_STBY                EU9R1            1        MOSFETN_1D3S_SOT5-IC,G68777-001
P12V_STBY                EU9R1            2        MOSFETN_1D3S_SOT5-IC,G68777-001
P12V_STBY                EU9R1            3        MOSFETN_1D3S_SOT5-IC,G68777-001
P12V_STBY                FB4A1            1        FERRITE_SM-22,FB,656554-051
P12V_STBY                FB4G1            1        FERRITE_SM-22,FB,656554-051
P12V_STBY                FB7B1            1        FERRITE_SM-22,FB,656554-051
P12V_STBY                FB7E1            1        FERRITE_SM-22,FB,656554-051
P12V_STBY                FB7F1            1        FERRITE_SM-22,FB,656554-051
P12V_STBY                FB9E1            1        FERRITE_SM-22,FB,656554-051
P12V_STBY                J4B2             A1       SCONN120_H61426002_SM-CONN,H61A
P12V_STBY                J4B2             A2       SCONN120_H61426002_SM-CONN,H61A
P12V_STBY                J4B2             A3       SCONN120_H61426002_SM-CONN,H61A
P12V_STBY                J4B2             A4       SCONN120_H61426002_SM-CONN,H61A
P12V_STBY                J4B2             A5       SCONN120_H61426002_SM-CONN,H61A
P12V_STBY                J4B2             A6       SCONN120_H61426002_SM-CONN,H61A
P12V_STBY                J4B2             A7       SCONN120_H61426002_SM-CONN,H61A
P12V_STBY                J4B2             A8       SCONN120_H61426002_SM-CONN,H61A
P12V_STBY                J4B2             B1       SCONN120_H61426002_SM-CONN,H61A
P12V_STBY                J4B2             B2       SCONN120_H61426002_SM-CONN,H61A
P12V_STBY                J4B2             B3       SCONN120_H61426002_SM-CONN,H61A
P12V_STBY                J4B2             B4       SCONN120_H61426002_SM-CONN,H61A
P12V_STBY                J4B2             B5       SCONN120_H61426002_SM-CONN,H61A
P12V_STBY                J4B2             B6       SCONN120_H61426002_SM-CONN,H61A
P12V_STBY                J4B2             B7       SCONN120_H61426002_SM-CONN,H61A
P12V_STBY                J4B2             B8       SCONN120_H61426002_SM-CONN,H61A
P12V_STBY                J6B1             A1       SCONN120_H61426002_SM-CONN,H61A
P12V_STBY                J6B1             A2       SCONN120_H61426002_SM-CONN,H61A
P12V_STBY                J6B1             A3       SCONN120_H61426002_SM-CONN,H61A
P12V_STBY                J6B1             A4       SCONN120_H61426002_SM-CONN,H61A
P12V_STBY                J6B1             A5       SCONN120_H61426002_SM-CONN,H61A
P12V_STBY                J6B1             A6       SCONN120_H61426002_SM-CONN,H61A
P12V_STBY                J6B1             A7       SCONN120_H61426002_SM-CONN,H61A
P12V_STBY                J6B1             A8       SCONN120_H61426002_SM-CONN,H61A
P12V_STBY                J6B1             B1       SCONN120_H61426002_SM-CONN,H61A
P12V_STBY                J6B1             B2       SCONN120_H61426002_SM-CONN,H61A
P12V_STBY                J6B1             B3       SCONN120_H61426002_SM-CONN,H61A
P12V_STBY                J6B1             B4       SCONN120_H61426002_SM-CONN,H61A
P12V_STBY                J6B1             B5       SCONN120_H61426002_SM-CONN,H61A
P12V_STBY                J6B1             B6       SCONN120_H61426002_SM-CONN,H61A
P12V_STBY                J6B1             B7       SCONN120_H61426002_SM-CONN,H61A
P12V_STBY                J6B1             B8       SCONN120_H61426002_SM-CONN,H61A
P12V_STBY                J8E3             2        SCONN80_E67482007_SM-CONN,E674A
P12V_STBY                J8E3             4        SCONN80_E67482007_SM-CONN,E674A
P12V_STBY                J8E4             33       SCONN64_H87568002_A_SMT-CONN,HA
P12V_STBY                J8E4             34       SCONN64_H87568002_A_SMT-CONN,HA
P12V_STBY                J8E4             35       SCONN64_H87568002_A_SMT-CONN,HA
P12V_STBY                J9B3             2        SCONN120_A28699018_SM-SCONN,A2A
P12V_STBY                J9B3             4        SCONN120_A28699018_SM-SCONN,A2A
P12V_STBY                J9B3             6        SCONN120_A28699018_SM-SCONN,A2A
P12V_STBY                L1B1             1        INDUCTOR_SM-100NH,IND,D92183-0B
P12V_STBY                L1B2             1        INDUCTOR_SM-100NH,IND,D92183-0A
P12V_STBY                L1F1             1        INDUCTOR_SM-100NH,IND,D92183-0B
P12V_STBY                L4C1             1        INDUCTOR_SM-100NH,IND,D92183-0A
P12V_STBY                L7A5             1        INDUCTOR_SM-100NH,IND,D92183-0B
P12V_STBY                L7C1             1        INDUCTOR_SM-100NH,IND,D92183-0B
P12V_STBY                L7F2             1        INDUCTOR_SM-100NH,IND,D92183-0B
P12V_STBY                Q1B1             5        MOSFET_N_LCC3-BSZ019N03LS,NFETA
P12V_STBY                Q7E7             5        MOSFET_N_LCC3-BSZ019N03LS,NFETA
P12V_STBY                R1D36            1        RES_0402-1.00K,1%,1/16W,CHIP,GA
P12V_STBY                R1F3             2        RES_1206-0.002,1%,1W,CHIP,G521A
P12V_STBY                R1L9             1        RES_0402-100.0K,1%,1/16W,CHIP,A
P12V_STBY                R1U32            1        RES_0402-5.11K,1%,1/16W,CHIP,GA
P12V_STBY                R3P48            1        RES_0402-90.9K,1%,1/16W,CHIP,GA
P12V_STBY                R4B12            2        RES_1206-0.002,1%,1W,CHIP,G521A
P12V_STBY                R4F2             2        RES_1206-0.002,1%,1W,CHIP,G521A
P12V_STBY                R9M4             2        RES_1206-0.002,1%,1W,CHIP,G521A
P12V_STBY                R9P7             1        RES_0402-249K,1.0%,1/16W,CHIP,A
P12V_STBY                R9P13            1        RES_0402-274K,1.0%,1/16W,CHIP,A
P12V_STBY                R9P18            1        RES_0402-15.0K,1%,1/16W,CHIP,GA
P12V_STBY                R9P23            1        RES_0402-100.0K,1%,1/16W,CHIP,A
P12V_STBY                R9P33            1        RES_0402-100.0K,1%,1/16W,CHIP,A
P12V_STBY                U1B1             5        MAX9634_SOT-IC,H35789-001
P12V_STBY                U1D2             2        TPS3700_SM-IC,H69492-001
P12V_STBY                U1F1             5        MAX9634_SOT-IC,H35789-001
P12V_STBY                U4B1             5        MAX9634_SOT-IC,H35789-001
P12V_STBY                U4F1             5        MAX9634_SOT-IC,H35789-001
P12V_STBY                U9P1             2        TPS3700_SM-IC,H69492-001
P12V_SWITCH_G            EU7E1            7        SLG55021_SM-IC,G56246-001
P12V_SWITCH_G            Q7E7             4        MOSFET_N_LCC3-BSZ019N03LS,NFETA
P1V05_PCH_STBY           C1L5             1        CAP_A_0402V-1.0UF,6.3V,10%,X6SA
P1V05_PCH_STBY           C2L25            1        CAPP_SM-470UF,2V,20%,ALUM,6990A
P1V05_PCH_STBY           C2L46            1        CAPP_SM-470UF,2V,20%,ALUM,6990A
P1V05_PCH_STBY           C2M6             1        CAP_A_0402V-1.0UF,6.3V,10%,X6SA
P1V05_PCH_STBY           C2M8             1        CAP_A_0402V-1.0UF,6.3V,10%,X6SA
P1V05_PCH_STBY           C2M11            1        CAP_0805-47UF,4V,20%,X6S,C9533A
P1V05_PCH_STBY           C2M12            1        CAP_A_0603V-22.0UF,4V,20%,X6S,A
P1V05_PCH_STBY           C2M13            1        CAP_A_0603V-22.0UF,4V,20%,X6S,A
P1V05_PCH_STBY           C2M17            1        CAP_0805-47UF,4V,20%,X6S,C9533A
P1V05_PCH_STBY           C2M18            1        CAP_A_0402V-1.0UF,6.3V,10%,X6SA
P1V05_PCH_STBY           C2M19            1        CAP_A_0402V-1.0UF,6.3V,10%,X6SA
P1V05_PCH_STBY           C2M20            1        CAP_A_0402V-1.0UF,6.3V,10%,X6SA
P1V05_PCH_STBY           C2M21            1        CAP_A_0402V-1.0UF,6.3V,10%,X6SA
P1V05_PCH_STBY           C2M22            1        CAP_A_0402V-1.0UF,6.3V,10%,X6SA
P1V05_PCH_STBY           C2M25            1        CAP_A_0402V-1.0UF,6.3V,10%,X6SA
P1V05_PCH_STBY           C2N2             1        CAP_A_0402V-1.0UF,6.3V,10%,X6SA
P1V05_PCH_STBY           C2N7             1        CAP_A_0402V-1.0UF,6.3V,10%,X6SA
P1V05_PCH_STBY           C2N8             1        CAP_A_0402V-1.0UF,6.3V,10%,X6SA
P1V05_PCH_STBY           C2N10            1        CAP_A_0603V-22.0UF,4V,20%,X6S,A
P1V05_PCH_STBY           C2N13            1        CAP_A_0402V-1.0UF,6.3V,10%,X6SA
P1V05_PCH_STBY           C3L19            1        CAPP_SM-470UF,2V,20%,ALUM,6990A
P1V05_PCH_STBY           C3M21            1        CAP_A_0402V-1.0UF,6.3V,10%,X6SA
P1V05_PCH_STBY           C3M22            1        CAP_A_0402V-1.0UF,6.3V,10%,X6SA
P1V05_PCH_STBY           C3M30            1        CAP_A_0402V-1.0UF,6.3V,10%,X6SA
P1V05_PCH_STBY           C3M31            1        CAP_A_0402V-1.0UF,6.3V,10%,X6SA
P1V05_PCH_STBY           C3M38            1        CAP_A_0402V-1.0UF,6.3V,10%,X6SA
P1V05_PCH_STBY           C3M39            1        CAP_A_0402V-1.0UF,6.3V,10%,X6SA
P1V05_PCH_STBY           C3M42            1        CAP_A_0402V-1.0UF,6.3V,10%,X6SA
P1V05_PCH_STBY           C3M43            1        CAP_A_0402V-1.0UF,6.3V,10%,X6SA
P1V05_PCH_STBY           C7A42            1        CAP_0805LF-22UF,4V,20%,X6S,C95A
P1V05_PCH_STBY           C7B15            1        CAP_A_0603V-22.0UF,4V,20%,X6S,A
P1V05_PCH_STBY           C7B16            1        CAP_A_0603V-22.0UF,4V,20%,X6S,A
P1V05_PCH_STBY           C7B17            1        CAP_A_0603V-22.0UF,4V,20%,X6S,A
P1V05_PCH_STBY           C7B18            1        CAP_A_0603V-22.0UF,4V,20%,X6S,A
P1V05_PCH_STBY           C7B19            1        CAP_A_0603V-22.0UF,4V,20%,X6S,A
P1V05_PCH_STBY           C7B20            1        CAP_A_0603V-22.0UF,4V,20%,X6S,A
P1V05_PCH_STBY           C7B21            1        CAP_A_0603V-22.0UF,4V,20%,X6S,A
P1V05_PCH_STBY           C7B22            1        CAP_A_0603V-22.0UF,4V,20%,X6S,A
P1V05_PCH_STBY           C7B23            1        CAP_A_0603V-22.0UF,4V,20%,X6S,A
P1V05_PCH_STBY           C7B24            1        CAP_A_0603V-22.0UF,4V,20%,X6S,A
P1V05_PCH_STBY           C8A13            1        CAP_0805-47UF,4V,20%,X6S,C9533A
P1V05_PCH_STBY           C8A15            1        CAPP_SM-470UF,2V,20%,ALUM,6990A
P1V05_PCH_STBY           C8B9             1        CAP_A_0603V-22.0UF,4V,20%,X6S,A
P1V05_PCH_STBY           C8B10            1        CAP_A_0603V-22.0UF,4V,20%,X6S,A
P1V05_PCH_STBY           C8B11            1        CAP_A_0603V-22.0UF,4V,20%,X6S,A
P1V05_PCH_STBY           C8B13            1        CAP_A_0603V-22.0UF,4V,20%,X6S,A
P1V05_PCH_STBY           C8B14            1        CAP_A_0603V-22.0UF,4V,20%,X6S,A
P1V05_PCH_STBY           C8B15            1        CAP_0805-47UF,4V,20%,X6S,C9533A
P1V05_PCH_STBY           C8B16            1        CAP_0805-47UF,4V,20%,X6S,C9533A
P1V05_PCH_STBY           C9A6             1        CAP_A_0402V-1.0UF,6.3V,10%,X6SA
P1V05_PCH_STBY           EU7A2            1        IR354XX_SM-IR35412,IC,H73684-0A
P1V05_PCH_STBY           FB1U3            2        FERRITE_SMLF-30,FB,693286-021
P1V05_PCH_STBY           FB2M1            1        FERRITE_SM-120,FB,693286-027
P1V05_PCH_STBY           FB2M2            1        FERRITE_SM-120,FB,693286-027
P1V05_PCH_STBY           FB3M1            1        FERRITE_SM-120,FB,693286-027
P1V05_PCH_STBY           FB3M2            1        FERRITE_SM-120,FB,693286-027
P1V05_PCH_STBY           FB3M3            1        FERRITE_SM-120,FB,693286-027
P1V05_PCH_STBY           FB3M4            1        FERRITE_SM-120,FB,693286-027
P1V05_PCH_STBY           J9A3             43       SCONN60_C21100002_SMLF-CONN,C2A
P1V05_PCH_STBY           J9A3             44       SCONN60_C21100002_SMLF-CONN,C2A
P1V05_PCH_STBY           L2M1             1        INDUCTOR_SMT-0.022UH,IND,72189A
P1V05_PCH_STBY           L7A4             2        INDUCTOR_SM-0.3UH,IND,D92183-0A
P1V05_PCH_STBY           R1L39            1        RES_0402-100.0,1%,1/16W,CHIP,GA
P1V05_PCH_STBY           R1L41            1        RES_0402-100.0,1%,1/16W,CHIP,GA
P1V05_PCH_STBY           R3N15            1        RES_0402-1.00K,1%,1/16W,CHIP,GA
P1V05_PCH_STBY           R3N16            1        RES_0402-1.00K,1%,1/16W,CHIP,GA
P1V05_PCH_STBY           R3P5             1        RES_0402-1.00K,1%,1/16W,CHIP,GA
P1V05_PCH_STBY           R3P6             1        RES_0402-1.00K,1%,1/16W,CHIP,GA
P1V05_PCH_STBY           R3P7             1        RES_0402-1.00K,1%,1/16W,CHIP,GA
P1V05_PCH_STBY           R3P8             1        RES_0402-1.00K,1%,1/16W,CHIP,GA
P1V05_PCH_STBY           R3P53            1        RES_0402-4.75K,1%,1/16W,CHIP,GA
P1V05_PCH_STBY           R7C21            1        RES_0402-10.0K,1%,1/16W,CHIP,GA
P1V05_PCH_STBY           R7D44            1        RES_0402-4.75K,1%,1/16W,CHIP,GA
P1V05_PCH_STBY           R8A13            1        RES_0402-150.0,1%,1/16W,CHIP,GA
P1V05_PCH_STBY           R8A14            1        RES_0402-150.0,1%,1/16W,CHIP,GA
P1V05_PCH_STBY           R8B14            2        RES_0402-0.0,5%,1/16W,CHIP,G21A
P1V05_PCH_STBY           R9A11            1        RES_0402-150.0,1%,1/16W,CHIP,GA
P1V05_PCH_STBY           R9A17            2        RES_0402-1.00K,1%,1/16W,CHIP,GA
P1V05_PCH_STBY           U7C1             AA24     LBG_CORE_QAT_EXT_D_BGA1-IC,H91A
P1V05_PCH_STBY           U7C1             AA45     LBG_CORE_QAT_EXT_D_BGA1-IC,H91A
P1V05_PCH_STBY           U7C1             AA46     LBG_CORE_QAT_EXT_D_BGA1-IC,H91A
P1V05_PCH_STBY           U7C1             AC26     LBG_CORE_QAT_EXT_D_BGA1-IC,H91A
P1V05_PCH_STBY           U7C1             AE27     LBG_CORE_QAT_EXT_D_BGA1-IC,H91A
P1V05_PCH_STBY           U7C1             AH50     LBG_CORE_QAT_EXT_D_BGA1-IC,H91A
P1V05_PCH_STBY           U7C1             AJ29     LBG_CORE_QAT_EXT_D_BGA1-IC,H91A
P1V05_PCH_STBY           U7C1             AJ43     LBG_CORE_QAT_EXT_D_BGA1-IC,H91A
P1V05_PCH_STBY           U7C1             AK27     LBG_CORE_QAT_EXT_D_BGA1-IC,H91A
P1V05_PCH_STBY           U7C1             AK43     LBG_CORE_QAT_EXT_D_BGA1-IC,H91A
P1V05_PCH_STBY           U7C1             AK45     LBG_CORE_QAT_EXT_D_BGA1-IC,H91A
P1V05_PCH_STBY           U7C1             AM27     LBG_CORE_QAT_EXT_D_BGA1-IC,H91A
P1V05_PCH_STBY           U7C1             AM43     LBG_CORE_QAT_EXT_D_BGA1-IC,H91A
P1V05_PCH_STBY           U7C1             AM45     LBG_CORE_QAT_EXT_D_BGA1-IC,H91A
P1V05_PCH_STBY           U7C1             AM48     LBG_CORE_QAT_EXT_D_BGA1-IC,H91A
P1V05_PCH_STBY           U7C1             AP43     LBG_CORE_QAT_EXT_D_BGA1-IC,H91A
P1V05_PCH_STBY           U7C1             AP45     LBG_CORE_QAT_EXT_D_BGA1-IC,H91A
P1V05_PCH_STBY           U7C1             AT39     LBG_CORE_QAT_EXT_D_BGA1-IC,H91A
P1V05_PCH_STBY           U7C1             AT43     LBG_CORE_QAT_EXT_D_BGA1-IC,H91A
P1V05_PCH_STBY           U7C1             AT45     LBG_CORE_QAT_EXT_D_BGA1-IC,H91A
P1V05_PCH_STBY           U7C1             AT48     LBG_CORE_QAT_EXT_D_BGA1-IC,H91A
P1V05_PCH_STBY           U7C1             AU37     LBG_CORE_QAT_EXT_D_BGA1-IC,H91A
P1V05_PCH_STBY           U7C1             AU39     LBG_CORE_QAT_EXT_D_BGA1-IC,H91A
P1V05_PCH_STBY           U7C1             AU43     LBG_CORE_QAT_EXT_D_BGA1-IC,H91A
P1V05_PCH_STBY           U7C1             AU45     LBG_CORE_QAT_EXT_D_BGA1-IC,H91A
P1V05_PCH_STBY           U7C1             AW43     LBG_CORE_QAT_EXT_D_BGA1-IC,H91A
P1V05_PCH_STBY           U7C1             AW45     LBG_CORE_QAT_EXT_D_BGA1-IC,H91A
P1V05_PCH_STBY           U7C1             BA30     LBG_CORE_QAT_EXT_D_BGA1-IC,H91A
P1V05_PCH_STBY           U7C1             BA32     LBG_CORE_QAT_EXT_D_BGA1-IC,H91A
P1V05_PCH_STBY           U7C1             BA34     LBG_CORE_QAT_EXT_D_BGA1-IC,H91A
P1V05_PCH_STBY           U7C1             BA36     LBG_CORE_QAT_EXT_D_BGA1-IC,H91A
P1V05_PCH_STBY           U7C1             BA37     LBG_CORE_QAT_EXT_D_BGA1-IC,H91A
P1V05_PCH_STBY           U7C1             BB33     LBG_CORE_QAT_EXT_D_BGA1-IC,H91A
P1V05_PCH_STBY           U7C1             BB37     LBG_CORE_QAT_EXT_D_BGA1-IC,H91A
P1V05_PCH_STBY           U7C1             BE48     LBG_CORE_QAT_EXT_D_BGA1-IC,H91A
P1V05_PCH_STBY           U7C1             BF46     LBG_CORE_QAT_EXT_D_BGA1-IC,H91A
P1V05_PCH_STBY           U7C1             R42      LBG_CORE_QAT_EXT_D_BGA1-IC,H91A
P1V05_PCH_STBY           U7C1             R46      LBG_CORE_QAT_EXT_D_BGA1-IC,H91A
P1V05_PCH_STBY           U7C1             T44      LBG_CORE_QAT_EXT_D_BGA1-IC,H91A
P1V05_PCH_STBY           U7C1             U46      LBG_CORE_QAT_EXT_D_BGA1-IC,H91A
P1V05_PCH_STBY           U7C1             U50      LBG_CORE_QAT_EXT_D_BGA1-IC,H91A
P1V05_PCH_STBY           U7C1             V44      LBG_CORE_QAT_EXT_D_BGA1-IC,H91A
P1V05_PCH_STBY           U7C1             Y26      LBG_CORE_QAT_EXT_D_BGA1-IC,H91A
P1V05_PCH_STBY           U7C1             Y45      LBG_CORE_QAT_EXT_D_BGA1-IC,H91A
P1V05_PCH_STBY           U7C1             Y46      LBG_CORE_QAT_EXT_D_BGA1-IC,H91A
P1V05_PCH_STBY_ISCLK_PLL C3M24            1        CAP_0603LF-10UF,4V,20%,X6S,E15A
P1V05_PCH_STBY_ISCLK_PLL C3M29            1        CAP_A_0402V-1.0UF,6.3V,10%,X6SA
P1V05_PCH_STBY_ISCLK_PLL FB3M4            2        FERRITE_SM-120,FB,693286-027
P1V05_PCH_STBY_ISCLK_PLL U7C1             AE46     LBG_CORE_QAT_EXT_D_BGA1-IC,H91A
P1V05_PCH_STBY_ISCLK_PLL U7C1             AG45     LBG_CORE_QAT_EXT_D_BGA1-IC,H91A
P1V05_PCH_STBY_ISCLK_PLL U7C1             AJ46     LBG_CORE_QAT_EXT_D_BGA1-IC,H91A
P1V05_PCH_STBY_ISCLK_PLL U7C1             AJ48     LBG_CORE_QAT_EXT_D_BGA1-IC,H91A
P1V05_PCH_STBY_ISCLK_PLL U7C1             W50      LBG_CORE_QAT_EXT_D_BGA1-IC,H91A
P1V05_PCH_STBY_KR_PLL    C2N5             1        CAP_A_0402V-1.0UF,6.3V,10%,X6SA
P1V05_PCH_STBY_KR_PLL    C2N6             1        CAP_0603LF-10UF,4V,20%,X6S,E15A
P1V05_PCH_STBY_KR_PLL    L2M1             2        INDUCTOR_SMT-0.022UH,IND,72189A
P1V05_PCH_STBY_KR_PLL    R2M6             2        RES_0402-1.0K,0.1%,1/16W,CHIP,A
P1V05_PCH_STBY_KR_PLL    R2N4             1        RES_0402-1.0K,0.1%,1/16W,CHIP,A
P1V05_PCH_STBY_KR_PLL    U7C1             BA39     LBG_CORE_QAT_EXT_D_BGA1-IC,H91A
P1V05_PCH_STBY_KR_PLL    U7C1             BA41     LBG_CORE_QAT_EXT_D_BGA1-IC,H91A
P1V05_PCH_STBY_KR_PLL    U7C1             BB40     LBG_CORE_QAT_EXT_D_BGA1-IC,H91A
P1V05_PCH_STBY_KR_PLL    U7C1             BD38     LBG_CORE_QAT_EXT_D_BGA1-IC,H91A
P1V05_PCH_STBY_VCCA_PLL0 C3M18            1        CAP_0603LF-10UF,4V,20%,X6S,E15A
P1V05_PCH_STBY_VCCA_PLL0 C3M20            1        CAP_A_0402V-1.0UF,6.3V,10%,X6SA
P1V05_PCH_STBY_VCCA_PLL0 FB3M2            2        FERRITE_SM-120,FB,693286-027
P1V05_PCH_STBY_VCCA_PLL0 U7C1             AG48     LBG_CORE_QAT_EXT_D_BGA1-IC,H91A
P1V05_PCH_STBY_VCCA_PLL1 C3M17            1        CAP_0603LF-10UF,4V,20%,X6S,E15A
P1V05_PCH_STBY_VCCA_PLL1 C3M19            1        CAP_A_0402V-1.0UF,6.3V,10%,X6SA
P1V05_PCH_STBY_VCCA_PLL1 FB3M1            2        FERRITE_SM-120,FB,693286-027
P1V05_PCH_STBY_VCCA_PLL1 U7C1             AE45     LBG_CORE_QAT_EXT_D_BGA1-IC,H91A
P1V05_PCH_STBY_VCCA_XTAL C3M23            1        CAP_0603LF-10UF,4V,20%,X6S,E15A
P1V05_PCH_STBY_VCCA_XTAL C3M27            1        CAP_A_0402V-1.0UF,6.3V,10%,X6SA
P1V05_PCH_STBY_VCCA_XTAL FB3M3            2        FERRITE_SM-120,FB,693286-027
P1V05_PCH_STBY_VCCA_XTAL U7C1             AD50     LBG_CORE_QAT_EXT_D_BGA1-IC,H91A
P1V05_PCH_STBY_WM20_PLL  C2M5             1        CAP_0603LF-10UF,4V,20%,X6S,E15A
P1V05_PCH_STBY_WM20_PLL  C2M7             1        CAP_A_0402V-1.0UF,6.3V,10%,X6SA
P1V05_PCH_STBY_WM20_PLL  FB2M1            2        FERRITE_SM-120,FB,693286-027
P1V05_PCH_STBY_WM20_PLL  U7C1             AK50     LBG_CORE_QAT_EXT_D_BGA1-IC,H91A
P1V05_PCH_STBY_WM20_PLL  U7C1             AN50     LBG_CORE_QAT_EXT_D_BGA1-IC,H91A
P1V05_PCH_STBY_WM26_PLL  C2M9             1        CAP_A_0402V-1.0UF,6.3V,10%,X6SA
P1V05_PCH_STBY_WM26_PLL  C2M10            1        CAP_0603LF-10UF,4V,20%,X6S,E15A
P1V05_PCH_STBY_WM26_PLL  FB2M2            2        FERRITE_SM-120,FB,693286-027
P1V05_PCH_STBY_WM26_PLL  U7C1             AP48     LBG_CORE_QAT_EXT_D_BGA1-IC,H91A
P1V05_PCH_STBY_WM26_PLL  U7C1             AU48     LBG_CORE_QAT_EXT_D_BGA1-IC,H91A
P1V05_PCH_STBY_WM26_PLL  U7C1             AW48     LBG_CORE_QAT_EXT_D_BGA1-IC,H91A
P1V26_BMC_STBY           C1T24            1        CAP_A_0402V-0.01UF,25V,10%,X7RA
P1V26_BMC_STBY           C1T27            1        CAP_A_0402V-0.01UF,25V,10%,X7RA
P1V26_BMC_STBY           C1T28            1        CAP_A_0402V-1.0UF,6.3V,10%,X6SA
P1V26_BMC_STBY           C1T34            1        CAP_A_0402V-0.01UF,25V,10%,X7RA
P1V26_BMC_STBY           C1T36            1        CAP_A_0402V-0.01UF,25V,10%,X7RA
P1V26_BMC_STBY           C1T42            1        CAP_0603-0.47UF,16V,10%,X7R,20A
P1V26_BMC_STBY           C1U1             1        CAP_0805-10UF,16V,10%,X6S,C953A
P1V26_BMC_STBY           C1U6             1        CAP_A_0402V-1.0UF,6.3V,10%,X6SA
P1V26_BMC_STBY           C1U7             1        CAP_A_0402V-1.0UF,6.3V,10%,X6SA
P1V26_BMC_STBY           C9E10            1        CAP_0603-10UF,6.3V,20%,X6S,E15A
P1V26_BMC_STBY           C9F4             1        CAP_0805LF-22UF,4V,20%,X6S,C95A
P1V26_BMC_STBY           EU9F1            1        RT9059_DFN-IC,H65765-001
P1V26_BMC_STBY           EU9F1            2        RT9059_DFN-IC,H65765-001
P1V26_BMC_STBY           EU9F1            3        RT9059_DFN-IC,H65765-001
P1V26_BMC_STBY           FB9F1            1        FERRITE_SMLF-300,FB,693286-046
P1V26_BMC_STBY           R9F6             1        RES_0402-5.76K,1%,1/16W,CHIP,GA
P1V26_BMC_STBY           U9F4             F14      AST1250_BGA-IC,G85138-002
P1V26_BMC_STBY           U9F4             F15      AST1250_BGA-IC,G85138-002
P1V26_BMC_STBY           U9F4             K6       AST1250_BGA-IC,G85138-002
P1V26_BMC_STBY           U9F4             K17      AST1250_BGA-IC,G85138-002
P1V26_BMC_STBY           U9F4             L6       AST1250_BGA-IC,G85138-002
P1V26_BMC_STBY           U9F4             L17      AST1250_BGA-IC,G85138-002
P1V26_BMC_STBY           U9F4             P6       AST1250_BGA-IC,G85138-002
P1V26_BMC_STBY           U9F4             P17      AST1250_BGA-IC,G85138-002
P1V26_BMC_STBY           U9F4             R6       AST1250_BGA-IC,G85138-002
P1V26_BMC_STBY           U9F4             R17      AST1250_BGA-IC,G85138-002
P1V26_BMC_STBY           U9F4             U12      AST1250_BGA-IC,G85138-002
P1V26_BMC_STBY           U9F4             U13      AST1250_BGA-IC,G85138-002
P1V26_BMC_STBY           U9F4             Y18      AST1250_BGA-IC,G85138-002
P1V26_BMC_STBY_V1PLLAV12 C9F12            1        CAP_A_0402V-1.0UF,6.3V,10%,X6SA
P1V26_BMC_STBY_V1PLLAV12 C9F14            1        CAP_A_0402V-0.1UF,16V,10%,X7R,A
P1V26_BMC_STBY_V1PLLAV12 C9F18            1        CAP_0402LF-100.0PF,50V,5%,COG,A
P1V26_BMC_STBY_V1PLLAV12 FB9F1            2        FERRITE_SMLF-300,FB,693286-046
P1V26_BMC_STBY_V1PLLAV12 U9F4             W19      AST1250_BGA-IC,G85138-002
P1V26_BMC_STBY_V1PLLAV12 U9F4             Y20      AST1250_BGA-IC,G85138-002
P1V538_BMC_STBY          C1T15            1        CAP_0603-10UF,6.3V,20%,X6S,E15A
P1V538_BMC_STBY          C1T31            1        CAP_A_0402V-1.0UF,6.3V,10%,X6SA
P1V538_BMC_STBY          C1T32            1        CAP_A_0402V-1.0UF,6.3V,10%,X6SA
P1V538_BMC_STBY          C1T33            1        CAP_A_0402V-0.1UF,16V,10%,X7R,A
P1V538_BMC_STBY          C1T35            1        CAP_A_0402V-1.0UF,6.3V,10%,X6SA
P1V538_BMC_STBY          C1T39            1        CAP_A_0402V-0.01UF,25V,10%,X7RA
P1V538_BMC_STBY          C1T40            1        CAP_A_0402V-0.1UF,16V,10%,X7R,A
P1V538_BMC_STBY          C1T46            1        CAP_A_0402V-1.0UF,6.3V,10%,X6SA
P1V538_BMC_STBY          C1T49            1        CAP_A_0402V-1.0UF,6.3V,10%,X6SA
P1V538_BMC_STBY          C1T53            1        CAP_A_0402V-0.1UF,16V,10%,X7R,A
P1V538_BMC_STBY          C1T54            1        CAP_A_0402V-0.1UF,16V,10%,X7R,A
P1V538_BMC_STBY          C1T55            1        CAP_A_0402V-1.0UF,6.3V,10%,X6SA
P1V538_BMC_STBY          C1U10            1        CAP_A_0402V-0.1UF,16V,10%,X7R,A
P1V538_BMC_STBY          C1U12            1        CAP_0805-10UF,16V,10%,X6S,C953A
P1V538_BMC_STBY          C1U13            1        CAP_A_0402V-0.1UF,16V,10%,X7R,A
P1V538_BMC_STBY          C1U14            1        CAP_A_0402V-0.1UF,16V,10%,X7R,A
P1V538_BMC_STBY          C1U15            1        CAP_A_0402V-0.1UF,16V,10%,X7R,A
P1V538_BMC_STBY          C1U16            1        CAP_A_0402V-0.1UF,16V,10%,X7R,A
P1V538_BMC_STBY          C9F3             1        CAP_0603-10UF,6.3V,20%,X6S,E15A
P1V538_BMC_STBY          C9F13            1        CAP_0805LF-22UF,4V,20%,X6S,C95A
P1V538_BMC_STBY          EU9F1            7        RT9059_DFN-IC,H65765-001
P1V538_BMC_STBY          EU9F1            8        RT9059_DFN-IC,H65765-001
P1V538_BMC_STBY          EU9F1            9        RT9059_DFN-IC,H65765-001
P1V538_BMC_STBY          EU9F2            1        RT9059_DFN-IC,H65765-001
P1V538_BMC_STBY          EU9F2            2        RT9059_DFN-IC,H65765-001
P1V538_BMC_STBY          EU9F2            3        RT9059_DFN-IC,H65765-001
P1V538_BMC_STBY          R1T30            1        RES_0402-1.00K,1%,1/16W,CHIP,GA
P1V538_BMC_STBY          R9F29            1        RES_0402-4.75K,1%,1/16W,CHIP,GA
P1V538_BMC_STBY          R9F31            1        RES_0402-12K,1%,1/16W,CHIP,G21A
P1V538_BMC_STBY          U9F4             U10      AST1250_BGA-IC,G85138-002
P1V538_BMC_STBY          U9F4             U11      AST1250_BGA-IC,G85138-002
P1V538_BMC_STBY          U9F4             U14      AST1250_BGA-IC,G85138-002
P1V538_BMC_STBY          U9F4             U15      AST1250_BGA-IC,G85138-002
P1V538_BMC_STBY          U9F5             A1       K4B1G16_BGA1-IC,G38649-001
P1V538_BMC_STBY          U9F5             A8       K4B1G16_BGA1-IC,G38649-001
P1V538_BMC_STBY          U9F5             B2       K4B1G16_BGA1-IC,G38649-001
P1V538_BMC_STBY          U9F5             C1       K4B1G16_BGA1-IC,G38649-001
P1V538_BMC_STBY          U9F5             C9       K4B1G16_BGA1-IC,G38649-001
P1V538_BMC_STBY          U9F5             D2       K4B1G16_BGA1-IC,G38649-001
P1V538_BMC_STBY          U9F5             D9       K4B1G16_BGA1-IC,G38649-001
P1V538_BMC_STBY          U9F5             E9       K4B1G16_BGA1-IC,G38649-001
P1V538_BMC_STBY          U9F5             F1       K4B1G16_BGA1-IC,G38649-001
P1V538_BMC_STBY          U9F5             G7       K4B1G16_BGA1-IC,G38649-001
P1V538_BMC_STBY          U9F5             H2       K4B1G16_BGA1-IC,G38649-001
P1V538_BMC_STBY          U9F5             H9       K4B1G16_BGA1-IC,G38649-001
P1V538_BMC_STBY          U9F5             K2       K4B1G16_BGA1-IC,G38649-001
P1V538_BMC_STBY          U9F5             K8       K4B1G16_BGA1-IC,G38649-001
P1V538_BMC_STBY          U9F5             N1       K4B1G16_BGA1-IC,G38649-001
P1V538_BMC_STBY          U9F5             N9       K4B1G16_BGA1-IC,G38649-001
P1V538_BMC_STBY          U9F5             R1       K4B1G16_BGA1-IC,G38649-001
P1V538_BMC_STBY          U9F5             R9       K4B1G16_BGA1-IC,G38649-001
P1V5_LAN                 C1R17            1        CAP_0603-10UF,6.3V,20%,X6S,E15A
P1V5_LAN                 C1R19            1        CAP_A_0402V-0.1UF,16V,10%,X7R,A
P1V5_LAN                 C1R26            1        CAP_A_0402V-0.1UF,16V,10%,X7R,A
P1V5_LAN                 C1R29            1        CAP_A_0402V-0.1UF,16V,10%,X7R,A
P1V5_LAN                 C1R30            1        CAP_0603-10UF,6.3V,20%,X6S,E15A
P1V5_LAN                 C1R31            1        CAP_A_0402V-0.1UF,16V,10%,X7R,A
P1V5_LAN                 C9E6             1        CAP_1210-47UF,16V,20%,EMPTY,D3A
P1V5_LAN                 EU9E1            39       SPRINGVILLE_SM1-IC,G47144-004
P1V5_LAN                 EU9E1            47       SPRINGVILLE_SM1-IC,G47144-004
P1V5_LAN                 R1T32            1        RES_0603-0,5.0%,1/10W,CHIP,G22A
P1V5_LAN                 R1T33            1        RES_0603-0,5.0%,1/10W,EMPTY,G2A
P1V5_LAN_I210            EU9E1            56       SPRINGVILLE_SM1-IC,G47144-004
P1V5_LAN_I210            R1T32            2        RES_0603-0,5.0%,1/10W,CHIP,G22A
P1V8_BMC_STBY_PCIE       C1T16            1        CAP_0603-10UF,6.3V,20%,EMPTY,EA
P1V8_BMC_STBY_PCIE       C1T17            1        CAP_A_0402V-0.1UF,16V,10%,EMPTA
P1V8_BMC_STBY_PCIE       C1T18            1        CAP_A_0402V-1.0UF,6.3V,10%,EMPA
P1V8_BMC_STBY_PCIE       FB1T1            2        FERRITE_SMLF-300,EMPTY,693286-A
P1V8_BMC_STBY_PCIE       U9F4             G20      AST1250_BGA-IC,G85138-002
P1V8_BMC_STBY_PCIEA      C8F9             1        CAP_A_0402V-1.0UF,6.3V,10%,EMPA
P1V8_BMC_STBY_PCIEA      C8F10            1        CAP_0603-10UF,6.3V,20%,EMPTY,EA
P1V8_BMC_STBY_PCIEA      C9F15            1        CAP_A_0402V-0.1UF,16V,10%,EMPTA
P1V8_BMC_STBY_PCIEA      FB2T1            2        FERRITE_SMLF-300,EMPTY,693286-A
P1V8_BMC_STBY_PCIEA      U9F4             C21      AST1250_BGA-IC,G85138-002
P1V8_BMC_STBY_PCIEA      U9F4             F20      AST1250_BGA-IC,G85138-002
P1V8_MCP_CPU0            C1M29            1        CAP_A_0402V-0.1UF,16V,10%,X7R,A
P1V8_MCP_CPU0            C3T1             1        CAP_A_0603V-47UF,4V,20%,X5R,60A
P1V8_MCP_CPU0            C3T2             1        CAP_A_0603V-47UF,4V,20%,X5R,60A
P1V8_MCP_CPU0            C4T1             1        CAP_A_0402V-1.0UF,6.3V,10%,X6SA
P1V8_MCP_CPU0            C4T2             1        CAP_A_0402V-1.0UF,6.3V,10%,X6SA
P1V8_MCP_CPU0            C6D1             1        CAP_0603LF-10UF,4V,20%,X6S,E15A
P1V8_MCP_CPU0            J6E1             E1       SCONN120_H61426002_SM-CONN,H61A
P1V8_MCP_CPU0            J6E1             E2       SCONN120_H61426002_SM-CONN,H61A
P1V8_MCP_CPU0            J6E1             F1       SCONN120_H61426002_SM-CONN,H61A
P1V8_MCP_CPU0            J6E1             F2       SCONN120_H61426002_SM-CONN,H61A
P1V8_MCP_CPU0            J9B4             4        SCONN10_C12536004_SMLF-CONN,C1A
P1V8_MCP_CPU0            R1M19            1        RES_0402-1.00K,1%,1/16W,CHIP,GA
P1V8_MCP_CPU0            R1M20            1        RES_0402-1.00K,1%,1/16W,CHIP,GA
P1V8_MCP_CPU0            R1M21            1        RES_0402-1.00K,1%,1/16W,CHIP,GA
P1V8_MCP_CPU0            R9B12            1        RES_0402-1.00K,1%,1/16W,CHIP,GA
P1V8_MCP_CPU0            U1M5             2        74CBTLV1G125_SMLF-IC,C88177-00A
P1V8_MCP_CPU0            U4R1             2        74CBTLV1G125_SMLF-IC,C88177-00A
P1V8_MCP_CPU0            U5D1             A14      SKX_EXT_B_BGA1-IC,TBD
P1V8_MCP_CPU0            U5D1             A16      SKX_EXT_B_BGA1-IC,TBD
P1V8_MCP_CPU0            U5D1             B13      SKX_EXT_B_BGA1-IC,TBD
P1V8_MCP_CPU0            U5D1             B15      SKX_EXT_B_BGA1-IC,TBD
P1V8_MCP_CPU0            U5D1             B17      SKX_EXT_B_BGA1-IC,TBD
P1V8_MCP_CPU0            U5D1             BT27     SKX_EXT_B_BGA1-IC,TBD
P1V8_MCP_CPU0            U5D1             BU26     SKX_EXT_B_BGA1-IC,TBD
P1V8_MCP_CPU0            U5D1             BV27     SKX_EXT_B_BGA1-IC,TBD
P1V8_MCP_CPU0            U5D1             BY27     SKX_EXT_B_BGA1-IC,TBD
P1V8_MCP_CPU1            C3D3             1        CAP_0603LF-10UF,4V,20%,X6S,E15A
P1V8_MCP_CPU1            C3F1             1        CAP_A_0603V-47UF,4V,20%,X5R,60A
P1V8_MCP_CPU1            C4F1             1        CAP_A_0402V-1.0UF,6.3V,10%,X6SA
P1V8_MCP_CPU1            C4F2             1        CAP_A_0603V-47UF,4V,20%,X5R,60A
P1V8_MCP_CPU1            C4F3             1        CAP_A_0402V-1.0UF,6.3V,10%,X6SA
P1V8_MCP_CPU1            J4E1             E1       SCONN120_H61426002_SM-CONN,H61A
P1V8_MCP_CPU1            J4E1             E2       SCONN120_H61426002_SM-CONN,H61A
P1V8_MCP_CPU1            J4E1             F1       SCONN120_H61426002_SM-CONN,H61A
P1V8_MCP_CPU1            J4E1             F2       SCONN120_H61426002_SM-CONN,H61A
P1V8_MCP_CPU1            U2D1             A14      SKX_EXT_B_BGA1-IC,TBD
P1V8_MCP_CPU1            U2D1             A16      SKX_EXT_B_BGA1-IC,TBD
P1V8_MCP_CPU1            U2D1             B13      SKX_EXT_B_BGA1-IC,TBD
P1V8_MCP_CPU1            U2D1             B15      SKX_EXT_B_BGA1-IC,TBD
P1V8_MCP_CPU1            U2D1             B17      SKX_EXT_B_BGA1-IC,TBD
P1V8_MCP_CPU1            U2D1             BT27     SKX_EXT_B_BGA1-IC,TBD
P1V8_MCP_CPU1            U2D1             BU26     SKX_EXT_B_BGA1-IC,TBD
P1V8_MCP_CPU1            U2D1             BV27     SKX_EXT_B_BGA1-IC,TBD
P1V8_MCP_CPU1            U2D1             BY27     SKX_EXT_B_BGA1-IC,TBD
P1V8_MCP_CPU1            U6M1             2        74CBTLV1G125_SMLF-IC,C88177-00A
P1V8_PCH_STBY            C2L32            1        CAP_0805-47UF,4V,20%,X6S,C9533A
P1V8_PCH_STBY            C2L45            1        CAP_0805-22UF,6.3V,20%,X6S,C95A
P1V8_PCH_STBY            C2M1             1        CAP_A_0603V-22.0UF,4V,20%,X6S,A
P1V8_PCH_STBY            C2M2             1        CAP_A_0603V-22.0UF,4V,20%,X6S,A
P1V8_PCH_STBY            C2N15            1        CAP_A_0402V-1.0UF,6.3V,10%,X6SA
P1V8_PCH_STBY            C2N16            1        CAP_A_0402V-1.0UF,6.3V,10%,X6SA
P1V8_PCH_STBY            C3N21            1        CAP_A_0402V-1.0UF,6.3V,10%,X6SA
P1V8_PCH_STBY            C3N22            1        CAP_A_0402V-1.0UF,6.3V,10%,X6SA
P1V8_PCH_STBY            C3N25            1        CAP_A_0402V-1.0UF,6.3V,10%,X6SA
P1V8_PCH_STBY            C7D3             1        CAP_A_0603V-22.0UF,4V,20%,X6S,A
P1V8_PCH_STBY            C8A12            1        CAP_0805-47UF,4V,20%,X6S,C9533A
P1V8_PCH_STBY            C8A14            1        CAP_0805-22UF,6.3V,20%,X6S,C95A
P1V8_PCH_STBY            C8B1             1        CAP_A_0603V-22.0UF,4V,20%,X6S,A
P1V8_PCH_STBY            C8B2             1        CAP_A_0603V-22.0UF,4V,20%,X6S,A
P1V8_PCH_STBY            C8B3             1        CAP_A_0603V-22.0UF,4V,20%,X6S,A
P1V8_PCH_STBY            C8B4             1        CAP_A_0603V-22.0UF,4V,20%,X6S,A
P1V8_PCH_STBY            EU8A2            1        RT9059_DFN-IC,H65765-001
P1V8_PCH_STBY            EU8A2            2        RT9059_DFN-IC,H65765-001
P1V8_PCH_STBY            EU8A2            3        RT9059_DFN-IC,H65765-001
P1V8_PCH_STBY            FB1T1            1        FERRITE_SMLF-300,EMPTY,693286-A
P1V8_PCH_STBY            FB2T1            1        FERRITE_SMLF-300,EMPTY,693286-A
P1V8_PCH_STBY            R2L20            1        RES_0402-63.4K,1.0%,1/16W,CHIPA
P1V8_PCH_STBY            R8A12            1        RES_0603-475.0,1%,1/10W,CHIP,GA
P1V8_PCH_STBY            U7C1             AE26     LBG_CORE_QAT_EXT_D_BGA1-IC,H91A
P1V8_PCH_STBY            U7C1             AG27     LBG_CORE_QAT_EXT_D_BGA1-IC,H91A
P1V8_PCH_STBY            U7C1             AK24     LBG_CORE_QAT_EXT_D_BGA1-IC,H91A
P1V8_PCH_STBY            U7C1             AK29     LBG_CORE_QAT_EXT_D_BGA1-IC,H91A
P1V8_PCH_STBY            U7C1             AM29     LBG_CORE_QAT_EXT_D_BGA1-IC,H91A
P1V8_PCH_STBY            U7C1             AP29     LBG_CORE_QAT_EXT_D_BGA1-IC,H91A
P1V8_PCH_STBY            U7C1             AT29     LBG_CORE_QAT_EXT_D_BGA1-IC,H91A
P1V8_PCH_STBY            U7C1             AU29     LBG_CORE_QAT_EXT_D_BGA1-IC,H91A
P1V8_PCH_STBY            U7C1             AW27     LBG_CORE_QAT_EXT_D_BGA1-IC,H91A
P1V8_PCH_STBY            U7C1             AW29     LBG_CORE_QAT_EXT_D_BGA1-IC,H91A
P1V8_PCH_STBY            U7C1             BA27     LBG_CORE_QAT_EXT_D_BGA1-IC,H91A
P1V8_PCH_STBY            U7C1             BA29     LBG_CORE_QAT_EXT_D_BGA1-IC,H91A
P1V8_PCH_STBY            U7C1             BD46     LBG_CORE_QAT_EXT_D_BGA1-IC,H91A
P2E_SSB_BMC_RX_C_DN      C9F16            2        CAP_A_0402V-0.1UF,16V,10%,EMPTA
P2E_SSB_BMC_RX_C_DN      R3M9             1        RES_0402-100.0K,1%,1/16W,CHIP,A
P2E_SSB_BMC_RX_C_DN      U7C1             AN70     LBG_CORE_QAT_EXT_D_BGA1-IC,H91A
P2E_SSB_BMC_RX_C_DP      C9F17            2        CAP_A_0402V-0.1UF,16V,10%,EMPTA
P2E_SSB_BMC_RX_C_DP      R3M8             1        RES_0402-100.0K,1%,1/16W,CHIP,A
P2E_SSB_BMC_RX_C_DP      U7C1             AN72     LBG_CORE_QAT_EXT_D_BGA1-IC,H91A
P2E_SSB_BMC_RX_DN        C9F16            1        CAP_A_0402V-0.1UF,16V,10%,EMPTA
P2E_SSB_BMC_RX_DN        U9F4             E21      AST1250_BGA-IC,G85138-002
P2E_SSB_BMC_RX_DP        C9F17            1        CAP_A_0402V-0.1UF,16V,10%,EMPTA
P2E_SSB_BMC_RX_DP        U9F4             E22      AST1250_BGA-IC,G85138-002
P2E_SSB_BMC_TX_C_DN      C2M3             2        CAP_A_0402V-0.1UF,16V,10%,EMPTA
P2E_SSB_BMC_TX_C_DN      R9F43            1        RES_0402-100.0K,1%,1/16W,CHIP,A
P2E_SSB_BMC_TX_C_DN      U9F4             F22      AST1250_BGA-IC,G85138-002
P2E_SSB_BMC_TX_C_DP      C2M4             2        CAP_A_0402V-0.1UF,16V,10%,EMPTA
P2E_SSB_BMC_TX_C_DP      R9F42            1        RES_0402-100.0K,1%,1/16W,CHIP,A
P2E_SSB_BMC_TX_C_DP      U9F4             F21      AST1250_BGA-IC,G85138-002
P2E_SSB_BMC_TX_DN        C2M3             1        CAP_A_0402V-0.1UF,16V,10%,EMPTA
P2E_SSB_BMC_TX_DN        U7C1             BG66     LBG_CORE_QAT_EXT_D_BGA1-IC,H91A
P2E_SSB_BMC_TX_DP        C2M4             1        CAP_A_0402V-0.1UF,16V,10%,EMPTA
P2E_SSB_BMC_TX_DP        U7C1             BJ66     LBG_CORE_QAT_EXT_D_BGA1-IC,H91A
P3E_CPU0_PE1_PCH_C_TXN<8> C6B19            2        CAP_0402-0.22UF,16V,10%,X7R,A3A
P3E_CPU0_PE1_PCH_C_TXN<8> U7C1             A57      LBG_CORE_QAT_EXT_D_BGA1-IC,H91A
P3E_CPU0_PE1_PCH_C_TXN<9> C6B17            2        CAP_0402-0.22UF,16V,10%,X7R,A3A
P3E_CPU0_PE1_PCH_C_TXN<9> U7C1             B58      LBG_CORE_QAT_EXT_D_BGA1-IC,H91A
P3E_CPU0_PE1_PCH_C_TXN<10> C6B15            2        CAP_0402-0.22UF,16V,10%,X7R,A3A
P3E_CPU0_PE1_PCH_C_TXN<10> U7C1             A59      LBG_CORE_QAT_EXT_D_BGA1-IC,H91A
P3E_CPU0_PE1_PCH_C_TXN<11> C6B14            2        CAP_0402-0.22UF,16V,10%,X7R,A3A
P3E_CPU0_PE1_PCH_C_TXN<11> U7C1             D60      LBG_CORE_QAT_EXT_D_BGA1-IC,H91A
P3E_CPU0_PE1_PCH_C_TXN<12> C6B11            2        CAP_0402-0.22UF,16V,10%,X7R,A3A
P3E_CPU0_PE1_PCH_C_TXN<12> U7C1             A61      LBG_CORE_QAT_EXT_D_BGA1-IC,H91A
P3E_CPU0_PE1_PCH_C_TXN<13> C6B9             2        CAP_0402-0.22UF,16V,10%,X7R,A3A
P3E_CPU0_PE1_PCH_C_TXN<13> U7C1             B62      LBG_CORE_QAT_EXT_D_BGA1-IC,H91A
P3E_CPU0_PE1_PCH_C_TXN<14> C6B6             2        CAP_0402-0.22UF,16V,10%,X7R,A3A
P3E_CPU0_PE1_PCH_C_TXN<14> U7C1             A63      LBG_CORE_QAT_EXT_D_BGA1-IC,H91A
P3E_CPU0_PE1_PCH_C_TXN<15> C6B4             2        CAP_0402-0.22UF,16V,10%,X7R,A3A
P3E_CPU0_PE1_PCH_C_TXN<15> U7C1             B64      LBG_CORE_QAT_EXT_D_BGA1-IC,H91A
P3E_CPU0_PE1_PCH_C_TXP<8> C6B20            2        CAP_0402-0.22UF,16V,10%,X7R,A3A
P3E_CPU0_PE1_PCH_C_TXP<8> U7C1             C57      LBG_CORE_QAT_EXT_D_BGA1-IC,H91A
P3E_CPU0_PE1_PCH_C_TXP<9> C6B18            2        CAP_0402-0.22UF,16V,10%,X7R,A3A
P3E_CPU0_PE1_PCH_C_TXP<9> U7C1             D58      LBG_CORE_QAT_EXT_D_BGA1-IC,H91A
P3E_CPU0_PE1_PCH_C_TXP<10> C6B16            2        CAP_0402-0.22UF,16V,10%,X7R,A3A
P3E_CPU0_PE1_PCH_C_TXP<10> U7C1             C59      LBG_CORE_QAT_EXT_D_BGA1-IC,H91A
P3E_CPU0_PE1_PCH_C_TXP<11> C6B13            2        CAP_0402-0.22UF,16V,10%,X7R,A3A
P3E_CPU0_PE1_PCH_C_TXP<11> U7C1             B60      LBG_CORE_QAT_EXT_D_BGA1-IC,H91A
P3E_CPU0_PE1_PCH_C_TXP<12> C6B12            2        CAP_0402-0.22UF,16V,10%,X7R,A3A
P3E_CPU0_PE1_PCH_C_TXP<12> U7C1             C61      LBG_CORE_QAT_EXT_D_BGA1-IC,H91A
P3E_CPU0_PE1_PCH_C_TXP<13> C6B10            2        CAP_0402-0.22UF,16V,10%,X7R,A3A
P3E_CPU0_PE1_PCH_C_TXP<13> U7C1             D62      LBG_CORE_QAT_EXT_D_BGA1-IC,H91A
P3E_CPU0_PE1_PCH_C_TXP<14> C6B8             2        CAP_0402-0.22UF,16V,10%,X7R,A3A
P3E_CPU0_PE1_PCH_C_TXP<14> U7C1             C63      LBG_CORE_QAT_EXT_D_BGA1-IC,H91A
P3E_CPU0_PE1_PCH_C_TXP<15> C6B5             2        CAP_0402-0.22UF,16V,10%,X7R,A3A
P3E_CPU0_PE1_PCH_C_TXP<15> U7C1             D64      LBG_CORE_QAT_EXT_D_BGA1-IC,H91A
P3E_CPU0_PE1_PCH_RXN<0>  C2U4             1        CAP_0402-0.22UF,16V,10%,X7R,A3A
P3E_CPU0_PE1_PCH_RXN<0>  U7C1             J52      LBG_CORE_QAT_EXT_D_BGA1-IC,H91A
P3E_CPU0_PE1_PCH_RXN<1>  C2U6             1        CAP_0402-0.22UF,16V,10%,X7R,A3A
P3E_CPU0_PE1_PCH_RXN<1>  U7C1             P56      LBG_CORE_QAT_EXT_D_BGA1-IC,H91A
P3E_CPU0_PE1_PCH_RXN<2>  C2U8             1        CAP_0402-0.22UF,16V,10%,X7R,A3A
P3E_CPU0_PE1_PCH_RXN<2>  U7C1             H54      LBG_CORE_QAT_EXT_D_BGA1-IC,H91A
P3E_CPU0_PE1_PCH_RXN<3>  C2U10            1        CAP_0402-0.22UF,16V,10%,X7R,A3A
P3E_CPU0_PE1_PCH_RXN<3>  U7C1             J56      LBG_CORE_QAT_EXT_D_BGA1-IC,H91A
P3E_CPU0_PE1_PCH_RXN<4>  C2U12            1        CAP_0402-0.22UF,16V,10%,X7R,A3A
P3E_CPU0_PE1_PCH_RXN<4>  U7C1             N58      LBG_CORE_QAT_EXT_D_BGA1-IC,H91A
P3E_CPU0_PE1_PCH_RXN<5>  C2U14            1        CAP_0402-0.22UF,16V,10%,X7R,A3A
P3E_CPU0_PE1_PCH_RXN<5>  U7C1             N61      LBG_CORE_QAT_EXT_D_BGA1-IC,H91A
P3E_CPU0_PE1_PCH_RXN<6>  C2U16            1        CAP_0402-0.22UF,16V,10%,X7R,A3A
P3E_CPU0_PE1_PCH_RXN<6>  U7C1             H61      LBG_CORE_QAT_EXT_D_BGA1-IC,H91A
P3E_CPU0_PE1_PCH_RXN<7>  C2U18            1        CAP_0402-0.22UF,16V,10%,X7R,A3A
P3E_CPU0_PE1_PCH_RXN<7>  U7C1             P59      LBG_CORE_QAT_EXT_D_BGA1-IC,H91A
P3E_CPU0_PE1_PCH_RXN<8>  C3M33            2        CAP_0402-0.22UF,16V,10%,X7R,A3A
P3E_CPU0_PE1_PCH_RXN<8>  U5D1             DM11     SKX_EXT_B_BGA1-IC,TBD
P3E_CPU0_PE1_PCH_RXN<9>  C3M35            2        CAP_0402-0.22UF,16V,10%,X7R,A3A
P3E_CPU0_PE1_PCH_RXN<9>  U5D1             DP11     SKX_EXT_B_BGA1-IC,TBD
P3E_CPU0_PE1_PCH_RXN<10> C3M32            2        CAP_0402-0.22UF,16V,10%,X7R,A3A
P3E_CPU0_PE1_PCH_RXN<10> U5D1             DT11     SKX_EXT_B_BGA1-IC,TBD
P3E_CPU0_PE1_PCH_RXN<11> C3M26            2        CAP_0402-0.22UF,16V,10%,X7R,A3A
P3E_CPU0_PE1_PCH_RXN<11> U5D1             DT13     SKX_EXT_B_BGA1-IC,TBD
P3E_CPU0_PE1_PCH_RXN<12> C3M4             2        CAP_0402-0.22UF,16V,10%,X7R,A3A
P3E_CPU0_PE1_PCH_RXN<12> U5D1             DV13     SKX_EXT_B_BGA1-IC,TBD
P3E_CPU0_PE1_PCH_RXN<13> C3M14            2        CAP_0402-0.22UF,16V,10%,X7R,A3A
P3E_CPU0_PE1_PCH_RXN<13> U5D1             DW14     SKX_EXT_B_BGA1-IC,TBD
P3E_CPU0_PE1_PCH_RXN<14> C3M12            2        CAP_0402-0.22UF,16V,10%,X7R,A3A
P3E_CPU0_PE1_PCH_RXN<14> U5D1             DY15     SKX_EXT_B_BGA1-IC,TBD
P3E_CPU0_PE1_PCH_RXN<15> C3M1             2        CAP_0402-0.22UF,16V,10%,X7R,A3A
P3E_CPU0_PE1_PCH_RXN<15> U5D1             DU16     SKX_EXT_B_BGA1-IC,TBD
P3E_CPU0_PE1_PCH_RXP<0>  C2U3             1        CAP_0402-0.22UF,16V,10%,X7R,A3A
P3E_CPU0_PE1_PCH_RXP<0>  U7C1             G52      LBG_CORE_QAT_EXT_D_BGA1-IC,H91A
P3E_CPU0_PE1_PCH_RXP<1>  C2U5             1        CAP_0402-0.22UF,16V,10%,X7R,A3A
P3E_CPU0_PE1_PCH_RXP<1>  U7C1             M56      LBG_CORE_QAT_EXT_D_BGA1-IC,H91A
P3E_CPU0_PE1_PCH_RXP<2>  C2U7             1        CAP_0402-0.22UF,16V,10%,X7R,A3A
P3E_CPU0_PE1_PCH_RXP<2>  U7C1             G56      LBG_CORE_QAT_EXT_D_BGA1-IC,H91A
P3E_CPU0_PE1_PCH_RXP<3>  C2U9             1        CAP_0402-0.22UF,16V,10%,X7R,A3A
P3E_CPU0_PE1_PCH_RXP<3>  U7C1             K58      LBG_CORE_QAT_EXT_D_BGA1-IC,H91A
P3E_CPU0_PE1_PCH_RXP<4>  C2U11            1        CAP_0402-0.22UF,16V,10%,X7R,A3A
P3E_CPU0_PE1_PCH_RXP<4>  U7C1             M59      LBG_CORE_QAT_EXT_D_BGA1-IC,H91A
P3E_CPU0_PE1_PCH_RXP<5>  C2U13            1        CAP_0402-0.22UF,16V,10%,X7R,A3A
P3E_CPU0_PE1_PCH_RXP<5>  U7C1             K61      LBG_CORE_QAT_EXT_D_BGA1-IC,H91A
P3E_CPU0_PE1_PCH_RXP<6>  C2U15            1        CAP_0402-0.22UF,16V,10%,X7R,A3A
P3E_CPU0_PE1_PCH_RXP<6>  U7C1             J63      LBG_CORE_QAT_EXT_D_BGA1-IC,H91A
P3E_CPU0_PE1_PCH_RXP<7>  C2U17            1        CAP_0402-0.22UF,16V,10%,X7R,A3A
P3E_CPU0_PE1_PCH_RXP<7>  U7C1             R61      LBG_CORE_QAT_EXT_D_BGA1-IC,H91A
P3E_CPU0_PE1_PCH_RXP<8>  C3M34            2        CAP_0402-0.22UF,16V,10%,X7R,A3A
P3E_CPU0_PE1_PCH_RXP<8>  U5D1             DK11     SKX_EXT_B_BGA1-IC,TBD
P3E_CPU0_PE1_PCH_RXP<9>  C3M36            2        CAP_0402-0.22UF,16V,10%,X7R,A3A
P3E_CPU0_PE1_PCH_RXP<9>  U5D1             DN10     SKX_EXT_B_BGA1-IC,TBD
P3E_CPU0_PE1_PCH_RXP<10> C3M28            2        CAP_0402-0.22UF,16V,10%,X7R,A3A
P3E_CPU0_PE1_PCH_RXP<10> U5D1             DR12     SKX_EXT_B_BGA1-IC,TBD
P3E_CPU0_PE1_PCH_RXP<11> C3M25            2        CAP_0402-0.22UF,16V,10%,X7R,A3A
P3E_CPU0_PE1_PCH_RXP<11> U5D1             DP13     SKX_EXT_B_BGA1-IC,TBD
P3E_CPU0_PE1_PCH_RXP<12> C3M3             2        CAP_0402-0.22UF,16V,10%,X7R,A3A
P3E_CPU0_PE1_PCH_RXP<12> U5D1             DU12     SKX_EXT_B_BGA1-IC,TBD
P3E_CPU0_PE1_PCH_RXP<13> C3M13            2        CAP_0402-0.22UF,16V,10%,X7R,A3A
P3E_CPU0_PE1_PCH_RXP<13> U5D1             DY13     SKX_EXT_B_BGA1-IC,TBD
P3E_CPU0_PE1_PCH_RXP<14> C3M11            2        CAP_0402-0.22UF,16V,10%,X7R,A3A
P3E_CPU0_PE1_PCH_RXP<14> U5D1             DV15     SKX_EXT_B_BGA1-IC,TBD
P3E_CPU0_PE1_PCH_RXP<15> C3M2             2        CAP_0402-0.22UF,16V,10%,X7R,A3A
P3E_CPU0_PE1_PCH_RXP<15> U5D1             DT15     SKX_EXT_B_BGA1-IC,TBD
P3E_CPU0_PE1_PCH_R_RXN<8> C3M33            1        CAP_0402-0.22UF,16V,10%,X7R,A3A
P3E_CPU0_PE1_PCH_R_RXN<8> U7C1             K65      LBG_CORE_QAT_EXT_D_BGA1-IC,H91A
P3E_CPU0_PE1_PCH_R_RXN<9> C3M35            1        CAP_0402-0.22UF,16V,10%,X7R,A3A
P3E_CPU0_PE1_PCH_R_RXN<9> U7C1             J66      LBG_CORE_QAT_EXT_D_BGA1-IC,H91A
P3E_CPU0_PE1_PCH_R_RXN<10> C3M32            1        CAP_0402-0.22UF,16V,10%,X7R,A3A
P3E_CPU0_PE1_PCH_R_RXN<10> U7C1             N65      LBG_CORE_QAT_EXT_D_BGA1-IC,H91A
P3E_CPU0_PE1_PCH_R_RXN<11> C3M26            1        CAP_0402-0.22UF,16V,10%,X7R,A3A
P3E_CPU0_PE1_PCH_R_RXN<11> U7C1             T59      LBG_CORE_QAT_EXT_D_BGA1-IC,H91A
P3E_CPU0_PE1_PCH_R_RXN<12> C3M4             1        CAP_0402-0.22UF,16V,10%,X7R,A3A
P3E_CPU0_PE1_PCH_R_RXN<12> U7C1             R65      LBG_CORE_QAT_EXT_D_BGA1-IC,H91A
P3E_CPU0_PE1_PCH_R_RXN<13> C3M14            1        CAP_0402-0.22UF,16V,10%,X7R,A3A
P3E_CPU0_PE1_PCH_R_RXN<13> U7C1             T63      LBG_CORE_QAT_EXT_D_BGA1-IC,H91A
P3E_CPU0_PE1_PCH_R_RXN<14> C3M12            1        CAP_0402-0.22UF,16V,10%,X7R,A3A
P3E_CPU0_PE1_PCH_R_RXN<14> U7C1             W65      LBG_CORE_QAT_EXT_D_BGA1-IC,H91A
P3E_CPU0_PE1_PCH_R_RXN<15> C3M1             1        CAP_0402-0.22UF,16V,10%,X7R,A3A
P3E_CPU0_PE1_PCH_R_RXN<15> U7C1             Y66      LBG_CORE_QAT_EXT_D_BGA1-IC,H91A
P3E_CPU0_PE1_PCH_R_RXP<8> C3M34            1        CAP_0402-0.22UF,16V,10%,X7R,A3A
P3E_CPU0_PE1_PCH_R_RXP<8> U7C1             M63      LBG_CORE_QAT_EXT_D_BGA1-IC,H91A
P3E_CPU0_PE1_PCH_R_RXP<9> C3M36            1        CAP_0402-0.22UF,16V,10%,X7R,A3A
P3E_CPU0_PE1_PCH_R_RXP<9> U7C1             M66      LBG_CORE_QAT_EXT_D_BGA1-IC,H91A
P3E_CPU0_PE1_PCH_R_RXP<10> C3M28            1        CAP_0402-0.22UF,16V,10%,X7R,A3A
P3E_CPU0_PE1_PCH_R_RXP<10> U7C1             P66      LBG_CORE_QAT_EXT_D_BGA1-IC,H91A
P3E_CPU0_PE1_PCH_R_RXP<11> C3M25            1        CAP_0402-0.22UF,16V,10%,X7R,A3A
P3E_CPU0_PE1_PCH_R_RXP<11> U7C1             V59      LBG_CORE_QAT_EXT_D_BGA1-IC,H91A
P3E_CPU0_PE1_PCH_R_RXP<12> C3M3             1        CAP_0402-0.22UF,16V,10%,X7R,A3A
P3E_CPU0_PE1_PCH_R_RXP<12> U7C1             U65      LBG_CORE_QAT_EXT_D_BGA1-IC,H91A
P3E_CPU0_PE1_PCH_R_RXP<13> C3M13            1        CAP_0402-0.22UF,16V,10%,X7R,A3A
P3E_CPU0_PE1_PCH_R_RXP<13> U7C1             U61      LBG_CORE_QAT_EXT_D_BGA1-IC,H91A
P3E_CPU0_PE1_PCH_R_RXP<14> C3M11            1        CAP_0402-0.22UF,16V,10%,X7R,A3A
P3E_CPU0_PE1_PCH_R_RXP<14> U7C1             V63      LBG_CORE_QAT_EXT_D_BGA1-IC,H91A
P3E_CPU0_PE1_PCH_R_RXP<15> C3M2             1        CAP_0402-0.22UF,16V,10%,X7R,A3A
P3E_CPU0_PE1_PCH_R_RXP<15> U7C1             AA65     LBG_CORE_QAT_EXT_D_BGA1-IC,H91A
P3E_CPU0_PE1_PCH_TXN<0>  C3P13            2        CAP_0402-0.22UF,16V,10%,X7R,A3A
P3E_CPU0_PE1_PCH_TXN<0>  U7C1             C48      LBG_CORE_QAT_EXT_D_BGA1-IC,H91A
P3E_CPU0_PE1_PCH_TXN<1>  C3P17            2        CAP_0402-0.22UF,16V,10%,X7R,A3A
P3E_CPU0_PE1_PCH_TXN<1>  U7C1             D49      LBG_CORE_QAT_EXT_D_BGA1-IC,H91A
P3E_CPU0_PE1_PCH_TXN<2>  C3P20            2        CAP_0402-0.22UF,16V,10%,X7R,A3A
P3E_CPU0_PE1_PCH_TXN<2>  U7C1             C50      LBG_CORE_QAT_EXT_D_BGA1-IC,H91A
P3E_CPU0_PE1_PCH_TXN<3>  C3P25            2        CAP_0402-0.22UF,16V,10%,X7R,A3A
P3E_CPU0_PE1_PCH_TXN<3>  U7C1             D51      LBG_CORE_QAT_EXT_D_BGA1-IC,H91A
P3E_CPU0_PE1_PCH_TXN<4>  C3P28            2        CAP_0402-0.22UF,16V,10%,X7R,A3A
P3E_CPU0_PE1_PCH_TXN<4>  U7C1             C52      LBG_CORE_QAT_EXT_D_BGA1-IC,H91A
P3E_CPU0_PE1_PCH_TXN<5>  C3P32            2        CAP_0402-0.22UF,16V,10%,X7R,A3A
P3E_CPU0_PE1_PCH_TXN<5>  U7C1             D53      LBG_CORE_QAT_EXT_D_BGA1-IC,H91A
P3E_CPU0_PE1_PCH_TXN<6>  C3P37            2        CAP_0402-0.22UF,16V,10%,X7R,A3A
P3E_CPU0_PE1_PCH_TXN<6>  U7C1             C54      LBG_CORE_QAT_EXT_D_BGA1-IC,H91A
P3E_CPU0_PE1_PCH_TXN<7>  C3P40            2        CAP_0402-0.22UF,16V,10%,X7R,A3A
P3E_CPU0_PE1_PCH_TXN<7>  U7C1             D55      LBG_CORE_QAT_EXT_D_BGA1-IC,H91A
P3E_CPU0_PE1_PCH_TXN<8>  C6B19            1        CAP_0402-0.22UF,16V,10%,X7R,A3A
P3E_CPU0_PE1_PCH_TXN<8>  U5D1             DT5      SKX_EXT_B_BGA1-IC,TBD
P3E_CPU0_PE1_PCH_TXN<9>  C6B17            1        CAP_0402-0.22UF,16V,10%,X7R,A3A
P3E_CPU0_PE1_PCH_TXN<9>  U5D1             DV3      SKX_EXT_B_BGA1-IC,TBD
P3E_CPU0_PE1_PCH_TXN<10> C6B15            1        CAP_0402-0.22UF,16V,10%,X7R,A3A
P3E_CPU0_PE1_PCH_TXN<10> U5D1             DW4      SKX_EXT_B_BGA1-IC,TBD
P3E_CPU0_PE1_PCH_TXN<11> C6B14            1        CAP_0402-0.22UF,16V,10%,X7R,A3A
P3E_CPU0_PE1_PCH_TXN<11> U5D1             DU6      SKX_EXT_B_BGA1-IC,TBD
P3E_CPU0_PE1_PCH_TXN<12> C6B11            1        CAP_0402-0.22UF,16V,10%,X7R,A3A
P3E_CPU0_PE1_PCH_TXN<12> U5D1             DV7      SKX_EXT_B_BGA1-IC,TBD
P3E_CPU0_PE1_PCH_TXN<13> C6B9             1        CAP_0402-0.22UF,16V,10%,X7R,A3A
P3E_CPU0_PE1_PCH_TXN<13> U5D1             DY7      SKX_EXT_B_BGA1-IC,TBD
P3E_CPU0_PE1_PCH_TXN<14> C6B6             1        CAP_0402-0.22UF,16V,10%,X7R,A3A
P3E_CPU0_PE1_PCH_TXN<14> U5D1             EA8      SKX_EXT_B_BGA1-IC,TBD
P3E_CPU0_PE1_PCH_TXN<15> C6B4             1        CAP_0402-0.22UF,16V,10%,X7R,A3A
P3E_CPU0_PE1_PCH_TXN<15> U5D1             ED9      SKX_EXT_B_BGA1-IC,TBD
P3E_CPU0_PE1_PCH_TXP<0>  C3P11            2        CAP_0402-0.22UF,16V,10%,X7R,A3A
P3E_CPU0_PE1_PCH_TXP<0>  U7C1             A48      LBG_CORE_QAT_EXT_D_BGA1-IC,H91A
P3E_CPU0_PE1_PCH_TXP<1>  C3P15            2        CAP_0402-0.22UF,16V,10%,X7R,A3A
P3E_CPU0_PE1_PCH_TXP<1>  U7C1             B49      LBG_CORE_QAT_EXT_D_BGA1-IC,H91A
P3E_CPU0_PE1_PCH_TXP<2>  C3P18            2        CAP_0402-0.22UF,16V,10%,X7R,A3A
P3E_CPU0_PE1_PCH_TXP<2>  U7C1             A50      LBG_CORE_QAT_EXT_D_BGA1-IC,H91A
P3E_CPU0_PE1_PCH_TXP<3>  C3P23            2        CAP_0402-0.22UF,16V,10%,X7R,A3A
P3E_CPU0_PE1_PCH_TXP<3>  U7C1             B51      LBG_CORE_QAT_EXT_D_BGA1-IC,H91A
P3E_CPU0_PE1_PCH_TXP<4>  C3P27            2        CAP_0402-0.22UF,16V,10%,X7R,A3A
P3E_CPU0_PE1_PCH_TXP<4>  U7C1             A52      LBG_CORE_QAT_EXT_D_BGA1-IC,H91A
P3E_CPU0_PE1_PCH_TXP<5>  C3P30            2        CAP_0402-0.22UF,16V,10%,X7R,A3A
P3E_CPU0_PE1_PCH_TXP<5>  U7C1             B53      LBG_CORE_QAT_EXT_D_BGA1-IC,H91A
P3E_CPU0_PE1_PCH_TXP<6>  C3P35            2        CAP_0402-0.22UF,16V,10%,X7R,A3A
P3E_CPU0_PE1_PCH_TXP<6>  U7C1             A54      LBG_CORE_QAT_EXT_D_BGA1-IC,H91A
P3E_CPU0_PE1_PCH_TXP<7>  C3P39            2        CAP_0402-0.22UF,16V,10%,X7R,A3A
P3E_CPU0_PE1_PCH_TXP<7>  U7C1             B55      LBG_CORE_QAT_EXT_D_BGA1-IC,H91A
P3E_CPU0_PE1_PCH_TXP<8>  C6B20            1        CAP_0402-0.22UF,16V,10%,X7R,A3A
P3E_CPU0_PE1_PCH_TXP<8>  U5D1             DR4      SKX_EXT_B_BGA1-IC,TBD
P3E_CPU0_PE1_PCH_TXP<9>  C6B18            1        CAP_0402-0.22UF,16V,10%,X7R,A3A
P3E_CPU0_PE1_PCH_TXP<9>  U5D1             DU2      SKX_EXT_B_BGA1-IC,TBD
P3E_CPU0_PE1_PCH_TXP<10> C6B16            1        CAP_0402-0.22UF,16V,10%,X7R,A3A
P3E_CPU0_PE1_PCH_TXP<10> U5D1             DU4      SKX_EXT_B_BGA1-IC,TBD
P3E_CPU0_PE1_PCH_TXP<11> C6B13            1        CAP_0402-0.22UF,16V,10%,X7R,A3A
P3E_CPU0_PE1_PCH_TXP<11> U5D1             DV5      SKX_EXT_B_BGA1-IC,TBD
P3E_CPU0_PE1_PCH_TXP<12> C6B12            1        CAP_0402-0.22UF,16V,10%,X7R,A3A
P3E_CPU0_PE1_PCH_TXP<12> U5D1             DT7      SKX_EXT_B_BGA1-IC,TBD
P3E_CPU0_PE1_PCH_TXP<13> C6B10            1        CAP_0402-0.22UF,16V,10%,X7R,A3A
P3E_CPU0_PE1_PCH_TXP<13> U5D1             DW6      SKX_EXT_B_BGA1-IC,TBD
P3E_CPU0_PE1_PCH_TXP<14> C6B8             1        CAP_0402-0.22UF,16V,10%,X7R,A3A
P3E_CPU0_PE1_PCH_TXP<14> U5D1             EB7      SKX_EXT_B_BGA1-IC,TBD
P3E_CPU0_PE1_PCH_TXP<15> C6B5             1        CAP_0402-0.22UF,16V,10%,X7R,A3A
P3E_CPU0_PE1_PCH_TXP<15> U5D1             EC8      SKX_EXT_B_BGA1-IC,TBD
P3E_CPU0_PE1_SS_C_TXN<0> C3P12            2        CAP_0402-0.22UF,16V,10%,EMPTY,A
P3E_CPU0_PE1_SS_C_TXN<0> J8G1             53       SCONN200_H68296001_SM-CONN,H68A
P3E_CPU0_PE1_SS_C_TXN<1> C3P16            2        CAP_0402-0.22UF,16V,10%,EMPTY,A
P3E_CPU0_PE1_SS_C_TXN<1> J8G1             59       SCONN200_H68296001_SM-CONN,H68A
P3E_CPU0_PE1_SS_C_TXN<2> C3P21            2        CAP_0402-0.22UF,16V,10%,EMPTY,A
P3E_CPU0_PE1_SS_C_TXN<2> J8G1             69       SCONN200_H68296001_SM-CONN,H68A
P3E_CPU0_PE1_SS_C_TXN<3> C3P24            2        CAP_0402-0.22UF,16V,10%,EMPTY,A
P3E_CPU0_PE1_SS_C_TXN<3> J8G1             75       SCONN200_H68296001_SM-CONN,H68A
P3E_CPU0_PE1_SS_C_TXN<4> C3P29            2        CAP_0402-0.22UF,16V,10%,EMPTY,A
P3E_CPU0_PE1_SS_C_TXN<4> J8G1             81       SCONN200_H68296001_SM-CONN,H68A
P3E_CPU0_PE1_SS_C_TXN<5> C3P33            2        CAP_0402-0.22UF,16V,10%,EMPTY,A
P3E_CPU0_PE1_SS_C_TXN<5> J8G1             87       SCONN200_H68296001_SM-CONN,H68A
P3E_CPU0_PE1_SS_C_TXN<6> C3P36            2        CAP_0402-0.22UF,16V,10%,EMPTY,A
P3E_CPU0_PE1_SS_C_TXN<6> J8G1             93       SCONN200_H68296001_SM-CONN,H68A
P3E_CPU0_PE1_SS_C_TXN<7> C3P41            2        CAP_0402-0.22UF,16V,10%,EMPTY,A
P3E_CPU0_PE1_SS_C_TXN<7> J8G1             99       SCONN200_H68296001_SM-CONN,H68A
P3E_CPU0_PE1_SS_C_TXP<0> C3P10            2        CAP_0402-0.22UF,16V,10%,EMPTY,A
P3E_CPU0_PE1_SS_C_TXP<0> J8G1             51       SCONN200_H68296001_SM-CONN,H68A
P3E_CPU0_PE1_SS_C_TXP<1> C3P14            2        CAP_0402-0.22UF,16V,10%,EMPTY,A
P3E_CPU0_PE1_SS_C_TXP<1> J8G1             57       SCONN200_H68296001_SM-CONN,H68A
P3E_CPU0_PE1_SS_C_TXP<2> C3P19            2        CAP_0402-0.22UF,16V,10%,EMPTY,A
P3E_CPU0_PE1_SS_C_TXP<2> J8G1             67       SCONN200_H68296001_SM-CONN,H68A
P3E_CPU0_PE1_SS_C_TXP<3> C3P22            2        CAP_0402-0.22UF,16V,10%,EMPTY,A
P3E_CPU0_PE1_SS_C_TXP<3> J8G1             73       SCONN200_H68296001_SM-CONN,H68A
P3E_CPU0_PE1_SS_C_TXP<4> C3P26            2        CAP_0402-0.22UF,16V,10%,EMPTY,A
P3E_CPU0_PE1_SS_C_TXP<4> J8G1             79       SCONN200_H68296001_SM-CONN,H68A
P3E_CPU0_PE1_SS_C_TXP<5> C3P31            2        CAP_0402-0.22UF,16V,10%,EMPTY,A
P3E_CPU0_PE1_SS_C_TXP<5> J8G1             85       SCONN200_H68296001_SM-CONN,H68A
P3E_CPU0_PE1_SS_C_TXP<6> C3P34            2        CAP_0402-0.22UF,16V,10%,EMPTY,A
P3E_CPU0_PE1_SS_C_TXP<6> J8G1             91       SCONN200_H68296001_SM-CONN,H68A
P3E_CPU0_PE1_SS_C_TXP<7> C3P38            2        CAP_0402-0.22UF,16V,10%,EMPTY,A
P3E_CPU0_PE1_SS_C_TXP<7> J8G1             97       SCONN200_H68296001_SM-CONN,H68A
P3E_CPU0_PE1_SS_RXN<0>   C2U4             2        CAP_0402-0.22UF,16V,10%,X7R,A3A
P3E_CPU0_PE1_SS_RXN<0>   R2U15            2        RES_0402-0.0,5%,1/16W,EMPTY,G2A
P3E_CPU0_PE1_SS_RXN<0>   U5D1             CW8      SKX_EXT_B_BGA1-IC,TBD
P3E_CPU0_PE1_SS_RXN<1>   C2U6             2        CAP_0402-0.22UF,16V,10%,X7R,A3A
P3E_CPU0_PE1_SS_RXN<1>   R2U17            2        RES_0402-0.0,5%,1/16W,EMPTY,G2A
P3E_CPU0_PE1_SS_RXN<1>   U5D1             DA8      SKX_EXT_B_BGA1-IC,TBD
P3E_CPU0_PE1_SS_RXN<2>   C2U8             2        CAP_0402-0.22UF,16V,10%,X7R,A3A
P3E_CPU0_PE1_SS_RXN<2>   R2U19            2        RES_0402-0.0,5%,1/16W,EMPTY,G2A
P3E_CPU0_PE1_SS_RXN<2>   U5D1             DC8      SKX_EXT_B_BGA1-IC,TBD
P3E_CPU0_PE1_SS_RXN<3>   C2U10            2        CAP_0402-0.22UF,16V,10%,X7R,A3A
P3E_CPU0_PE1_SS_RXN<3>   R2U21            2        RES_0402-0.0,5%,1/16W,EMPTY,G2A
P3E_CPU0_PE1_SS_RXN<3>   U5D1             DC10     SKX_EXT_B_BGA1-IC,TBD
P3E_CPU0_PE1_SS_RXN<4>   C2U12            2        CAP_0402-0.22UF,16V,10%,X7R,A3A
P3E_CPU0_PE1_SS_RXN<4>   R2U23            2        RES_0402-0.0,5%,1/16W,EMPTY,G2A
P3E_CPU0_PE1_SS_RXN<4>   U5D1             DE10     SKX_EXT_B_BGA1-IC,TBD
P3E_CPU0_PE1_SS_RXN<5>   C2U14            2        CAP_0402-0.22UF,16V,10%,X7R,A3A
P3E_CPU0_PE1_SS_RXN<5>   R2U25            2        RES_0402-0.0,5%,1/16W,EMPTY,G2A
P3E_CPU0_PE1_SS_RXN<5>   U5D1             DH9      SKX_EXT_B_BGA1-IC,TBD
P3E_CPU0_PE1_SS_RXN<6>   C2U16            2        CAP_0402-0.22UF,16V,10%,X7R,A3A
P3E_CPU0_PE1_SS_RXN<6>   R2U27            2        RES_0402-0.0,5%,1/16W,EMPTY,G2A
P3E_CPU0_PE1_SS_RXN<6>   U5D1             DK9      SKX_EXT_B_BGA1-IC,TBD
P3E_CPU0_PE1_SS_RXN<7>   C2U18            2        CAP_0402-0.22UF,16V,10%,X7R,A3A
P3E_CPU0_PE1_SS_RXN<7>   R2U29            2        RES_0402-0.0,5%,1/16W,EMPTY,G2A
P3E_CPU0_PE1_SS_RXN<7>   U5D1             DM9      SKX_EXT_B_BGA1-IC,TBD
P3E_CPU0_PE1_SS_RXP<0>   C2U3             2        CAP_0402-0.22UF,16V,10%,X7R,A3A
P3E_CPU0_PE1_SS_RXP<0>   R2U14            2        RES_0402-0.0,5%,1/16W,EMPTY,G2A
P3E_CPU0_PE1_SS_RXP<0>   U5D1             CU8      SKX_EXT_B_BGA1-IC,TBD
P3E_CPU0_PE1_SS_RXP<1>   C2U5             2        CAP_0402-0.22UF,16V,10%,X7R,A3A
P3E_CPU0_PE1_SS_RXP<1>   R2U16            2        RES_0402-0.0,5%,1/16W,EMPTY,G2A
P3E_CPU0_PE1_SS_RXP<1>   U5D1             CY7      SKX_EXT_B_BGA1-IC,TBD
P3E_CPU0_PE1_SS_RXP<2>   C2U7             2        CAP_0402-0.22UF,16V,10%,X7R,A3A
P3E_CPU0_PE1_SS_RXP<2>   R2U18            2        RES_0402-0.0,5%,1/16W,EMPTY,G2A
P3E_CPU0_PE1_SS_RXP<2>   U5D1             DB9      SKX_EXT_B_BGA1-IC,TBD
P3E_CPU0_PE1_SS_RXP<3>   C2U9             2        CAP_0402-0.22UF,16V,10%,X7R,A3A
P3E_CPU0_PE1_SS_RXP<3>   R2U20            2        RES_0402-0.0,5%,1/16W,EMPTY,G2A
P3E_CPU0_PE1_SS_RXP<3>   U5D1             DA10     SKX_EXT_B_BGA1-IC,TBD
P3E_CPU0_PE1_SS_RXP<4>   C2U11            2        CAP_0402-0.22UF,16V,10%,X7R,A3A
P3E_CPU0_PE1_SS_RXP<4>   R2U22            2        RES_0402-0.0,5%,1/16W,EMPTY,G2A
P3E_CPU0_PE1_SS_RXP<4>   U5D1             DD9      SKX_EXT_B_BGA1-IC,TBD
P3E_CPU0_PE1_SS_RXP<5>   C2U13            2        CAP_0402-0.22UF,16V,10%,X7R,A3A
P3E_CPU0_PE1_SS_RXP<5>   R2U24            2        RES_0402-0.0,5%,1/16W,EMPTY,G2A
P3E_CPU0_PE1_SS_RXP<5>   U5D1             DF9      SKX_EXT_B_BGA1-IC,TBD
P3E_CPU0_PE1_SS_RXP<6>   C2U15            2        CAP_0402-0.22UF,16V,10%,X7R,A3A
P3E_CPU0_PE1_SS_RXP<6>   R2U26            2        RES_0402-0.0,5%,1/16W,EMPTY,G2A
P3E_CPU0_PE1_SS_RXP<6>   U5D1             DJ8      SKX_EXT_B_BGA1-IC,TBD
P3E_CPU0_PE1_SS_RXP<7>   C2U17            2        CAP_0402-0.22UF,16V,10%,X7R,A3A
P3E_CPU0_PE1_SS_RXP<7>   R2U28            2        RES_0402-0.0,5%,1/16W,EMPTY,G2A
P3E_CPU0_PE1_SS_RXP<7>   U5D1             DL10     SKX_EXT_B_BGA1-IC,TBD
P3E_CPU0_PE1_SS_R_RXN<0> J8G1             56       SCONN200_H68296001_SM-CONN,H68A
P3E_CPU0_PE1_SS_R_RXN<0> R2U15            1        RES_0402-0.0,5%,1/16W,EMPTY,G2A
P3E_CPU0_PE1_SS_R_RXN<1> J8G1             62       SCONN200_H68296001_SM-CONN,H68A
P3E_CPU0_PE1_SS_R_RXN<1> R2U17            1        RES_0402-0.0,5%,1/16W,EMPTY,G2A
P3E_CPU0_PE1_SS_R_RXN<2> J8G1             72       SCONN200_H68296001_SM-CONN,H68A
P3E_CPU0_PE1_SS_R_RXN<2> R2U19            1        RES_0402-0.0,5%,1/16W,EMPTY,G2A
P3E_CPU0_PE1_SS_R_RXN<3> J8G1             78       SCONN200_H68296001_SM-CONN,H68A
P3E_CPU0_PE1_SS_R_RXN<3> R2U21            1        RES_0402-0.0,5%,1/16W,EMPTY,G2A
P3E_CPU0_PE1_SS_R_RXN<4> J8G1             84       SCONN200_H68296001_SM-CONN,H68A
P3E_CPU0_PE1_SS_R_RXN<4> R2U23            1        RES_0402-0.0,5%,1/16W,EMPTY,G2A
P3E_CPU0_PE1_SS_R_RXN<5> J8G1             90       SCONN200_H68296001_SM-CONN,H68A
P3E_CPU0_PE1_SS_R_RXN<5> R2U25            1        RES_0402-0.0,5%,1/16W,EMPTY,G2A
P3E_CPU0_PE1_SS_R_RXN<6> J8G1             96       SCONN200_H68296001_SM-CONN,H68A
P3E_CPU0_PE1_SS_R_RXN<6> R2U27            1        RES_0402-0.0,5%,1/16W,EMPTY,G2A
P3E_CPU0_PE1_SS_R_RXN<7> J8G1             102      SCONN200_H68296001_SM-CONN,H68A
P3E_CPU0_PE1_SS_R_RXN<7> R2U29            1        RES_0402-0.0,5%,1/16W,EMPTY,G2A
P3E_CPU0_PE1_SS_R_RXP<0> J8G1             54       SCONN200_H68296001_SM-CONN,H68A
P3E_CPU0_PE1_SS_R_RXP<0> R2U14            1        RES_0402-0.0,5%,1/16W,EMPTY,G2A
P3E_CPU0_PE1_SS_R_RXP<1> J8G1             60       SCONN200_H68296001_SM-CONN,H68A
P3E_CPU0_PE1_SS_R_RXP<1> R2U16            1        RES_0402-0.0,5%,1/16W,EMPTY,G2A
P3E_CPU0_PE1_SS_R_RXP<2> J8G1             70       SCONN200_H68296001_SM-CONN,H68A
P3E_CPU0_PE1_SS_R_RXP<2> R2U18            1        RES_0402-0.0,5%,1/16W,EMPTY,G2A
P3E_CPU0_PE1_SS_R_RXP<3> J8G1             76       SCONN200_H68296001_SM-CONN,H68A
P3E_CPU0_PE1_SS_R_RXP<3> R2U20            1        RES_0402-0.0,5%,1/16W,EMPTY,G2A
P3E_CPU0_PE1_SS_R_RXP<4> J8G1             82       SCONN200_H68296001_SM-CONN,H68A
P3E_CPU0_PE1_SS_R_RXP<4> R2U22            1        RES_0402-0.0,5%,1/16W,EMPTY,G2A
P3E_CPU0_PE1_SS_R_RXP<5> J8G1             88       SCONN200_H68296001_SM-CONN,H68A
P3E_CPU0_PE1_SS_R_RXP<5> R2U24            1        RES_0402-0.0,5%,1/16W,EMPTY,G2A
P3E_CPU0_PE1_SS_R_RXP<6> J8G1             94       SCONN200_H68296001_SM-CONN,H68A
P3E_CPU0_PE1_SS_R_RXP<6> R2U26            1        RES_0402-0.0,5%,1/16W,EMPTY,G2A
P3E_CPU0_PE1_SS_R_RXP<7> J8G1             100      SCONN200_H68296001_SM-CONN,H68A
P3E_CPU0_PE1_SS_R_RXP<7> R2U28            1        RES_0402-0.0,5%,1/16W,EMPTY,G2A
P3E_CPU0_PE1_SS_TXN<0>   C3P12            1        CAP_0402-0.22UF,16V,10%,EMPTY,A
P3E_CPU0_PE1_SS_TXN<0>   C3P13            1        CAP_0402-0.22UF,16V,10%,X7R,A3A
P3E_CPU0_PE1_SS_TXN<0>   U5D1             DA2      SKX_EXT_B_BGA1-IC,TBD
P3E_CPU0_PE1_SS_TXN<1>   C3P16            1        CAP_0402-0.22UF,16V,10%,EMPTY,A
P3E_CPU0_PE1_SS_TXN<1>   C3P17            1        CAP_0402-0.22UF,16V,10%,X7R,A3A
P3E_CPU0_PE1_SS_TXN<1>   U5D1             DC2      SKX_EXT_B_BGA1-IC,TBD
P3E_CPU0_PE1_SS_TXN<2>   C3P20            1        CAP_0402-0.22UF,16V,10%,X7R,A3A
P3E_CPU0_PE1_SS_TXN<2>   C3P21            1        CAP_0402-0.22UF,16V,10%,EMPTY,A
P3E_CPU0_PE1_SS_TXN<2>   U5D1             DE2      SKX_EXT_B_BGA1-IC,TBD
P3E_CPU0_PE1_SS_TXN<3>   C3P24            1        CAP_0402-0.22UF,16V,10%,EMPTY,A
P3E_CPU0_PE1_SS_TXN<3>   C3P25            1        CAP_0402-0.22UF,16V,10%,X7R,A3A
P3E_CPU0_PE1_SS_TXN<3>   U5D1             DE4      SKX_EXT_B_BGA1-IC,TBD
P3E_CPU0_PE1_SS_TXN<4>   C3P28            1        CAP_0402-0.22UF,16V,10%,X7R,A3A
P3E_CPU0_PE1_SS_TXN<4>   C3P29            1        CAP_0402-0.22UF,16V,10%,EMPTY,A
P3E_CPU0_PE1_SS_TXN<4>   U5D1             DG4      SKX_EXT_B_BGA1-IC,TBD
P3E_CPU0_PE1_SS_TXN<5>   C3P32            1        CAP_0402-0.22UF,16V,10%,X7R,A3A
P3E_CPU0_PE1_SS_TXN<5>   C3P33            1        CAP_0402-0.22UF,16V,10%,EMPTY,A
P3E_CPU0_PE1_SS_TXN<5>   U5D1             DK3      SKX_EXT_B_BGA1-IC,TBD
P3E_CPU0_PE1_SS_TXN<6>   C3P36            1        CAP_0402-0.22UF,16V,10%,EMPTY,A
P3E_CPU0_PE1_SS_TXN<6>   C3P37            1        CAP_0402-0.22UF,16V,10%,X7R,A3A
P3E_CPU0_PE1_SS_TXN<6>   U5D1             DM3      SKX_EXT_B_BGA1-IC,TBD
P3E_CPU0_PE1_SS_TXN<7>   C3P40            1        CAP_0402-0.22UF,16V,10%,X7R,A3A
P3E_CPU0_PE1_SS_TXN<7>   C3P41            1        CAP_0402-0.22UF,16V,10%,EMPTY,A
P3E_CPU0_PE1_SS_TXN<7>   U5D1             DN4      SKX_EXT_B_BGA1-IC,TBD
P3E_CPU0_PE1_SS_TXP<0>   C3P10            1        CAP_0402-0.22UF,16V,10%,EMPTY,A
P3E_CPU0_PE1_SS_TXP<0>   C3P11            1        CAP_0402-0.22UF,16V,10%,X7R,A3A
P3E_CPU0_PE1_SS_TXP<0>   U5D1             CW2      SKX_EXT_B_BGA1-IC,TBD
P3E_CPU0_PE1_SS_TXP<1>   C3P14            1        CAP_0402-0.22UF,16V,10%,EMPTY,A
P3E_CPU0_PE1_SS_TXP<1>   C3P15            1        CAP_0402-0.22UF,16V,10%,X7R,A3A
P3E_CPU0_PE1_SS_TXP<1>   U5D1             DB1      SKX_EXT_B_BGA1-IC,TBD
P3E_CPU0_PE1_SS_TXP<2>   C3P18            1        CAP_0402-0.22UF,16V,10%,X7R,A3A
P3E_CPU0_PE1_SS_TXP<2>   C3P19            1        CAP_0402-0.22UF,16V,10%,EMPTY,A
P3E_CPU0_PE1_SS_TXP<2>   U5D1             DD3      SKX_EXT_B_BGA1-IC,TBD
P3E_CPU0_PE1_SS_TXP<3>   C3P22            1        CAP_0402-0.22UF,16V,10%,EMPTY,A
P3E_CPU0_PE1_SS_TXP<3>   C3P23            1        CAP_0402-0.22UF,16V,10%,X7R,A3A
P3E_CPU0_PE1_SS_TXP<3>   U5D1             DC4      SKX_EXT_B_BGA1-IC,TBD
P3E_CPU0_PE1_SS_TXP<4>   C3P26            1        CAP_0402-0.22UF,16V,10%,EMPTY,A
P3E_CPU0_PE1_SS_TXP<4>   C3P27            1        CAP_0402-0.22UF,16V,10%,X7R,A3A
P3E_CPU0_PE1_SS_TXP<4>   U5D1             DF3      SKX_EXT_B_BGA1-IC,TBD
P3E_CPU0_PE1_SS_TXP<5>   C3P30            1        CAP_0402-0.22UF,16V,10%,X7R,A3A
P3E_CPU0_PE1_SS_TXP<5>   C3P31            1        CAP_0402-0.22UF,16V,10%,EMPTY,A
P3E_CPU0_PE1_SS_TXP<5>   U5D1             DH3      SKX_EXT_B_BGA1-IC,TBD
P3E_CPU0_PE1_SS_TXP<6>   C3P34            1        CAP_0402-0.22UF,16V,10%,EMPTY,A
P3E_CPU0_PE1_SS_TXP<6>   C3P35            1        CAP_0402-0.22UF,16V,10%,X7R,A3A
P3E_CPU0_PE1_SS_TXP<6>   U5D1             DL2      SKX_EXT_B_BGA1-IC,TBD
P3E_CPU0_PE1_SS_TXP<7>   C3P38            1        CAP_0402-0.22UF,16V,10%,EMPTY,A
P3E_CPU0_PE1_SS_TXP<7>   C3P39            1        CAP_0402-0.22UF,16V,10%,X7R,A3A
P3E_CPU0_PE1_SS_TXP<7>   U5D1             DP3      SKX_EXT_B_BGA1-IC,TBD
P3E_CPU0_PE2_SS_C_TXN<0> C8G10            2        CAP_0402-0.22UF,16V,10%,X7R,A3A
P3E_CPU0_PE2_SS_C_TXN<0> J8G1             103      SCONN200_H68296001_SM-CONN,H68A
P3E_CPU0_PE2_SS_C_TXN<1> C8G7             2        CAP_0402-0.22UF,16V,10%,X7R,A3A
P3E_CPU0_PE2_SS_C_TXN<1> J8G1             111      SCONN200_H68296001_SM-CONN,H68A
P3E_CPU0_PE2_SS_C_TXN<2> C8G6             2        CAP_0402-0.22UF,16V,10%,X7R,A3A
P3E_CPU0_PE2_SS_C_TXN<2> J8G1             115      SCONN200_H68296001_SM-CONN,H68A
P3E_CPU0_PE2_SS_C_TXN<3> C8G4             2        CAP_0402-0.22UF,16V,10%,X7R,A3A
P3E_CPU0_PE2_SS_C_TXN<3> J8G1             121      SCONN200_H68296001_SM-CONN,H68A
P3E_CPU0_PE2_SS_C_TXN<4> C8G2             2        CAP_0402-0.22UF,16V,10%,X7R,A3A
P3E_CPU0_PE2_SS_C_TXN<4> J8G1             127      SCONN200_H68296001_SM-CONN,H68A
P3E_CPU0_PE2_SS_C_TXN<5> C7G26            2        CAP_0402-0.22UF,16V,10%,X7R,A3A
P3E_CPU0_PE2_SS_C_TXN<5> J8G1             133      SCONN200_H68296001_SM-CONN,H68A
P3E_CPU0_PE2_SS_C_TXN<6> C7G24            2        CAP_0402-0.22UF,16V,10%,X7R,A3A
P3E_CPU0_PE2_SS_C_TXN<6> J8G1             139      SCONN200_H68296001_SM-CONN,H68A
P3E_CPU0_PE2_SS_C_TXN<7> C7G22            2        CAP_0402-0.22UF,16V,10%,X7R,A3A
P3E_CPU0_PE2_SS_C_TXN<7> J8G1             145      SCONN200_H68296001_SM-CONN,H68A
P3E_CPU0_PE2_SS_C_TXN<8> C7G20            2        CAP_0402-0.22UF,16V,10%,X7R,A3A
P3E_CPU0_PE2_SS_C_TXN<8> J8G1             151      SCONN200_H68296001_SM-CONN,H68A
P3E_CPU0_PE2_SS_C_TXN<9> C7G18            2        CAP_0402-0.22UF,16V,10%,X7R,A3A
P3E_CPU0_PE2_SS_C_TXN<9> J8G1             157      SCONN200_H68296001_SM-CONN,H68A
P3E_CPU0_PE2_SS_C_TXN<10> C7G16            2        CAP_0402-0.22UF,16V,10%,X7R,A3A
P3E_CPU0_PE2_SS_C_TXN<10> J8G1             163      SCONN200_H68296001_SM-CONN,H68A
P3E_CPU0_PE2_SS_C_TXN<11> C7G13            2        CAP_0402-0.22UF,16V,10%,X7R,A3A
P3E_CPU0_PE2_SS_C_TXN<11> J8G1             171      SCONN200_H68296001_SM-CONN,H68A
P3E_CPU0_PE2_SS_C_TXN<12> C7G12            2        CAP_0402-0.22UF,16V,10%,X7R,A3A
P3E_CPU0_PE2_SS_C_TXN<12> J8G1             175      SCONN200_H68296001_SM-CONN,H68A
P3E_CPU0_PE2_SS_C_TXN<13> C7G10            2        CAP_0402-0.22UF,16V,10%,X7R,A3A
P3E_CPU0_PE2_SS_C_TXN<13> J8G1             181      SCONN200_H68296001_SM-CONN,H68A
P3E_CPU0_PE2_SS_C_TXN<14> C7G7             2        CAP_0402-0.22UF,16V,10%,X7R,A3A
P3E_CPU0_PE2_SS_C_TXN<14> J8G1             189      SCONN200_H68296001_SM-CONN,H68A
P3E_CPU0_PE2_SS_C_TXN<15> C7G6             2        CAP_0402-0.22UF,16V,10%,X7R,A3A
P3E_CPU0_PE2_SS_C_TXN<15> J8G1             193      SCONN200_H68296001_SM-CONN,H68A
P3E_CPU0_PE2_SS_C_TXP<0> C8G9             2        CAP_0402-0.22UF,16V,10%,X7R,A3A
P3E_CPU0_PE2_SS_C_TXP<0> J8G1             105      SCONN200_H68296001_SM-CONN,H68A
P3E_CPU0_PE2_SS_C_TXP<1> C8G8             2        CAP_0402-0.22UF,16V,10%,X7R,A3A
P3E_CPU0_PE2_SS_C_TXP<1> J8G1             109      SCONN200_H68296001_SM-CONN,H68A
P3E_CPU0_PE2_SS_C_TXP<2> C8G5             2        CAP_0402-0.22UF,16V,10%,X7R,A3A
P3E_CPU0_PE2_SS_C_TXP<2> J8G1             117      SCONN200_H68296001_SM-CONN,H68A
P3E_CPU0_PE2_SS_C_TXP<3> C8G3             2        CAP_0402-0.22UF,16V,10%,X7R,A3A
P3E_CPU0_PE2_SS_C_TXP<3> J8G1             123      SCONN200_H68296001_SM-CONN,H68A
P3E_CPU0_PE2_SS_C_TXP<4> C8G1             2        CAP_0402-0.22UF,16V,10%,X7R,A3A
P3E_CPU0_PE2_SS_C_TXP<4> J8G1             129      SCONN200_H68296001_SM-CONN,H68A
P3E_CPU0_PE2_SS_C_TXP<5> C7G25            2        CAP_0402-0.22UF,16V,10%,X7R,A3A
P3E_CPU0_PE2_SS_C_TXP<5> J8G1             135      SCONN200_H68296001_SM-CONN,H68A
P3E_CPU0_PE2_SS_C_TXP<6> C7G23            2        CAP_0402-0.22UF,16V,10%,X7R,A3A
P3E_CPU0_PE2_SS_C_TXP<6> J8G1             141      SCONN200_H68296001_SM-CONN,H68A
P3E_CPU0_PE2_SS_C_TXP<7> C7G21            2        CAP_0402-0.22UF,16V,10%,X7R,A3A
P3E_CPU0_PE2_SS_C_TXP<7> J8G1             147      SCONN200_H68296001_SM-CONN,H68A
P3E_CPU0_PE2_SS_C_TXP<8> C7G19            2        CAP_0402-0.22UF,16V,10%,X7R,A3A
P3E_CPU0_PE2_SS_C_TXP<8> J8G1             153      SCONN200_H68296001_SM-CONN,H68A
P3E_CPU0_PE2_SS_C_TXP<9> C7G17            2        CAP_0402-0.22UF,16V,10%,X7R,A3A
P3E_CPU0_PE2_SS_C_TXP<9> J8G1             159      SCONN200_H68296001_SM-CONN,H68A
P3E_CPU0_PE2_SS_C_TXP<10> C7G15            2        CAP_0402-0.22UF,16V,10%,X7R,A3A
P3E_CPU0_PE2_SS_C_TXP<10> J8G1             165      SCONN200_H68296001_SM-CONN,H68A
P3E_CPU0_PE2_SS_C_TXP<11> C7G14            2        CAP_0402-0.22UF,16V,10%,X7R,A3A
P3E_CPU0_PE2_SS_C_TXP<11> J8G1             169      SCONN200_H68296001_SM-CONN,H68A
P3E_CPU0_PE2_SS_C_TXP<12> C7G11            2        CAP_0402-0.22UF,16V,10%,X7R,A3A
P3E_CPU0_PE2_SS_C_TXP<12> J8G1             177      SCONN200_H68296001_SM-CONN,H68A
P3E_CPU0_PE2_SS_C_TXP<13> C7G9             2        CAP_0402-0.22UF,16V,10%,X7R,A3A
P3E_CPU0_PE2_SS_C_TXP<13> J8G1             183      SCONN200_H68296001_SM-CONN,H68A
P3E_CPU0_PE2_SS_C_TXP<14> C7G8             2        CAP_0402-0.22UF,16V,10%,X7R,A3A
P3E_CPU0_PE2_SS_C_TXP<14> J8G1             187      SCONN200_H68296001_SM-CONN,H68A
P3E_CPU0_PE2_SS_C_TXP<15> C7G5             2        CAP_0402-0.22UF,16V,10%,X7R,A3A
P3E_CPU0_PE2_SS_C_TXP<15> J8G1             195      SCONN200_H68296001_SM-CONN,H68A
P3E_CPU0_PE2_SS_RXN<0>   J8G1             106      SCONN200_H68296001_SM-CONN,H68A
P3E_CPU0_PE2_SS_RXN<0>   U5D1             CT9      SKX_EXT_B_BGA1-IC,TBD
P3E_CPU0_PE2_SS_RXN<1>   J8G1             112      SCONN200_H68296001_SM-CONN,H68A
P3E_CPU0_PE2_SS_RXN<1>   U5D1             CP9      SKX_EXT_B_BGA1-IC,TBD
P3E_CPU0_PE2_SS_RXN<2>   J8G1             118      SCONN200_H68296001_SM-CONN,H68A
P3E_CPU0_PE2_SS_RXN<2>   U5D1             CP7      SKX_EXT_B_BGA1-IC,TBD
P3E_CPU0_PE2_SS_RXN<3>   J8G1             124      SCONN200_H68296001_SM-CONN,H68A
P3E_CPU0_PE2_SS_RXN<3>   U5D1             CM7      SKX_EXT_B_BGA1-IC,TBD
P3E_CPU0_PE2_SS_RXN<4>   J8G1             130      SCONN200_H68296001_SM-CONN,H68A
P3E_CPU0_PE2_SS_RXN<4>   U5D1             CK7      SKX_EXT_B_BGA1-IC,TBD
P3E_CPU0_PE2_SS_RXN<5>   J8G1             136      SCONN200_H68296001_SM-CONN,H68A
P3E_CPU0_PE2_SS_RXN<5>   U5D1             CG8      SKX_EXT_B_BGA1-IC,TBD
P3E_CPU0_PE2_SS_RXN<6>   J8G1             144      SCONN200_H68296001_SM-CONN,H68A
P3E_CPU0_PE2_SS_RXN<6>   U5D1             CE6      SKX_EXT_B_BGA1-IC,TBD
P3E_CPU0_PE2_SS_RXN<7>   J8G1             148      SCONN200_H68296001_SM-CONN,H68A
P3E_CPU0_PE2_SS_RXN<7>   U5D1             CE8      SKX_EXT_B_BGA1-IC,TBD
P3E_CPU0_PE2_SS_RXN<8>   J8G1             154      SCONN200_H68296001_SM-CONN,H68A
P3E_CPU0_PE2_SS_RXN<8>   U5D1             BY9      SKX_EXT_B_BGA1-IC,TBD
P3E_CPU0_PE2_SS_RXN<9>   J8G1             160      SCONN200_H68296001_SM-CONN,H68A
P3E_CPU0_PE2_SS_RXN<9>   U5D1             BY7      SKX_EXT_B_BGA1-IC,TBD
P3E_CPU0_PE2_SS_RXN<10>  J8G1             166      SCONN200_H68296001_SM-CONN,H68A
P3E_CPU0_PE2_SS_RXN<10>  U5D1             BV7      SKX_EXT_B_BGA1-IC,TBD
P3E_CPU0_PE2_SS_RXN<11>  J8G1             172      SCONN200_H68296001_SM-CONN,H68A
P3E_CPU0_PE2_SS_RXN<11>  U5D1             BT7      SKX_EXT_B_BGA1-IC,TBD
P3E_CPU0_PE2_SS_RXN<12>  J8G1             178      SCONN200_H68296001_SM-CONN,H68A
P3E_CPU0_PE2_SS_RXN<12>  U5D1             BR8      SKX_EXT_B_BGA1-IC,TBD
P3E_CPU0_PE2_SS_RXN<13>  J8G1             186      SCONN200_H68296001_SM-CONN,H68A
P3E_CPU0_PE2_SS_RXN<13>  U5D1             BN8      SKX_EXT_B_BGA1-IC,TBD
P3E_CPU0_PE2_SS_RXN<14>  J8G1             190      SCONN200_H68296001_SM-CONN,H68A
P3E_CPU0_PE2_SS_RXN<14>  U5D1             BL8      SKX_EXT_B_BGA1-IC,TBD
P3E_CPU0_PE2_SS_RXN<15>  J8G1             196      SCONN200_H68296001_SM-CONN,H68A
P3E_CPU0_PE2_SS_RXN<15>  U5D1             BK9      SKX_EXT_B_BGA1-IC,TBD
P3E_CPU0_PE2_SS_RXP<0>   J8G1             108      SCONN200_H68296001_SM-CONN,H68A
P3E_CPU0_PE2_SS_RXP<0>   U5D1             CR8      SKX_EXT_B_BGA1-IC,TBD
P3E_CPU0_PE2_SS_RXP<1>   J8G1             114      SCONN200_H68296001_SM-CONN,H68A
P3E_CPU0_PE2_SS_RXP<1>   U5D1             CM9      SKX_EXT_B_BGA1-IC,TBD
P3E_CPU0_PE2_SS_RXP<2>   J8G1             120      SCONN200_H68296001_SM-CONN,H68A
P3E_CPU0_PE2_SS_RXP<2>   U5D1             CN8      SKX_EXT_B_BGA1-IC,TBD
P3E_CPU0_PE2_SS_RXP<3>   J8G1             126      SCONN200_H68296001_SM-CONN,H68A
P3E_CPU0_PE2_SS_RXP<3>   U5D1             CL6      SKX_EXT_B_BGA1-IC,TBD
P3E_CPU0_PE2_SS_RXP<4>   J8G1             132      SCONN200_H68296001_SM-CONN,H68A
P3E_CPU0_PE2_SS_RXP<4>   U5D1             CH7      SKX_EXT_B_BGA1-IC,TBD
P3E_CPU0_PE2_SS_RXP<5>   J8G1             138      SCONN200_H68296001_SM-CONN,H68A
P3E_CPU0_PE2_SS_RXP<5>   U5D1             CF7      SKX_EXT_B_BGA1-IC,TBD
P3E_CPU0_PE2_SS_RXP<6>   J8G1             142      SCONN200_H68296001_SM-CONN,H68A
P3E_CPU0_PE2_SS_RXP<6>   U5D1             CD7      SKX_EXT_B_BGA1-IC,TBD
P3E_CPU0_PE2_SS_RXP<7>   J8G1             150      SCONN200_H68296001_SM-CONN,H68A
P3E_CPU0_PE2_SS_RXP<7>   U5D1             CC8      SKX_EXT_B_BGA1-IC,TBD
P3E_CPU0_PE2_SS_RXP<8>   J8G1             156      SCONN200_H68296001_SM-CONN,H68A
P3E_CPU0_PE2_SS_RXP<8>   U5D1             BV9      SKX_EXT_B_BGA1-IC,TBD
P3E_CPU0_PE2_SS_RXP<9>   J8G1             162      SCONN200_H68296001_SM-CONN,H68A
P3E_CPU0_PE2_SS_RXP<9>   U5D1             BW8      SKX_EXT_B_BGA1-IC,TBD
P3E_CPU0_PE2_SS_RXP<10>  J8G1             168      SCONN200_H68296001_SM-CONN,H68A
P3E_CPU0_PE2_SS_RXP<10>  U5D1             BU6      SKX_EXT_B_BGA1-IC,TBD
P3E_CPU0_PE2_SS_RXP<11>  J8G1             174      SCONN200_H68296001_SM-CONN,H68A
P3E_CPU0_PE2_SS_RXP<11>  U5D1             BP7      SKX_EXT_B_BGA1-IC,TBD
P3E_CPU0_PE2_SS_RXP<12>  J8G1             180      SCONN200_H68296001_SM-CONN,H68A
P3E_CPU0_PE2_SS_RXP<12>  U5D1             BP9      SKX_EXT_B_BGA1-IC,TBD
P3E_CPU0_PE2_SS_RXP<13>  J8G1             184      SCONN200_H68296001_SM-CONN,H68A
P3E_CPU0_PE2_SS_RXP<13>  U5D1             BM7      SKX_EXT_B_BGA1-IC,TBD
P3E_CPU0_PE2_SS_RXP<14>  J8G1             192      SCONN200_H68296001_SM-CONN,H68A
P3E_CPU0_PE2_SS_RXP<14>  U5D1             BJ8      SKX_EXT_B_BGA1-IC,TBD
P3E_CPU0_PE2_SS_RXP<15>  J8G1             198      SCONN200_H68296001_SM-CONN,H68A
P3E_CPU0_PE2_SS_RXP<15>  U5D1             BJ10     SKX_EXT_B_BGA1-IC,TBD
P3E_CPU0_PE2_SS_TXN<0>   C8G10            1        CAP_0402-0.22UF,16V,10%,X7R,A3A
P3E_CPU0_PE2_SS_TXN<0>   U5D1             CY3      SKX_EXT_B_BGA1-IC,TBD
P3E_CPU0_PE2_SS_TXN<1>   C8G7             1        CAP_0402-0.22UF,16V,10%,X7R,A3A
P3E_CPU0_PE2_SS_TXN<1>   U5D1             CV3      SKX_EXT_B_BGA1-IC,TBD
P3E_CPU0_PE2_SS_TXN<2>   C8G6             1        CAP_0402-0.22UF,16V,10%,X7R,A3A
P3E_CPU0_PE2_SS_TXN<2>   U5D1             CT1      SKX_EXT_B_BGA1-IC,TBD
P3E_CPU0_PE2_SS_TXN<3>   C8G4             1        CAP_0402-0.22UF,16V,10%,X7R,A3A
P3E_CPU0_PE2_SS_TXN<3>   U5D1             CT3      SKX_EXT_B_BGA1-IC,TBD
P3E_CPU0_PE2_SS_TXN<4>   C8G2             1        CAP_0402-0.22UF,16V,10%,X7R,A3A
P3E_CPU0_PE2_SS_TXN<4>   U5D1             CM1      SKX_EXT_B_BGA1-IC,TBD
P3E_CPU0_PE2_SS_TXN<5>   C7G26            1        CAP_0402-0.22UF,16V,10%,X7R,A3A
P3E_CPU0_PE2_SS_TXN<5>   U5D1             CL2      SKX_EXT_B_BGA1-IC,TBD
P3E_CPU0_PE2_SS_TXN<6>   C7G24            1        CAP_0402-0.22UF,16V,10%,X7R,A3A
P3E_CPU0_PE2_SS_TXN<6>   U5D1             CG2      SKX_EXT_B_BGA1-IC,TBD
P3E_CPU0_PE2_SS_TXN<7>   C7G22            1        CAP_0402-0.22UF,16V,10%,X7R,A3A
P3E_CPU0_PE2_SS_TXN<7>   U5D1             CF3      SKX_EXT_B_BGA1-IC,TBD
P3E_CPU0_PE2_SS_TXN<8>   C7G20            1        CAP_0402-0.22UF,16V,10%,X7R,A3A
P3E_CPU0_PE2_SS_TXN<8>   U5D1             CC2      SKX_EXT_B_BGA1-IC,TBD
P3E_CPU0_PE2_SS_TXN<9>   C7G18            1        CAP_0402-0.22UF,16V,10%,X7R,A3A
P3E_CPU0_PE2_SS_TXN<9>   U5D1             CB3      SKX_EXT_B_BGA1-IC,TBD
P3E_CPU0_PE2_SS_TXN<10>  C7G16            1        CAP_0402-0.22UF,16V,10%,X7R,A3A
P3E_CPU0_PE2_SS_TXN<10>  U5D1             CA4      SKX_EXT_B_BGA1-IC,TBD
P3E_CPU0_PE2_SS_TXN<11>  C7G13            1        CAP_0402-0.22UF,16V,10%,X7R,A3A
P3E_CPU0_PE2_SS_TXN<11>  U5D1             BW4      SKX_EXT_B_BGA1-IC,TBD
P3E_CPU0_PE2_SS_TXN<12>  C7G12            1        CAP_0402-0.22UF,16V,10%,X7R,A3A
P3E_CPU0_PE2_SS_TXN<12>  U5D1             BU4      SKX_EXT_B_BGA1-IC,TBD
P3E_CPU0_PE2_SS_TXN<13>  C7G10            1        CAP_0402-0.22UF,16V,10%,X7R,A3A
P3E_CPU0_PE2_SS_TXN<13>  U5D1             BP5      SKX_EXT_B_BGA1-IC,TBD
P3E_CPU0_PE2_SS_TXN<14>  C7G7             1        CAP_0402-0.22UF,16V,10%,X7R,A3A
P3E_CPU0_PE2_SS_TXN<14>  U5D1             BL4      SKX_EXT_B_BGA1-IC,TBD
P3E_CPU0_PE2_SS_TXN<15>  C7G6             1        CAP_0402-0.22UF,16V,10%,X7R,A3A
P3E_CPU0_PE2_SS_TXN<15>  U5D1             BM5      SKX_EXT_B_BGA1-IC,TBD
P3E_CPU0_PE2_SS_TXP<0>   C8G9             1        CAP_0402-0.22UF,16V,10%,X7R,A3A
P3E_CPU0_PE2_SS_TXP<0>   U5D1             CW4      SKX_EXT_B_BGA1-IC,TBD
P3E_CPU0_PE2_SS_TXP<1>   C8G8             1        CAP_0402-0.22UF,16V,10%,X7R,A3A
P3E_CPU0_PE2_SS_TXP<1>   U5D1             CU2      SKX_EXT_B_BGA1-IC,TBD
P3E_CPU0_PE2_SS_TXP<2>   C8G5             1        CAP_0402-0.22UF,16V,10%,X7R,A3A
P3E_CPU0_PE2_SS_TXP<2>   U5D1             CR2      SKX_EXT_B_BGA1-IC,TBD
P3E_CPU0_PE2_SS_TXP<3>   C8G3             1        CAP_0402-0.22UF,16V,10%,X7R,A3A
P3E_CPU0_PE2_SS_TXP<3>   U5D1             CP3      SKX_EXT_B_BGA1-IC,TBD
P3E_CPU0_PE2_SS_TXP<4>   C8G1             1        CAP_0402-0.22UF,16V,10%,X7R,A3A
P3E_CPU0_PE2_SS_TXP<4>   U5D1             CK1      SKX_EXT_B_BGA1-IC,TBD
P3E_CPU0_PE2_SS_TXP<5>   C7G25            1        CAP_0402-0.22UF,16V,10%,X7R,A3A
P3E_CPU0_PE2_SS_TXP<5>   U5D1             CK3      SKX_EXT_B_BGA1-IC,TBD
P3E_CPU0_PE2_SS_TXP<6>   C7G23            1        CAP_0402-0.22UF,16V,10%,X7R,A3A
P3E_CPU0_PE2_SS_TXP<6>   U5D1             CE2      SKX_EXT_B_BGA1-IC,TBD
P3E_CPU0_PE2_SS_TXP<7>   C7G21            1        CAP_0402-0.22UF,16V,10%,X7R,A3A
P3E_CPU0_PE2_SS_TXP<7>   U5D1             CE4      SKX_EXT_B_BGA1-IC,TBD
P3E_CPU0_PE2_SS_TXP<8>   C7G19            1        CAP_0402-0.22UF,16V,10%,X7R,A3A
P3E_CPU0_PE2_SS_TXP<8>   U5D1             CD3      SKX_EXT_B_BGA1-IC,TBD
P3E_CPU0_PE2_SS_TXP<9>   C7G17            1        CAP_0402-0.22UF,16V,10%,X7R,A3A
P3E_CPU0_PE2_SS_TXP<9>   U5D1             BY3      SKX_EXT_B_BGA1-IC,TBD
P3E_CPU0_PE2_SS_TXP<10>  C7G15            1        CAP_0402-0.22UF,16V,10%,X7R,A3A
P3E_CPU0_PE2_SS_TXP<10>  U5D1             BY5      SKX_EXT_B_BGA1-IC,TBD
P3E_CPU0_PE2_SS_TXP<11>  C7G14            1        CAP_0402-0.22UF,16V,10%,X7R,A3A
P3E_CPU0_PE2_SS_TXP<11>  U5D1             BV3      SKX_EXT_B_BGA1-IC,TBD
P3E_CPU0_PE2_SS_TXP<12>  C7G11            1        CAP_0402-0.22UF,16V,10%,X7R,A3A
P3E_CPU0_PE2_SS_TXP<12>  U5D1             BR4      SKX_EXT_B_BGA1-IC,TBD
P3E_CPU0_PE2_SS_TXP<13>  C7G9             1        CAP_0402-0.22UF,16V,10%,X7R,A3A
P3E_CPU0_PE2_SS_TXP<13>  U5D1             BN4      SKX_EXT_B_BGA1-IC,TBD
P3E_CPU0_PE2_SS_TXP<14>  C7G8             1        CAP_0402-0.22UF,16V,10%,X7R,A3A
P3E_CPU0_PE2_SS_TXP<14>  U5D1             BM3      SKX_EXT_B_BGA1-IC,TBD
P3E_CPU0_PE2_SS_TXP<15>  C7G5             1        CAP_0402-0.22UF,16V,10%,X7R,A3A
P3E_CPU0_PE2_SS_TXP<15>  U5D1             BK5      SKX_EXT_B_BGA1-IC,TBD
P3E_CPU0_PE3_OCP_RXN<0>  J8E3             63       SCONN80_E67482007_SM-CONN,E674A
P3E_CPU0_PE3_OCP_RXN<0>  U5D1             EA18     SKX_EXT_B_BGA1-IC,TBD
P3E_CPU0_PE3_OCP_RXN<1>  J8E3             55       SCONN80_E67482007_SM-CONN,E674A
P3E_CPU0_PE3_OCP_RXN<1>  U5D1             DW18     SKX_EXT_B_BGA1-IC,TBD
P3E_CPU0_PE3_OCP_RXN<2>  J8E3             47       SCONN80_E67482007_SM-CONN,E674A
P3E_CPU0_PE3_OCP_RXN<2>  U5D1             DW16     SKX_EXT_B_BGA1-IC,TBD
P3E_CPU0_PE3_OCP_RXN<3>  J8E3             39       SCONN80_E67482007_SM-CONN,E674A
P3E_CPU0_PE3_OCP_RXN<3>  U5D1             DT19     SKX_EXT_B_BGA1-IC,TBD
P3E_CPU0_PE3_OCP_RXN<4>  J8E3             29       SCONN80_E67482007_SM-CONN,E674A
P3E_CPU0_PE3_OCP_RXN<4>  U5D1             DR16     SKX_EXT_B_BGA1-IC,TBD
P3E_CPU0_PE3_OCP_RXN<5>  J8E3             21       SCONN80_E67482007_SM-CONN,E674A
P3E_CPU0_PE3_OCP_RXN<5>  U5D1             DR14     SKX_EXT_B_BGA1-IC,TBD
P3E_CPU0_PE3_OCP_RXN<6>  J8E3             13       SCONN80_E67482007_SM-CONN,E674A
P3E_CPU0_PE3_OCP_RXN<6>  U5D1             DN14     SKX_EXT_B_BGA1-IC,TBD
P3E_CPU0_PE3_OCP_RXN<7>  J8E3             7        SCONN80_E67482007_SM-CONN,E674A
P3E_CPU0_PE3_OCP_RXN<7>  U5D1             DL14     SKX_EXT_B_BGA1-IC,TBD
P3E_CPU0_PE3_OCP_RXN<8>  J9B3             117      SCONN120_A28699018_SM-SCONN,A2A
P3E_CPU0_PE3_OCP_RXN<8>  U5D1             DL12     SKX_EXT_B_BGA1-IC,TBD
P3E_CPU0_PE3_OCP_RXN<9>  J9B3             109      SCONN120_A28699018_SM-SCONN,A2A
P3E_CPU0_PE3_OCP_RXN<9>  U5D1             DJ12     SKX_EXT_B_BGA1-IC,TBD
P3E_CPU0_PE3_OCP_RXN<10> J9B3             101      SCONN120_A28699018_SM-SCONN,A2A
P3E_CPU0_PE3_OCP_RXN<10> U5D1             DG12     SKX_EXT_B_BGA1-IC,TBD
P3E_CPU0_PE3_OCP_RXN<11> J9B3             93       SCONN120_A28699018_SM-SCONN,A2A
P3E_CPU0_PE3_OCP_RXN<11> U5D1             DG10     SKX_EXT_B_BGA1-IC,TBD
P3E_CPU0_PE3_OCP_RXN<12> J9B3             85       SCONN120_A28699018_SM-SCONN,A2A
P3E_CPU0_PE3_OCP_RXN<12> U5D1             DD13     SKX_EXT_B_BGA1-IC,TBD
P3E_CPU0_PE3_OCP_RXN<13> J9B3             77       SCONN120_A28699018_SM-SCONN,A2A
P3E_CPU0_PE3_OCP_RXN<13> U5D1             DB11     SKX_EXT_B_BGA1-IC,TBD
P3E_CPU0_PE3_OCP_RXN<14> J9B3             69       SCONN120_A28699018_SM-SCONN,A2A
P3E_CPU0_PE3_OCP_RXN<14> U5D1             CY11     SKX_EXT_B_BGA1-IC,TBD
P3E_CPU0_PE3_OCP_RXN<15> J9B3             61       SCONN120_A28699018_SM-SCONN,A2A
P3E_CPU0_PE3_OCP_RXN<15> U5D1             CV9      SKX_EXT_B_BGA1-IC,TBD
P3E_CPU0_PE3_OCP_RXP<0>  J8E3             61       SCONN80_E67482007_SM-CONN,E674A
P3E_CPU0_PE3_OCP_RXP<0>  U5D1             DY17     SKX_EXT_B_BGA1-IC,TBD
P3E_CPU0_PE3_OCP_RXP<1>  J8E3             53       SCONN80_E67482007_SM-CONN,E674A
P3E_CPU0_PE3_OCP_RXP<1>  U5D1             DU18     SKX_EXT_B_BGA1-IC,TBD
P3E_CPU0_PE3_OCP_RXP<2>  J8E3             45       SCONN80_E67482007_SM-CONN,E674A
P3E_CPU0_PE3_OCP_RXP<2>  U5D1             DV17     SKX_EXT_B_BGA1-IC,TBD
P3E_CPU0_PE3_OCP_RXP<3>  J8E3             37       SCONN80_E67482007_SM-CONN,E674A
P3E_CPU0_PE3_OCP_RXP<3>  U5D1             DR18     SKX_EXT_B_BGA1-IC,TBD
P3E_CPU0_PE3_OCP_RXP<4>  J8E3             31       SCONN80_E67482007_SM-CONN,E674A
P3E_CPU0_PE3_OCP_RXP<4>  U5D1             DN16     SKX_EXT_B_BGA1-IC,TBD
P3E_CPU0_PE3_OCP_RXP<5>  J8E3             23       SCONN80_E67482007_SM-CONN,E674A
P3E_CPU0_PE3_OCP_RXP<5>  U5D1             DP15     SKX_EXT_B_BGA1-IC,TBD
P3E_CPU0_PE3_OCP_RXP<6>  J8E3             15       SCONN80_E67482007_SM-CONN,E674A
P3E_CPU0_PE3_OCP_RXP<6>  U5D1             DM13     SKX_EXT_B_BGA1-IC,TBD
P3E_CPU0_PE3_OCP_RXP<7>  J8E3             5        SCONN80_E67482007_SM-CONN,E674A
P3E_CPU0_PE3_OCP_RXP<7>  U5D1             DJ14     SKX_EXT_B_BGA1-IC,TBD
P3E_CPU0_PE3_OCP_RXP<8>  J9B3             115      SCONN120_A28699018_SM-SCONN,A2A
P3E_CPU0_PE3_OCP_RXP<8>  U5D1             DK13     SKX_EXT_B_BGA1-IC,TBD
P3E_CPU0_PE3_OCP_RXP<9>  J9B3             107      SCONN120_A28699018_SM-SCONN,A2A
P3E_CPU0_PE3_OCP_RXP<9>  U5D1             DH11     SKX_EXT_B_BGA1-IC,TBD
P3E_CPU0_PE3_OCP_RXP<10> J9B3             99       SCONN120_A28699018_SM-SCONN,A2A
P3E_CPU0_PE3_OCP_RXP<10> U5D1             DE12     SKX_EXT_B_BGA1-IC,TBD
P3E_CPU0_PE3_OCP_RXP<11> J9B3             91       SCONN120_A28699018_SM-SCONN,A2A
P3E_CPU0_PE3_OCP_RXP<11> U5D1             DF11     SKX_EXT_B_BGA1-IC,TBD
P3E_CPU0_PE3_OCP_RXP<12> J9B3             83       SCONN120_A28699018_SM-SCONN,A2A
P3E_CPU0_PE3_OCP_RXP<12> U5D1             DC12     SKX_EXT_B_BGA1-IC,TBD
P3E_CPU0_PE3_OCP_RXP<13> J9B3             75       SCONN120_A28699018_SM-SCONN,A2A
P3E_CPU0_PE3_OCP_RXP<13> U5D1             DA12     SKX_EXT_B_BGA1-IC,TBD
P3E_CPU0_PE3_OCP_RXP<14> J9B3             67       SCONN120_A28699018_SM-SCONN,A2A
P3E_CPU0_PE3_OCP_RXP<14> U5D1             CW10     SKX_EXT_B_BGA1-IC,TBD
P3E_CPU0_PE3_OCP_RXP<15> J9B3             59       SCONN120_A28699018_SM-SCONN,A2A
P3E_CPU0_PE3_OCP_RXP<15> U5D1             CU10     SKX_EXT_B_BGA1-IC,TBD
P3E_CPU0_PE3_OCP_TXN<0>  C1R1             1        CAP_0402-0.22UF,16V,10%,X7R,A3A
P3E_CPU0_PE3_OCP_TXN<0>  U5D1             EE14     SKX_EXT_B_BGA1-IC,TBD
P3E_CPU0_PE3_OCP_TXN<1>  C1R3             1        CAP_0402-0.22UF,16V,10%,X7R,A3A
P3E_CPU0_PE3_OCP_TXN<1>  U5D1             EE12     SKX_EXT_B_BGA1-IC,TBD
P3E_CPU0_PE3_OCP_TXN<2>  C1R5             1        CAP_0402-0.22UF,16V,10%,X7R,A3A
P3E_CPU0_PE3_OCP_TXN<2>  U5D1             EC12     SKX_EXT_B_BGA1-IC,TBD
P3E_CPU0_PE3_OCP_TXN<3>  C1R7             1        CAP_0402-0.22UF,16V,10%,X7R,A3A
P3E_CPU0_PE3_OCP_TXN<3>  U5D1             DY11     SKX_EXT_B_BGA1-IC,TBD
P3E_CPU0_PE3_OCP_TXN<4>  C1R9             1        CAP_0402-0.22UF,16V,10%,X7R,A3A
P3E_CPU0_PE3_OCP_TXN<4>  U5D1             EB9      SKX_EXT_B_BGA1-IC,TBD
P3E_CPU0_PE3_OCP_TXN<5>  C2R13            1        CAP_0402-0.22UF,16V,10%,X7R,A3A
P3E_CPU0_PE3_OCP_TXN<5>  U5D1             DW10     SKX_EXT_B_BGA1-IC,TBD
P3E_CPU0_PE3_OCP_TXN<6>  C2R7             1        CAP_0402-0.22UF,16V,10%,X7R,A3A
P3E_CPU0_PE3_OCP_TXN<6>  U5D1             DU8      SKX_EXT_B_BGA1-IC,TBD
P3E_CPU0_PE3_OCP_TXN<7>  C2R9             1        CAP_0402-0.22UF,16V,10%,X7R,A3A
P3E_CPU0_PE3_OCP_TXN<7>  U5D1             DR8      SKX_EXT_B_BGA1-IC,TBD
P3E_CPU0_PE3_OCP_TXN<8>  C2M15            1        CAP_0402-0.22UF,16V,10%,X7R,A3A
P3E_CPU0_PE3_OCP_TXN<8>  U5D1             DM7      SKX_EXT_B_BGA1-IC,TBD
P3E_CPU0_PE3_OCP_TXN<9>  C1M19            1        CAP_0402-0.22UF,16V,10%,X7R,A3A
P3E_CPU0_PE3_OCP_TXN<9>  U5D1             DP5      SKX_EXT_B_BGA1-IC,TBD
P3E_CPU0_PE3_OCP_TXN<10> C1M17            1        CAP_0402-0.22UF,16V,10%,X7R,A3A
P3E_CPU0_PE3_OCP_TXN<10> U5D1             DL6      SKX_EXT_B_BGA1-IC,TBD
P3E_CPU0_PE3_OCP_TXN<11> C1M15            1        CAP_0402-0.22UF,16V,10%,X7R,A3A
P3E_CPU0_PE3_OCP_TXN<11> U5D1             DJ4      SKX_EXT_B_BGA1-IC,TBD
P3E_CPU0_PE3_OCP_TXN<12> C1M13            1        CAP_0402-0.22UF,16V,10%,X7R,A3A
P3E_CPU0_PE3_OCP_TXN<12> U5D1             DJ6      SKX_EXT_B_BGA1-IC,TBD
P3E_CPU0_PE3_OCP_TXN<13> C1M11            1        CAP_0402-0.22UF,16V,10%,X7R,A3A
P3E_CPU0_PE3_OCP_TXN<13> U5D1             DD5      SKX_EXT_B_BGA1-IC,TBD
P3E_CPU0_PE3_OCP_TXN<14> C1M9             1        CAP_0402-0.22UF,16V,10%,X7R,A3A
P3E_CPU0_PE3_OCP_TXN<14> U5D1             DB5      SKX_EXT_B_BGA1-IC,TBD
P3E_CPU0_PE3_OCP_TXN<15> C1M7             1        CAP_0402-0.22UF,16V,10%,X7R,A3A
P3E_CPU0_PE3_OCP_TXN<15> U5D1             CY5      SKX_EXT_B_BGA1-IC,TBD
P3E_CPU0_PE3_OCP_TXP<0>  C1R2             1        CAP_0402-0.22UF,16V,10%,X7R,A3A
P3E_CPU0_PE3_OCP_TXP<0>  U5D1             EC14     SKX_EXT_B_BGA1-IC,TBD
P3E_CPU0_PE3_OCP_TXP<1>  C1R4             1        CAP_0402-0.22UF,16V,10%,X7R,A3A
P3E_CPU0_PE3_OCP_TXP<1>  U5D1             ED13     SKX_EXT_B_BGA1-IC,TBD
P3E_CPU0_PE3_OCP_TXP<2>  C1R6             1        CAP_0402-0.22UF,16V,10%,X7R,A3A
P3E_CPU0_PE3_OCP_TXP<2>  U5D1             EB11     SKX_EXT_B_BGA1-IC,TBD
P3E_CPU0_PE3_OCP_TXP<3>  C1R8             1        CAP_0402-0.22UF,16V,10%,X7R,A3A
P3E_CPU0_PE3_OCP_TXP<3>  U5D1             EA10     SKX_EXT_B_BGA1-IC,TBD
P3E_CPU0_PE3_OCP_TXP<4>  C1R10            1        CAP_0402-0.22UF,16V,10%,X7R,A3A
P3E_CPU0_PE3_OCP_TXP<4>  U5D1             DY9      SKX_EXT_B_BGA1-IC,TBD
P3E_CPU0_PE3_OCP_TXP<5>  C2R14            1        CAP_0402-0.22UF,16V,10%,X7R,A3A
P3E_CPU0_PE3_OCP_TXP<5>  U5D1             DV9      SKX_EXT_B_BGA1-IC,TBD
P3E_CPU0_PE3_OCP_TXP<6>  C2R8             1        CAP_0402-0.22UF,16V,10%,X7R,A3A
P3E_CPU0_PE3_OCP_TXP<6>  U5D1             DT9      SKX_EXT_B_BGA1-IC,TBD
P3E_CPU0_PE3_OCP_TXP<7>  C2R10            1        CAP_0402-0.22UF,16V,10%,X7R,A3A
P3E_CPU0_PE3_OCP_TXP<7>  U5D1             DP7      SKX_EXT_B_BGA1-IC,TBD
P3E_CPU0_PE3_OCP_TXP<8>  C2M14            1        CAP_0402-0.22UF,16V,10%,X7R,A3A
P3E_CPU0_PE3_OCP_TXP<8>  U5D1             DN6      SKX_EXT_B_BGA1-IC,TBD
P3E_CPU0_PE3_OCP_TXP<9>  C1M18            1        CAP_0402-0.22UF,16V,10%,X7R,A3A
P3E_CPU0_PE3_OCP_TXP<9>  U5D1             DM5      SKX_EXT_B_BGA1-IC,TBD
P3E_CPU0_PE3_OCP_TXP<10> C1M16            1        CAP_0402-0.22UF,16V,10%,X7R,A3A
P3E_CPU0_PE3_OCP_TXP<10> U5D1             DK5      SKX_EXT_B_BGA1-IC,TBD
P3E_CPU0_PE3_OCP_TXP<11> C1M14            1        CAP_0402-0.22UF,16V,10%,X7R,A3A
P3E_CPU0_PE3_OCP_TXP<11> U5D1             DH5      SKX_EXT_B_BGA1-IC,TBD
P3E_CPU0_PE3_OCP_TXP<12> C1M12            1        CAP_0402-0.22UF,16V,10%,X7R,A3A
P3E_CPU0_PE3_OCP_TXP<12> U5D1             DG6      SKX_EXT_B_BGA1-IC,TBD
P3E_CPU0_PE3_OCP_TXP<13> C1M10            1        CAP_0402-0.22UF,16V,10%,X7R,A3A
P3E_CPU0_PE3_OCP_TXP<13> U5D1             DC6      SKX_EXT_B_BGA1-IC,TBD
P3E_CPU0_PE3_OCP_TXP<14> C1M8             1        CAP_0402-0.22UF,16V,10%,X7R,A3A
P3E_CPU0_PE3_OCP_TXP<14> U5D1             DA4      SKX_EXT_B_BGA1-IC,TBD
P3E_CPU0_PE3_OCP_TXP<15> C1M6             1        CAP_0402-0.22UF,16V,10%,X7R,A3A
P3E_CPU0_PE3_OCP_TXP<15> U5D1             CV5      SKX_EXT_B_BGA1-IC,TBD
P3E_CPU1_PE3_MP_C_TXN<0> C1F20            1        CAP_0402-0.22UF,16V,10%,X7R,A3A
P3E_CPU1_PE3_MP_C_TXN<0> J1F1             B8       CONN76_H22707001_THMT1-CONN,H2A
P3E_CPU1_PE3_MP_C_TXN<1> C1F16            1        CAP_0402-0.22UF,16V,10%,X7R,A3A
P3E_CPU1_PE3_MP_C_TXN<1> J1F1             E8       CONN76_H22707001_THMT1-CONN,H2A
P3E_CPU1_PE3_MP_C_TXN<2> C1F15            1        CAP_0402-0.22UF,16V,10%,X7R,A3A
P3E_CPU1_PE3_MP_C_TXN<2> J1F1             H8       CONN76_H22707001_THMT1-CONN,H2A
P3E_CPU1_PE3_MP_C_TXN<3> C1F13            1        CAP_0402-0.22UF,16V,10%,X7R,A3A
P3E_CPU1_PE3_MP_C_TXN<3> J1F1             A7       CONN76_H22707001_THMT1-CONN,H2A
P3E_CPU1_PE3_MP_C_TXN<4> C1F10            1        CAP_0402-0.22UF,16V,10%,X7R,A3A
P3E_CPU1_PE3_MP_C_TXN<4> J1F1             D7       CONN76_H22707001_THMT1-CONN,H2A
P3E_CPU1_PE3_MP_C_TXN<5> C1F8             1        CAP_0402-0.22UF,16V,10%,X7R,A3A
P3E_CPU1_PE3_MP_C_TXN<5> J1F1             H7       CONN76_H22707001_THMT1-CONN,H2A
P3E_CPU1_PE3_MP_C_TXN<6> C1F4             1        CAP_0402-0.22UF,16V,10%,X7R,A3A
P3E_CPU1_PE3_MP_C_TXN<6> J1F1             E6       CONN76_H22707001_THMT1-CONN,H2A
P3E_CPU1_PE3_MP_C_TXN<7> C1F3             1        CAP_0402-0.22UF,16V,10%,X7R,A3A
P3E_CPU1_PE3_MP_C_TXN<7> J1F1             I6       CONN76_H22707001_THMT1-CONN,H2A
P3E_CPU1_PE3_MP_C_TXN<8> C9N18            1        CAP_0402-0.22UF,16V,10%,X7R,A3A
P3E_CPU1_PE3_MP_C_TXN<8> J1C1             B8       CONN76_H22707001_THMT1-CONN,H2A
P3E_CPU1_PE3_MP_C_TXN<9> C9N15            1        CAP_0402-0.22UF,16V,10%,X7R,A3A
P3E_CPU1_PE3_MP_C_TXN<9> J1C1             E8       CONN76_H22707001_THMT1-CONN,H2A
P3E_CPU1_PE3_MP_C_TXN<10> C9N2             1        CAP_0402-0.22UF,16V,10%,X7R,A3A
P3E_CPU1_PE3_MP_C_TXN<10> J1C1             I8       CONN76_H22707001_THMT1-CONN,H2A
P3E_CPU1_PE3_MP_C_TXN<11> C9N3             1        CAP_0402-0.22UF,16V,10%,X7R,A3A
P3E_CPU1_PE3_MP_C_TXN<11> J1C1             A7       CONN76_H22707001_THMT1-CONN,H2A
P3E_CPU1_PE3_MP_C_TXN<12> C9N16            1        CAP_0402-0.22UF,16V,10%,X7R,A3A
P3E_CPU1_PE3_MP_C_TXN<12> J1C1             D7       CONN76_H22707001_THMT1-CONN,H2A
P3E_CPU1_PE3_MP_C_TXN<13> C9N6             1        CAP_0402-0.22UF,16V,10%,X7R,A3A
P3E_CPU1_PE3_MP_C_TXN<13> J1C1             G7       CONN76_H22707001_THMT1-CONN,H2A
P3E_CPU1_PE3_MP_C_TXN<14> C9N8             1        CAP_0402-0.22UF,16V,10%,X7R,A3A
P3E_CPU1_PE3_MP_C_TXN<14> J1C1             E6       CONN76_H22707001_THMT1-CONN,H2A
P3E_CPU1_PE3_MP_C_TXN<15> C9N9             1        CAP_0402-0.22UF,16V,10%,X7R,A3A
P3E_CPU1_PE3_MP_C_TXN<15> J1C1             H6       CONN76_H22707001_THMT1-CONN,H2A
P3E_CPU1_PE3_MP_C_TXP<0> C1F18            1        CAP_0402-0.22UF,16V,10%,X7R,A3A
P3E_CPU1_PE3_MP_C_TXP<0> J1F1             C8       CONN76_H22707001_THMT1-CONN,H2A
P3E_CPU1_PE3_MP_C_TXP<1> C1F17            1        CAP_0402-0.22UF,16V,10%,X7R,A3A
P3E_CPU1_PE3_MP_C_TXP<1> J1F1             F8       CONN76_H22707001_THMT1-CONN,H2A
P3E_CPU1_PE3_MP_C_TXP<2> C1F14            1        CAP_0402-0.22UF,16V,10%,X7R,A3A
P3E_CPU1_PE3_MP_C_TXP<2> J1F1             I8       CONN76_H22707001_THMT1-CONN,H2A
P3E_CPU1_PE3_MP_C_TXP<3> C1F12            1        CAP_0402-0.22UF,16V,10%,X7R,A3A
P3E_CPU1_PE3_MP_C_TXP<3> J1F1             B7       CONN76_H22707001_THMT1-CONN,H2A
P3E_CPU1_PE3_MP_C_TXP<4> C1F11            1        CAP_0402-0.22UF,16V,10%,X7R,A3A
P3E_CPU1_PE3_MP_C_TXP<4> J1F1             E7       CONN76_H22707001_THMT1-CONN,H2A
P3E_CPU1_PE3_MP_C_TXP<5> C1F6             1        CAP_0402-0.22UF,16V,10%,X7R,A3A
P3E_CPU1_PE3_MP_C_TXP<5> J1F1             G7       CONN76_H22707001_THMT1-CONN,H2A
P3E_CPU1_PE3_MP_C_TXP<6> C1F5             1        CAP_0402-0.22UF,16V,10%,X7R,A3A
P3E_CPU1_PE3_MP_C_TXP<6> J1F1             F6       CONN76_H22707001_THMT1-CONN,H2A
P3E_CPU1_PE3_MP_C_TXP<7> C1F2             1        CAP_0402-0.22UF,16V,10%,X7R,A3A
P3E_CPU1_PE3_MP_C_TXP<7> J1F1             H6       CONN76_H22707001_THMT1-CONN,H2A
P3E_CPU1_PE3_MP_C_TXP<8> C9N17            1        CAP_0402-0.22UF,16V,10%,X7R,A3A
P3E_CPU1_PE3_MP_C_TXP<8> J1C1             C8       CONN76_H22707001_THMT1-CONN,H2A
P3E_CPU1_PE3_MP_C_TXP<9> C9N12            1        CAP_0402-0.22UF,16V,10%,X7R,A3A
P3E_CPU1_PE3_MP_C_TXP<9> J1C1             F8       CONN76_H22707001_THMT1-CONN,H2A
P3E_CPU1_PE3_MP_C_TXP<10> C9N1             1        CAP_0402-0.22UF,16V,10%,X7R,A3A
P3E_CPU1_PE3_MP_C_TXP<10> J1C1             H8       CONN76_H22707001_THMT1-CONN,H2A
P3E_CPU1_PE3_MP_C_TXP<11> C9N4             1        CAP_0402-0.22UF,16V,10%,X7R,A3A
P3E_CPU1_PE3_MP_C_TXP<11> J1C1             B7       CONN76_H22707001_THMT1-CONN,H2A
P3E_CPU1_PE3_MP_C_TXP<12> C9N14            1        CAP_0402-0.22UF,16V,10%,X7R,A3A
P3E_CPU1_PE3_MP_C_TXP<12> J1C1             E7       CONN76_H22707001_THMT1-CONN,H2A
P3E_CPU1_PE3_MP_C_TXP<13> C9N5             1        CAP_0402-0.22UF,16V,10%,X7R,A3A
P3E_CPU1_PE3_MP_C_TXP<13> J1C1             H7       CONN76_H22707001_THMT1-CONN,H2A
P3E_CPU1_PE3_MP_C_TXP<14> C9N10            1        CAP_0402-0.22UF,16V,10%,X7R,A3A
P3E_CPU1_PE3_MP_C_TXP<14> J1C1             F6       CONN76_H22707001_THMT1-CONN,H2A
P3E_CPU1_PE3_MP_C_TXP<15> C9N7             1        CAP_0402-0.22UF,16V,10%,X7R,A3A
P3E_CPU1_PE3_MP_C_TXP<15> J1C1             I6       CONN76_H22707001_THMT1-CONN,H2A
P3E_CPU1_PE3_MP_RXN<0>   J1F1             A1       CONN76_H22707001_THMT1-CONN,H2A
P3E_CPU1_PE3_MP_RXN<0>   U2D1             EA18     SKX_EXT_B_BGA1-IC,TBD
P3E_CPU1_PE3_MP_RXN<1>   J1F1             D1       CONN76_H22707001_THMT1-CONN,H2A
P3E_CPU1_PE3_MP_RXN<1>   U2D1             DW18     SKX_EXT_B_BGA1-IC,TBD
P3E_CPU1_PE3_MP_RXN<2>   J1F1             H1       CONN76_H22707001_THMT1-CONN,H2A
P3E_CPU1_PE3_MP_RXN<2>   U2D1             DW16     SKX_EXT_B_BGA1-IC,TBD
P3E_CPU1_PE3_MP_RXN<3>   J1F1             B2       CONN76_H22707001_THMT1-CONN,H2A
P3E_CPU1_PE3_MP_RXN<3>   U2D1             DT19     SKX_EXT_B_BGA1-IC,TBD
P3E_CPU1_PE3_MP_RXN<4>   J1F1             E2       CONN76_H22707001_THMT1-CONN,H2A
P3E_CPU1_PE3_MP_RXN<4>   U2D1             DR16     SKX_EXT_B_BGA1-IC,TBD
P3E_CPU1_PE3_MP_RXN<5>   J1F1             I2       CONN76_H22707001_THMT1-CONN,H2A
P3E_CPU1_PE3_MP_RXN<5>   U2D1             DR14     SKX_EXT_B_BGA1-IC,TBD
P3E_CPU1_PE3_MP_RXN<6>   J1F1             B3       CONN76_H22707001_THMT1-CONN,H2A
P3E_CPU1_PE3_MP_RXN<6>   U2D1             DN14     SKX_EXT_B_BGA1-IC,TBD
P3E_CPU1_PE3_MP_RXN<7>   J1F1             D3       CONN76_H22707001_THMT1-CONN,H2A
P3E_CPU1_PE3_MP_RXN<7>   U2D1             DL14     SKX_EXT_B_BGA1-IC,TBD
P3E_CPU1_PE3_MP_RXN<8>   J1C1             A1       CONN76_H22707001_THMT1-CONN,H2A
P3E_CPU1_PE3_MP_RXN<8>   U2D1             DL12     SKX_EXT_B_BGA1-IC,TBD
P3E_CPU1_PE3_MP_RXN<9>   J1C1             D1       CONN76_H22707001_THMT1-CONN,H2A
P3E_CPU1_PE3_MP_RXN<9>   U2D1             DJ12     SKX_EXT_B_BGA1-IC,TBD
P3E_CPU1_PE3_MP_RXN<10>  J1C1             H1       CONN76_H22707001_THMT1-CONN,H2A
P3E_CPU1_PE3_MP_RXN<10>  U2D1             DG12     SKX_EXT_B_BGA1-IC,TBD
P3E_CPU1_PE3_MP_RXN<11>  J1C1             B2       CONN76_H22707001_THMT1-CONN,H2A
P3E_CPU1_PE3_MP_RXN<11>  U2D1             DG10     SKX_EXT_B_BGA1-IC,TBD
P3E_CPU1_PE3_MP_RXN<12>  J1C1             E2       CONN76_H22707001_THMT1-CONN,H2A
P3E_CPU1_PE3_MP_RXN<12>  U2D1             DC12     SKX_EXT_B_BGA1-IC,TBD
P3E_CPU1_PE3_MP_RXN<13>  J1C1             I2       CONN76_H22707001_THMT1-CONN,H2A
P3E_CPU1_PE3_MP_RXN<13>  U2D1             DB11     SKX_EXT_B_BGA1-IC,TBD
P3E_CPU1_PE3_MP_RXN<14>  J1C1             B3       CONN76_H22707001_THMT1-CONN,H2A
P3E_CPU1_PE3_MP_RXN<14>  U2D1             CY11     SKX_EXT_B_BGA1-IC,TBD
P3E_CPU1_PE3_MP_RXN<15>  J1C1             D3       CONN76_H22707001_THMT1-CONN,H2A
P3E_CPU1_PE3_MP_RXN<15>  U2D1             CV9      SKX_EXT_B_BGA1-IC,TBD
P3E_CPU1_PE3_MP_RXP<0>   J1F1             B1       CONN76_H22707001_THMT1-CONN,H2A
P3E_CPU1_PE3_MP_RXP<0>   U2D1             DY17     SKX_EXT_B_BGA1-IC,TBD
P3E_CPU1_PE3_MP_RXP<1>   J1F1             E1       CONN76_H22707001_THMT1-CONN,H2A
P3E_CPU1_PE3_MP_RXP<1>   U2D1             DU18     SKX_EXT_B_BGA1-IC,TBD
P3E_CPU1_PE3_MP_RXP<2>   J1F1             G1       CONN76_H22707001_THMT1-CONN,H2A
P3E_CPU1_PE3_MP_RXP<2>   U2D1             DV17     SKX_EXT_B_BGA1-IC,TBD
P3E_CPU1_PE3_MP_RXP<3>   J1F1             C2       CONN76_H22707001_THMT1-CONN,H2A
P3E_CPU1_PE3_MP_RXP<3>   U2D1             DR18     SKX_EXT_B_BGA1-IC,TBD
P3E_CPU1_PE3_MP_RXP<4>   J1F1             F2       CONN76_H22707001_THMT1-CONN,H2A
P3E_CPU1_PE3_MP_RXP<4>   U2D1             DN16     SKX_EXT_B_BGA1-IC,TBD
P3E_CPU1_PE3_MP_RXP<5>   J1F1             H2       CONN76_H22707001_THMT1-CONN,H2A
P3E_CPU1_PE3_MP_RXP<5>   U2D1             DP15     SKX_EXT_B_BGA1-IC,TBD
P3E_CPU1_PE3_MP_RXP<6>   J1F1             A3       CONN76_H22707001_THMT1-CONN,H2A
P3E_CPU1_PE3_MP_RXP<6>   U2D1             DM13     SKX_EXT_B_BGA1-IC,TBD
P3E_CPU1_PE3_MP_RXP<7>   J1F1             E3       CONN76_H22707001_THMT1-CONN,H2A
P3E_CPU1_PE3_MP_RXP<7>   U2D1             DJ14     SKX_EXT_B_BGA1-IC,TBD
P3E_CPU1_PE3_MP_RXP<8>   J1C1             B1       CONN76_H22707001_THMT1-CONN,H2A
P3E_CPU1_PE3_MP_RXP<8>   U2D1             DK13     SKX_EXT_B_BGA1-IC,TBD
P3E_CPU1_PE3_MP_RXP<9>   J1C1             E1       CONN76_H22707001_THMT1-CONN,H2A
P3E_CPU1_PE3_MP_RXP<9>   U2D1             DH11     SKX_EXT_B_BGA1-IC,TBD
P3E_CPU1_PE3_MP_RXP<10>  J1C1             G1       CONN76_H22707001_THMT1-CONN,H2A
P3E_CPU1_PE3_MP_RXP<10>  U2D1             DE12     SKX_EXT_B_BGA1-IC,TBD
P3E_CPU1_PE3_MP_RXP<11>  J1C1             C2       CONN76_H22707001_THMT1-CONN,H2A
P3E_CPU1_PE3_MP_RXP<11>  U2D1             DF11     SKX_EXT_B_BGA1-IC,TBD
P3E_CPU1_PE3_MP_RXP<12>  J1C1             F2       CONN76_H22707001_THMT1-CONN,H2A
P3E_CPU1_PE3_MP_RXP<12>  U2D1             DD13     SKX_EXT_B_BGA1-IC,TBD
P3E_CPU1_PE3_MP_RXP<13>  J1C1             H2       CONN76_H22707001_THMT1-CONN,H2A
P3E_CPU1_PE3_MP_RXP<13>  U2D1             DA12     SKX_EXT_B_BGA1-IC,TBD
P3E_CPU1_PE3_MP_RXP<14>  J1C1             A3       CONN76_H22707001_THMT1-CONN,H2A
P3E_CPU1_PE3_MP_RXP<14>  U2D1             CW10     SKX_EXT_B_BGA1-IC,TBD
P3E_CPU1_PE3_MP_RXP<15>  J1C1             E3       CONN76_H22707001_THMT1-CONN,H2A
P3E_CPU1_PE3_MP_RXP<15>  U2D1             CU10     SKX_EXT_B_BGA1-IC,TBD
P3E_CPU1_PE3_MP_TXN<0>   C1F20            2        CAP_0402-0.22UF,16V,10%,X7R,A3A
P3E_CPU1_PE3_MP_TXN<0>   U2D1             EE14     SKX_EXT_B_BGA1-IC,TBD
P3E_CPU1_PE3_MP_TXN<1>   C1F16            2        CAP_0402-0.22UF,16V,10%,X7R,A3A
P3E_CPU1_PE3_MP_TXN<1>   U2D1             EE12     SKX_EXT_B_BGA1-IC,TBD
P3E_CPU1_PE3_MP_TXN<2>   C1F15            2        CAP_0402-0.22UF,16V,10%,X7R,A3A
P3E_CPU1_PE3_MP_TXN<2>   U2D1             EC12     SKX_EXT_B_BGA1-IC,TBD
P3E_CPU1_PE3_MP_TXN<3>   C1F13            2        CAP_0402-0.22UF,16V,10%,X7R,A3A
P3E_CPU1_PE3_MP_TXN<3>   U2D1             DY11     SKX_EXT_B_BGA1-IC,TBD
P3E_CPU1_PE3_MP_TXN<4>   C1F10            2        CAP_0402-0.22UF,16V,10%,X7R,A3A
P3E_CPU1_PE3_MP_TXN<4>   U2D1             EB9      SKX_EXT_B_BGA1-IC,TBD
P3E_CPU1_PE3_MP_TXN<5>   C1F8             2        CAP_0402-0.22UF,16V,10%,X7R,A3A
P3E_CPU1_PE3_MP_TXN<5>   U2D1             DW10     SKX_EXT_B_BGA1-IC,TBD
P3E_CPU1_PE3_MP_TXN<6>   C1F4             2        CAP_0402-0.22UF,16V,10%,X7R,A3A
P3E_CPU1_PE3_MP_TXN<6>   U2D1             DU8      SKX_EXT_B_BGA1-IC,TBD
P3E_CPU1_PE3_MP_TXN<7>   C1F3             2        CAP_0402-0.22UF,16V,10%,X7R,A3A
P3E_CPU1_PE3_MP_TXN<7>   U2D1             DR8      SKX_EXT_B_BGA1-IC,TBD
P3E_CPU1_PE3_MP_TXN<8>   C9N18            2        CAP_0402-0.22UF,16V,10%,X7R,A3A
P3E_CPU1_PE3_MP_TXN<8>   U2D1             DM7      SKX_EXT_B_BGA1-IC,TBD
P3E_CPU1_PE3_MP_TXN<9>   C9N15            2        CAP_0402-0.22UF,16V,10%,X7R,A3A
P3E_CPU1_PE3_MP_TXN<9>   U2D1             DP5      SKX_EXT_B_BGA1-IC,TBD
P3E_CPU1_PE3_MP_TXN<10>  C9N2             2        CAP_0402-0.22UF,16V,10%,X7R,A3A
P3E_CPU1_PE3_MP_TXN<10>  U2D1             DL6      SKX_EXT_B_BGA1-IC,TBD
P3E_CPU1_PE3_MP_TXN<11>  C9N3             2        CAP_0402-0.22UF,16V,10%,X7R,A3A
P3E_CPU1_PE3_MP_TXN<11>  U2D1             DJ4      SKX_EXT_B_BGA1-IC,TBD
P3E_CPU1_PE3_MP_TXN<12>  C9N16            2        CAP_0402-0.22UF,16V,10%,X7R,A3A
P3E_CPU1_PE3_MP_TXN<12>  U2D1             DJ6      SKX_EXT_B_BGA1-IC,TBD
P3E_CPU1_PE3_MP_TXN<13>  C9N6             2        CAP_0402-0.22UF,16V,10%,X7R,A3A
P3E_CPU1_PE3_MP_TXN<13>  U2D1             DD5      SKX_EXT_B_BGA1-IC,TBD
P3E_CPU1_PE3_MP_TXN<14>  C9N8             2        CAP_0402-0.22UF,16V,10%,X7R,A3A
P3E_CPU1_PE3_MP_TXN<14>  U2D1             DB5      SKX_EXT_B_BGA1-IC,TBD
P3E_CPU1_PE3_MP_TXN<15>  C9N9             2        CAP_0402-0.22UF,16V,10%,X7R,A3A
P3E_CPU1_PE3_MP_TXN<15>  U2D1             CY5      SKX_EXT_B_BGA1-IC,TBD
P3E_CPU1_PE3_MP_TXP<0>   C1F18            2        CAP_0402-0.22UF,16V,10%,X7R,A3A
P3E_CPU1_PE3_MP_TXP<0>   U2D1             EC14     SKX_EXT_B_BGA1-IC,TBD
P3E_CPU1_PE3_MP_TXP<1>   C1F17            2        CAP_0402-0.22UF,16V,10%,X7R,A3A
P3E_CPU1_PE3_MP_TXP<1>   U2D1             ED13     SKX_EXT_B_BGA1-IC,TBD
P3E_CPU1_PE3_MP_TXP<2>   C1F14            2        CAP_0402-0.22UF,16V,10%,X7R,A3A
P3E_CPU1_PE3_MP_TXP<2>   U2D1             EB11     SKX_EXT_B_BGA1-IC,TBD
P3E_CPU1_PE3_MP_TXP<3>   C1F12            2        CAP_0402-0.22UF,16V,10%,X7R,A3A
P3E_CPU1_PE3_MP_TXP<3>   U2D1             EA10     SKX_EXT_B_BGA1-IC,TBD
P3E_CPU1_PE3_MP_TXP<4>   C1F11            2        CAP_0402-0.22UF,16V,10%,X7R,A3A
P3E_CPU1_PE3_MP_TXP<4>   U2D1             DY9      SKX_EXT_B_BGA1-IC,TBD
P3E_CPU1_PE3_MP_TXP<5>   C1F6             2        CAP_0402-0.22UF,16V,10%,X7R,A3A
P3E_CPU1_PE3_MP_TXP<5>   U2D1             DV9      SKX_EXT_B_BGA1-IC,TBD
P3E_CPU1_PE3_MP_TXP<6>   C1F5             2        CAP_0402-0.22UF,16V,10%,X7R,A3A
P3E_CPU1_PE3_MP_TXP<6>   U2D1             DT9      SKX_EXT_B_BGA1-IC,TBD
P3E_CPU1_PE3_MP_TXP<7>   C1F2             2        CAP_0402-0.22UF,16V,10%,X7R,A3A
P3E_CPU1_PE3_MP_TXP<7>   U2D1             DP7      SKX_EXT_B_BGA1-IC,TBD
P3E_CPU1_PE3_MP_TXP<8>   C9N17            2        CAP_0402-0.22UF,16V,10%,X7R,A3A
P3E_CPU1_PE3_MP_TXP<8>   U2D1             DN6      SKX_EXT_B_BGA1-IC,TBD
P3E_CPU1_PE3_MP_TXP<9>   C9N12            2        CAP_0402-0.22UF,16V,10%,X7R,A3A
P3E_CPU1_PE3_MP_TXP<9>   U2D1             DM5      SKX_EXT_B_BGA1-IC,TBD
P3E_CPU1_PE3_MP_TXP<10>  C9N1             2        CAP_0402-0.22UF,16V,10%,X7R,A3A
P3E_CPU1_PE3_MP_TXP<10>  U2D1             DK5      SKX_EXT_B_BGA1-IC,TBD
P3E_CPU1_PE3_MP_TXP<11>  C9N4             2        CAP_0402-0.22UF,16V,10%,X7R,A3A
P3E_CPU1_PE3_MP_TXP<11>  U2D1             DH5      SKX_EXT_B_BGA1-IC,TBD
P3E_CPU1_PE3_MP_TXP<12>  C9N14            2        CAP_0402-0.22UF,16V,10%,X7R,A3A
P3E_CPU1_PE3_MP_TXP<12>  U2D1             DG6      SKX_EXT_B_BGA1-IC,TBD
P3E_CPU1_PE3_MP_TXP<13>  C9N5             2        CAP_0402-0.22UF,16V,10%,X7R,A3A
P3E_CPU1_PE3_MP_TXP<13>  U2D1             DC6      SKX_EXT_B_BGA1-IC,TBD
P3E_CPU1_PE3_MP_TXP<14>  C9N10            2        CAP_0402-0.22UF,16V,10%,X7R,A3A
P3E_CPU1_PE3_MP_TXP<14>  U2D1             DA4      SKX_EXT_B_BGA1-IC,TBD
P3E_CPU1_PE3_MP_TXP<15>  C9N7             2        CAP_0402-0.22UF,16V,10%,X7R,A3A
P3E_CPU1_PE3_MP_TXP<15>  U2D1             CV5      SKX_EXT_B_BGA1-IC,TBD
P3E_OCP_CPU0_PE3_C_TXN<0> C1R1             2        CAP_0402-0.22UF,16V,10%,X7R,A3A
P3E_OCP_CPU0_PE3_C_TXN<0> J8E3             68       SCONN80_E67482007_SM-CONN,E674A
P3E_OCP_CPU0_PE3_C_TXN<1> C1R3             2        CAP_0402-0.22UF,16V,10%,X7R,A3A
P3E_OCP_CPU0_PE3_C_TXN<1> J8E3             60       SCONN80_E67482007_SM-CONN,E674A
P3E_OCP_CPU0_PE3_C_TXN<2> C1R5             2        CAP_0402-0.22UF,16V,10%,X7R,A3A
P3E_OCP_CPU0_PE3_C_TXN<2> J8E3             52       SCONN80_E67482007_SM-CONN,E674A
P3E_OCP_CPU0_PE3_C_TXN<3> C1R7             2        CAP_0402-0.22UF,16V,10%,X7R,A3A
P3E_OCP_CPU0_PE3_C_TXN<3> J8E3             44       SCONN80_E67482007_SM-CONN,E674A
P3E_OCP_CPU0_PE3_C_TXN<4> C1R9             2        CAP_0402-0.22UF,16V,10%,X7R,A3A
P3E_OCP_CPU0_PE3_C_TXN<4> J8E3             36       SCONN80_E67482007_SM-CONN,E674A
P3E_OCP_CPU0_PE3_C_TXN<5> C2R13            2        CAP_0402-0.22UF,16V,10%,X7R,A3A
P3E_OCP_CPU0_PE3_C_TXN<5> J8E3             28       SCONN80_E67482007_SM-CONN,E674A
P3E_OCP_CPU0_PE3_C_TXN<6> C2R7             2        CAP_0402-0.22UF,16V,10%,X7R,A3A
P3E_OCP_CPU0_PE3_C_TXN<6> J8E3             20       SCONN80_E67482007_SM-CONN,E674A
P3E_OCP_CPU0_PE3_C_TXN<7> C2R9             2        CAP_0402-0.22UF,16V,10%,X7R,A3A
P3E_OCP_CPU0_PE3_C_TXN<7> J8E3             12       SCONN80_E67482007_SM-CONN,E674A
P3E_OCP_CPU0_PE3_C_TXN<8> C2M15            2        CAP_0402-0.22UF,16V,10%,X7R,A3A
P3E_OCP_CPU0_PE3_C_TXN<8> J9B3             114      SCONN120_A28699018_SM-SCONN,A2A
P3E_OCP_CPU0_PE3_C_TXN<9> C1M19            2        CAP_0402-0.22UF,16V,10%,X7R,A3A
P3E_OCP_CPU0_PE3_C_TXN<9> J9B3             106      SCONN120_A28699018_SM-SCONN,A2A
P3E_OCP_CPU0_PE3_C_TXN<10> C1M17            2        CAP_0402-0.22UF,16V,10%,X7R,A3A
P3E_OCP_CPU0_PE3_C_TXN<10> J9B3             98       SCONN120_A28699018_SM-SCONN,A2A
P3E_OCP_CPU0_PE3_C_TXN<11> C1M15            2        CAP_0402-0.22UF,16V,10%,X7R,A3A
P3E_OCP_CPU0_PE3_C_TXN<11> J9B3             90       SCONN120_A28699018_SM-SCONN,A2A
P3E_OCP_CPU0_PE3_C_TXN<12> C1M13            2        CAP_0402-0.22UF,16V,10%,X7R,A3A
P3E_OCP_CPU0_PE3_C_TXN<12> J9B3             82       SCONN120_A28699018_SM-SCONN,A2A
P3E_OCP_CPU0_PE3_C_TXN<13> C1M11            2        CAP_0402-0.22UF,16V,10%,X7R,A3A
P3E_OCP_CPU0_PE3_C_TXN<13> J9B3             74       SCONN120_A28699018_SM-SCONN,A2A
P3E_OCP_CPU0_PE3_C_TXN<14> C1M9             2        CAP_0402-0.22UF,16V,10%,X7R,A3A
P3E_OCP_CPU0_PE3_C_TXN<14> J9B3             66       SCONN120_A28699018_SM-SCONN,A2A
P3E_OCP_CPU0_PE3_C_TXN<15> C1M7             2        CAP_0402-0.22UF,16V,10%,X7R,A3A
P3E_OCP_CPU0_PE3_C_TXN<15> J9B3             58       SCONN120_A28699018_SM-SCONN,A2A
P3E_OCP_CPU0_PE3_C_TXP<0> C1R2             2        CAP_0402-0.22UF,16V,10%,X7R,A3A
P3E_OCP_CPU0_PE3_C_TXP<0> J8E3             66       SCONN80_E67482007_SM-CONN,E674A
P3E_OCP_CPU0_PE3_C_TXP<1> C1R4             2        CAP_0402-0.22UF,16V,10%,X7R,A3A
P3E_OCP_CPU0_PE3_C_TXP<1> J8E3             58       SCONN80_E67482007_SM-CONN,E674A
P3E_OCP_CPU0_PE3_C_TXP<2> C1R6             2        CAP_0402-0.22UF,16V,10%,X7R,A3A
P3E_OCP_CPU0_PE3_C_TXP<2> J8E3             50       SCONN80_E67482007_SM-CONN,E674A
P3E_OCP_CPU0_PE3_C_TXP<3> C1R8             2        CAP_0402-0.22UF,16V,10%,X7R,A3A
P3E_OCP_CPU0_PE3_C_TXP<3> J8E3             42       SCONN80_E67482007_SM-CONN,E674A
P3E_OCP_CPU0_PE3_C_TXP<4> C1R10            2        CAP_0402-0.22UF,16V,10%,X7R,A3A
P3E_OCP_CPU0_PE3_C_TXP<4> J8E3             34       SCONN80_E67482007_SM-CONN,E674A
P3E_OCP_CPU0_PE3_C_TXP<5> C2R14            2        CAP_0402-0.22UF,16V,10%,X7R,A3A
P3E_OCP_CPU0_PE3_C_TXP<5> J8E3             26       SCONN80_E67482007_SM-CONN,E674A
P3E_OCP_CPU0_PE3_C_TXP<6> C2R8             2        CAP_0402-0.22UF,16V,10%,X7R,A3A
P3E_OCP_CPU0_PE3_C_TXP<6> J8E3             18       SCONN80_E67482007_SM-CONN,E674A
P3E_OCP_CPU0_PE3_C_TXP<7> C2R10            2        CAP_0402-0.22UF,16V,10%,X7R,A3A
P3E_OCP_CPU0_PE3_C_TXP<7> J8E3             10       SCONN80_E67482007_SM-CONN,E674A
P3E_OCP_CPU0_PE3_C_TXP<8> C2M14            2        CAP_0402-0.22UF,16V,10%,X7R,A3A
P3E_OCP_CPU0_PE3_C_TXP<8> J9B3             112      SCONN120_A28699018_SM-SCONN,A2A
P3E_OCP_CPU0_PE3_C_TXP<9> C1M18            2        CAP_0402-0.22UF,16V,10%,X7R,A3A
P3E_OCP_CPU0_PE3_C_TXP<9> J9B3             104      SCONN120_A28699018_SM-SCONN,A2A
P3E_OCP_CPU0_PE3_C_TXP<10> C1M16            2        CAP_0402-0.22UF,16V,10%,X7R,A3A
P3E_OCP_CPU0_PE3_C_TXP<10> J9B3             96       SCONN120_A28699018_SM-SCONN,A2A
P3E_OCP_CPU0_PE3_C_TXP<11> C1M14            2        CAP_0402-0.22UF,16V,10%,X7R,A3A
P3E_OCP_CPU0_PE3_C_TXP<11> J9B3             88       SCONN120_A28699018_SM-SCONN,A2A
P3E_OCP_CPU0_PE3_C_TXP<12> C1M12            2        CAP_0402-0.22UF,16V,10%,X7R,A3A
P3E_OCP_CPU0_PE3_C_TXP<12> J9B3             80       SCONN120_A28699018_SM-SCONN,A2A
P3E_OCP_CPU0_PE3_C_TXP<13> C1M10            2        CAP_0402-0.22UF,16V,10%,X7R,A3A
P3E_OCP_CPU0_PE3_C_TXP<13> J9B3             72       SCONN120_A28699018_SM-SCONN,A2A
P3E_OCP_CPU0_PE3_C_TXP<14> C1M8             2        CAP_0402-0.22UF,16V,10%,X7R,A3A
P3E_OCP_CPU0_PE3_C_TXP<14> J9B3             64       SCONN120_A28699018_SM-SCONN,A2A
P3E_OCP_CPU0_PE3_C_TXP<15> C1M6             2        CAP_0402-0.22UF,16V,10%,X7R,A3A
P3E_OCP_CPU0_PE3_C_TXP<15> J9B3             56       SCONN120_A28699018_SM-SCONN,A2A
P3E_PCH_M2_RX_DN<1>      J8F1             29       SCONN75K_H17033002_SMT1-SCONN,A
P3E_PCH_M2_RX_DN<1>      U7C1             AY72     LBG_CORE_QAT_EXT_D_BGA1-IC,H91A
P3E_PCH_M2_RX_DN<2>      J8F1             17       SCONN75K_H17033002_SMT1-SCONN,A
P3E_PCH_M2_RX_DN<2>      U7C1             AW71     LBG_CORE_QAT_EXT_D_BGA1-IC,H91A
P3E_PCH_M2_RX_DN<3>      J8F1             5        SCONN75K_H17033002_SMT1-SCONN,A
P3E_PCH_M2_RX_DN<3>      U7C1             AV72     LBG_CORE_QAT_EXT_D_BGA1-IC,H91A
P3E_PCH_M2_RX_DP<1>      J8F1             31       SCONN75K_H17033002_SMT1-SCONN,A
P3E_PCH_M2_RX_DP<1>      U7C1             AY70     LBG_CORE_QAT_EXT_D_BGA1-IC,H91A
P3E_PCH_M2_RX_DP<2>      J8F1             19       SCONN75K_H17033002_SMT1-SCONN,A
P3E_PCH_M2_RX_DP<2>      U7C1             AW69     LBG_CORE_QAT_EXT_D_BGA1-IC,H91A
P3E_PCH_M2_RX_DP<3>      J8F1             7        SCONN75K_H17033002_SMT1-SCONN,A
P3E_PCH_M2_RX_DP<3>      U7C1             AV70     LBG_CORE_QAT_EXT_D_BGA1-IC,H91A
P3E_PCH_M2_SATA6G_RX_R_DN C8F15            2        CAP_A_0402V-0.01UF,25V,10%,EMPA
P3E_PCH_M2_SATA6G_RX_R_DN J8F1             43       SCONN75K_H17033002_SMT1-SCONN,A
P3E_PCH_M2_SATA6G_RX_R_DN R8F21            2        RES_0402-0.0,5%,1/16W,CHIP,G21A
P3E_PCH_M2_SATA6G_RX_R_DP C8F13            2        CAP_A_0402V-0.01UF,25V,10%,EMPA
P3E_PCH_M2_SATA6G_RX_R_DP J8F1             41       SCONN75K_H17033002_SMT1-SCONN,A
P3E_PCH_M2_SATA6G_RX_R_DP R8F18            2        RES_0402-0.0,5%,1/16W,CHIP,G21A
P3E_PCH_M2_SATA6G_TX_R_DN C8F11            2        CAP_A_0402V-0.01UF,25V,10%,EMPA
P3E_PCH_M2_SATA6G_TX_R_DN C8F12            2        CAP_0402-0.22UF,16V,10%,X7R,A3A
P3E_PCH_M2_SATA6G_TX_R_DN J8F1             47       SCONN75K_H17033002_SMT1-SCONN,A
P3E_PCH_M2_SATA6G_TX_R_DP C8F6             2        CAP_A_0402V-0.01UF,25V,10%,EMPA
P3E_PCH_M2_SATA6G_TX_R_DP C8F7             2        CAP_0402-0.22UF,16V,10%,X7R,A3A
P3E_PCH_M2_SATA6G_TX_R_DP J8F1             49       SCONN75K_H17033002_SMT1-SCONN,A
P3E_PCH_M2_TX_C_DN<1>    C2T11            1        CAP_0402-0.22UF,16V,10%,X7R,A3A
P3E_PCH_M2_TX_C_DN<1>    J8F1             35       SCONN75K_H17033002_SMT1-SCONN,A
P3E_PCH_M2_TX_C_DN<2>    C2T14            1        CAP_0402-0.22UF,16V,10%,X7R,A3A
P3E_PCH_M2_TX_C_DN<2>    J8F1             23       SCONN75K_H17033002_SMT1-SCONN,A
P3E_PCH_M2_TX_C_DN<3>    C2T23            1        CAP_0402-0.22UF,16V,10%,X7R,A3A
P3E_PCH_M2_TX_C_DN<3>    J8F1             11       SCONN75K_H17033002_SMT1-SCONN,A
P3E_PCH_M2_TX_C_DP<1>    C2T10            1        CAP_0402-0.22UF,16V,10%,X7R,A3A
P3E_PCH_M2_TX_C_DP<1>    J8F1             37       SCONN75K_H17033002_SMT1-SCONN,A
P3E_PCH_M2_TX_C_DP<2>    C2T13            1        CAP_0402-0.22UF,16V,10%,X7R,A3A
P3E_PCH_M2_TX_C_DP<2>    J8F1             25       SCONN75K_H17033002_SMT1-SCONN,A
P3E_PCH_M2_TX_C_DP<3>    C2T20            1        CAP_0402-0.22UF,16V,10%,X7R,A3A
P3E_PCH_M2_TX_C_DP<3>    J8F1             13       SCONN75K_H17033002_SMT1-SCONN,A
P3E_PCH_M2_TX_DN<1>      C2T11            2        CAP_0402-0.22UF,16V,10%,X7R,A3A
P3E_PCH_M2_TX_DN<1>      U7C1             BM65     LBG_CORE_QAT_EXT_D_BGA1-IC,H91A
P3E_PCH_M2_TX_DN<2>      C2T14            2        CAP_0402-0.22UF,16V,10%,X7R,A3A
P3E_PCH_M2_TX_DN<2>      U7C1             BK65     LBG_CORE_QAT_EXT_D_BGA1-IC,H91A
P3E_PCH_M2_TX_DN<3>      C2T23            2        CAP_0402-0.22UF,16V,10%,X7R,A3A
P3E_PCH_M2_TX_DN<3>      U7C1             BH61     LBG_CORE_QAT_EXT_D_BGA1-IC,H91A
P3E_PCH_M2_TX_DP<1>      C2T10            2        CAP_0402-0.22UF,16V,10%,X7R,A3A
P3E_PCH_M2_TX_DP<1>      U7C1             BR65     LBG_CORE_QAT_EXT_D_BGA1-IC,H91A
P3E_PCH_M2_TX_DP<2>      C2T13            2        CAP_0402-0.22UF,16V,10%,X7R,A3A
P3E_PCH_M2_TX_DP<2>      U7C1             BL66     LBG_CORE_QAT_EXT_D_BGA1-IC,H91A
P3E_PCH_M2_TX_DP<3>      C2T20            2        CAP_0402-0.22UF,16V,10%,X7R,A3A
P3E_PCH_M2_TX_DP<3>      U7C1             BK61     LBG_CORE_QAT_EXT_D_BGA1-IC,H91A
P3E_PCH_RX_0_DN          R8F21            1        RES_0402-0.0,5%,1/16W,CHIP,G21A
P3E_PCH_RX_0_DN          U7C1             BA71     LBG_CORE_QAT_EXT_D_BGA1-IC,H91A
P3E_PCH_RX_0_DP          R8F18            1        RES_0402-0.0,5%,1/16W,CHIP,G21A
P3E_PCH_RX_0_DP          U7C1             BA69     LBG_CORE_QAT_EXT_D_BGA1-IC,H91A
P3E_PCH_TX_0_DN          C8F12            1        CAP_0402-0.22UF,16V,10%,X7R,A3A
P3E_PCH_TX_0_DN          U7C1             BR61     LBG_CORE_QAT_EXT_D_BGA1-IC,H91A
P3E_PCH_TX_0_DP          C8F7             1        CAP_0402-0.22UF,16V,10%,X7R,A3A
P3E_PCH_TX_0_DP          U7C1             BN63     LBG_CORE_QAT_EXT_D_BGA1-IC,H91A
P3V3                     C1L16            1        CAP_A_0402V-0.1UF,16V,10%,X7R,A
P3V3                     C1M3             1        CAP_A_0402V-1.0UF,6.3V,10%,X6SA
P3V3                     C1M21            1        CAP_A_0402V-1.0UF,6.3V,10%,X6SA
P3V3                     C1M24            1        CAP_A_0402V-0.1UF,16V,10%,X7R,A
P3V3                     C1U19            1        CAP_0402-1.0UF,16V,10%,X6S,D97A
P3V3                     C2T2             1        CAP_A_0402V-0.1UF,16V,10%,X7R,A
P3V3                     C2T4             1        CAP_A_0402V-0.1UF,16V,10%,X7R,A
P3V3                     C2T5             1        CAP_A_0402V-0.1UF,16V,10%,X7R,A
P3V3                     C2T15            1        CAP_A_0402V-0.1UF,16V,10%,X7R,A
P3V3                     C2T16            1        CAP_A_0402V-0.1UF,16V,10%,X7R,A
P3V3                     C2T21            1        CAP_A_0402V-0.1UF,16V,10%,X7R,A
P3V3                     C2T24            1        CAP_A_0402V-0.1UF,16V,10%,X7R,A
P3V3                     C2T26            1        CAP_A_0402V-0.1UF,16V,10%,X7R,A
P3V3                     C2T29            1        CAP_A_0402V-0.1UF,16V,10%,X7R,A
P3V3                     C2T33            1        CAP_A_0402V-1.0UF,6.3V,10%,X6SA
P3V3                     C2U2             1        CAP_0805-10UF,16V,10%,X6S,C953A
P3V3                     C2U19            1        CAP_A_0402V-0.1UF,16V,10%,X7R,A
P3V3                     C2U21            1        CAP_A_0402V-0.1UF,16V,10%,X7R,A
P3V3                     C2U25            1        CAP_A_0402V-0.1UF,16V,10%,X7R,A
P3V3                     C3F2             1        CAP_A_0402V-0.1UF,16V,10%,X7R,A
P3V3                     C3P50            1        CAP_0402-1.0UF,16V,10%,X6S,D97A
P3V3                     C6F1             1        CAP_A_0402V-0.1UF,16V,10%,X7R,A
P3V3                     C7D4             1        CAP_0402-1.0UF,16V,10%,X6S,D97A
P3V3                     EU2T1            6        SLG55021_SM-IC,G56246-001
P3V3                     FB6P1            1        FERRITE_SMLF-600,FB,656554-043
P3V3                     J4B2             D1       SCONN120_H61426002_SM-CONN,H61A
P3V3                     J6B1             D1       SCONN120_H61426002_SM-CONN,H61A
P3V3                     J8B1             18       SCONN24_H46321001_SM-SCONN,H46A
P3V3                     J8B1             20       SCONN24_H46321001_SM-SCONN,H46A
P3V3                     J8F1             2        SCONN75K_H17033002_SMT1-SCONN,A
P3V3                     J8F1             4        SCONN75K_H17033002_SMT1-SCONN,A
P3V3                     J8F1             12       SCONN75K_H17033002_SMT1-SCONN,A
P3V3                     J8F1             14       SCONN75K_H17033002_SMT1-SCONN,A
P3V3                     J8F1             16       SCONN75K_H17033002_SMT1-SCONN,A
P3V3                     J8F1             18       SCONN75K_H17033002_SMT1-SCONN,A
P3V3                     J8F1             70       SCONN75K_H17033002_SMT1-SCONN,A
P3V3                     J8F1             72       SCONN75K_H17033002_SMT1-SCONN,A
P3V3                     J8F1             74       SCONN75K_H17033002_SMT1-SCONN,A
P3V3                     J8G1             21       SCONN200_H68296001_SM-CONN,H68A
P3V3                     J8G1             22       SCONN200_H68296001_SM-CONN,H68A
P3V3                     J8G1             23       SCONN200_H68296001_SM-CONN,H68A
P3V3                     J8G1             24       SCONN200_H68296001_SM-CONN,H68A
P3V3                     J9B3             18       SCONN120_A28699018_SM-SCONN,A2A
P3V3                     J9B3             19       SCONN120_A28699018_SM-SCONN,A2A
P3V3                     J9B3             20       SCONN120_A28699018_SM-SCONN,A2A
P3V3                     J9B3             21       SCONN120_A28699018_SM-SCONN,A2A
P3V3                     J9B3             22       SCONN120_A28699018_SM-SCONN,A2A
P3V3                     J9B3             23       SCONN120_A28699018_SM-SCONN,A2A
P3V3                     J9B3             24       SCONN120_A28699018_SM-SCONN,A2A
P3V3                     J9B3             25       SCONN120_A28699018_SM-SCONN,A2A
P3V3                     Q8G1             1        MOSFET_N_LCC3-BSZ019N03LS,NFETA
P3V3                     Q9A1             3        NPN_DUAL_SSOPLF-MBT3904,EMPTY,A
P3V3                     R1L1             1        RES_0402-2.0K,1%,1/16W,CHIP,G2A
P3V3                     R1L21            1        RES_0402-64.9,1.0%,1/16W,CHIP,A
P3V3                     R1M11            1        RES_0402-10.0K,1%,1/16W,CHIP,GA
P3V3                     R1M12            1        RES_0402-10.0K,1%,1/16W,CHIP,GA
P3V3                     R1U26            1        RES_0402-5.11K,1%,1/16W,CHIP,GA
P3V3                     R2L21            1        RES_0402-2.0K,1%,1/16W,CHIP,G2A
P3V3                     R2L23            1        RES_0402-2.0K,1%,1/16W,CHIP,G2A
P3V3                     R2N27            1        RES_0402-4.75K,1%,1/16W,CHIP,GA
P3V3                     R2P15            1        RES_0402-10.0K,1%,1/16W,CHIP,GA
P3V3                     R3R4             1        RES_0402-4.75K,1%,1/16W,CHIP,GA
P3V3                     R3R10            1        RES_0402-4.75K,1%,1/16W,CHIP,GA
P3V3                     R4A5             1        RES_0402-10.0K,1%,1/16W,CHIP,GA
P3V3                     R4D69            1        RES_0402-4.75K,1%,1/16W,CHIP,GA
P3V3                     R4D70            1        RES_0402-4.75K,1%,1/16W,CHIP,GA
P3V3                     R4G17            1        RES_0402-10.0K,1%,1/16W,CHIP,GA
P3V3                     R4G18            1        RES_0402-10.0K,1%,1/16W,CHIP,GA
P3V3                     R6L4             1        RES_0402-1.0M,1%,1/16W,EMPTY,GA
P3V3                     R6L5             1        RES_0402-1.0M,1%,1/16W,EMPTY,GA
P3V3                     R6L8             1        RES_0402-0.0,5%,1/16W,CHIP,G21A
P3V3                     R6L9             1        RES_0402-10.0K,1%,1/16W,CHIP,GA
P3V3                     R6L11            1        RES_0402-0.0,5%,1/16W,CHIP,G21A
P3V3                     R6M4             1        RES_0402-4.75K,1%,1/16W,CHIP,GA
P3V3                     R6P48            1        RES_0402-4.75K,1%,1/16W,CHIP,GA
P3V3                     R6U3             1        RES_0402-1.0M,1%,1/16W,EMPTY,GA
P3V3                     R6U4             1        RES_0402-0.0,5%,1/16W,CHIP,G21A
P3V3                     R6U7             1        RES_0402-0.0,5%,1/16W,CHIP,G21A
P3V3                     R6U15            1        RES_0402-1.0M,1%,1/16W,EMPTY,GA
P3V3                     R7E7             1        RES_0402-4.75K,1%,1/16W,CHIP,GA
P3V3                     R7E10            1        RES_0402-4.75K,1%,1/16W,CHIP,GA
P3V3                     R7E11            1        RES_0402-4.75K,1%,1/16W,CHIP,GA
P3V3                     R7E21            1        RES_0402-4.75K,1%,1/16W,CHIP,GA
P3V3                     R7G7             1        RES_0402-4.75K,1%,1/16W,CHIP,GA
P3V3                     R8F36            1        RES_0402-10.0K,1%,1/16W,CHIP,GA
P3V3                     R9A1             1        RES_0402-1.00K,1%,1/16W,EMPTY,A
P3V3                     U1L3             3        ADM809_SMLF-IC,D23047-001-GND=A
P3V3                     U2T4             14       GTL2014_SM-IC,D66151-001
P3V3                     U3P2             14       GTL2014_SM-IC,D66151-001
P3V3                     U7D2             14       GTL2014_SM-IC,D66151-001
P3V3                     U9G1             14       GTL2014_SM-IC,D66151-001
P3V3                     Y3F1             6        OSC_C_6P10-156.25MHZ,OSC,G6383A
P3V3                     Y6F1             6        OSC_C_6P10-156.25MHZ,OSC,G6383A
P3V3_DB1200              C3D22            1        CAP_0805-10UF,16V,10%,X7R,G106A
P3V3_DB1200              C6P4             1        CAP_A_0402V-0.1UF,16V,10%,X7R,A
P3V3_DB1200              C6P5             1        CAP_A_0402V-0.1UF,16V,10%,X7R,A
P3V3_DB1200              C6P6             1        CAP_A_0402V-0.1UF,16V,10%,X7R,A
P3V3_DB1200              C6P9             1        CAP_A_0402V-0.1UF,16V,10%,X7R,A
P3V3_DB1200              C6P10            1        CAP_A_0402V-0.1UF,16V,10%,X7R,A
P3V3_DB1200              C6P11            1        CAP_A_0402V-0.1UF,16V,10%,X7R,A
P3V3_DB1200              C6P12            1        CAP_A_0402V-0.1UF,16V,10%,X7R,A
P3V3_DB1200              EU4D2            24       NB3W1200L_LCC-IC,H13585-001
P3V3_DB1200              EU4D2            25       NB3W1200L_LCC-IC,H13585-001
P3V3_DB1200              EU4D2            32       NB3W1200L_LCC-IC,H13585-001
P3V3_DB1200              EU4D2            40       NB3W1200L_LCC-IC,H13585-001
P3V3_DB1200              EU4D2            49       NB3W1200L_LCC-IC,H13585-001
P3V3_DB1200              EU4D2            56       NB3W1200L_LCC-IC,H13585-001
P3V3_DB1200              EU4D2            57       NB3W1200L_LCC-IC,H13585-001
P3V3_DB1200              FB6P1            2        FERRITE_SMLF-600,FB,656554-043
P3V3_DB1200              R3D14            1        RES_0603-2.2,1.0%,1/10W,CHIP,GA
P3V3_DB1200              R4D35            1        RES_0402-10.0K,1%,1/16W,EMPTY,A
P3V3_DB1200              R4D38            1        RES_0402-10.0K,1%,1/16W,EMPTY,A
P3V3_DB1200              R4D40            1        RES_0402-4.75K,1%,1/16W,CHIP,GA
P3V3_DB1200              R4D41            1        RES_0402-4.75K,1%,1/16W,CHIP,GA
P3V3_DB1200              R6P25            1        RES_0603-2.2,1.0%,1/10W,CHIP,GA
P3V3_DB1200_A            C4D23            1        CAP_A_0402V-1.0UF,6.3V,10%,X6SA
P3V3_DB1200_A            C4D24            1        CAP_A_0402V-0.1UF,16V,10%,X7R,A
P3V3_DB1200_A            EU4D2            1        NB3W1200L_LCC-IC,H13585-001
P3V3_DB1200_A            R3D14            2        RES_0603-2.2,1.0%,1/10W,CHIP,GA
P3V3_DB1200_R            C4D22            1        CAP_A_0402V-0.1UF,16V,10%,X7R,A
P3V3_DB1200_R            C4D27            1        CAP_A_0402V-1.0UF,6.3V,10%,X6SA
P3V3_DB1200_R            EU4D2            8        NB3W1200L_LCC-IC,H13585-001
P3V3_DB1200_R            R6P25            2        RES_0603-2.2,1.0%,1/10W,CHIP,GA
P3V3_FB_ADC128_VCC       C1U20            1        CAP_0805-10UF,16V,10%,X7R,G106A
P3V3_FB_ADC128_VCC       C9G19            1        CAP_A_0402V-0.1UF,16V,10%,X7R,A
P3V3_FB_ADC128_VCC       EU9G1            5        ADC128D818_SM-IC,H63642-001
P3V3_FB_ADC128_VCC       FB1U2            2        FERRITE_SMLF-60,FB,693286-001
P3V3_RTC_STBY            C2U26            1        CAP_A_0402V-1.0UF,6.3V,10%,X6SA
P3V3_RTC_STBY            CR2U1            3        DIODE2A_DUAL_SMLF-BAS70-05,DIOA
P3V3_RTC_STBY            R3N4             1        RES_0402-20.0K,1%,1/16W,CHIP,GA
P3V3_RTC_STBY            R7C10            1        RES_0402-20.0K,1%,1/16W,CHIP,GA
P3V3_RTC_STBY            U7C1             AJ27     LBG_CORE_QAT_EXT_D_BGA1-IC,H91A
P3V3_STBY                C1E22            1        CAP_A_0402V-0.1UF,16V,10%,X7R,A
P3V3_STBY                C1L1             1        CAP_0402-1.0UF,16V,10%,X6S,D97A
P3V3_STBY                C1L9             1        CAP_A_0402V-0.1UF,16V,10%,X7R,A
P3V3_STBY                C1L11            1        CAP_A_0402V-0.1UF,16V,10%,X7R,A
P3V3_STBY                C1L17            1        CAP_A_0402V-0.1UF,16V,10%,X7R,A
P3V3_STBY                C1L19            1        CAP_0402-1.0UF,16V,10%,X6S,D97A
P3V3_STBY                C1L20            1        CAP_A_0402V-0.01UF,25V,10%,X7RA
P3V3_STBY                C1M20            1        CAP_A_0402V-0.1UF,16V,10%,X7R,A
P3V3_STBY                C1M25            1        CAP_A_0402V-1.0UF,6.3V,10%,X6SA
P3V3_STBY                C1M28            1        CAP_A_0402V-0.01UF,25V,10%,X7RA
P3V3_STBY                C1M30            1        CAP_A_0402V-0.01UF,25V,10%,X7RA
P3V3_STBY                C1M31            1        CAP_A_0402V-0.01UF,25V,10%,X7RA
P3V3_STBY                C1M32            1        CAP_A_0402V-1.0UF,6.3V,10%,X6SA
P3V3_STBY                C1M34            1        CAP_A_0402V-0.01UF,25V,10%,X7RA
P3V3_STBY                C1M35            1        CAP_A_0402V-0.01UF,25V,10%,X7RA
P3V3_STBY                C1M36            1        CAP_A_0402V-0.01UF,25V,10%,X7RA
P3V3_STBY                C1M37            1        CAP_A_0402V-1.0UF,6.3V,10%,X6SA
P3V3_STBY                C1R13            1        CAP_0603-10UF,6.3V,20%,X6S,E15A
P3V3_STBY                C1R14            1        CAP_A_0402V-0.1UF,16V,10%,X7R,A
P3V3_STBY                C1R20            1        CAP_A_0402V-0.1UF,16V,10%,X7R,A
P3V3_STBY                C1R21            1        CAP_A_0402V-0.1UF,16V,10%,X7R,A
P3V3_STBY                C1R22            1        CAP_0603-10UF,6.3V,20%,X6S,E15A
P3V3_STBY                C1R25            1        CAP_A_0402V-0.1UF,16V,10%,X7R,A
P3V3_STBY                C1R27            1        CAP_A_0402V-0.1UF,16V,10%,X7R,A
P3V3_STBY                C1R28            1        CAP_A_0402V-0.1UF,16V,10%,X7R,A
P3V3_STBY                C1T3             1        CAP_A_0402V-0.1UF,16V,10%,X7R,A
P3V3_STBY                C1T7             1        CAP_0603-10UF,6.3V,20%,X6S,E15A
P3V3_STBY                C1T8             1        CAP_A_0402V-0.1UF,16V,10%,X7R,A
P3V3_STBY                C1T9             1        CAP_0805-22UF,6.3V,20%,X6S,C95A
P3V3_STBY                C1T10            1        CAP_A_0402V-0.1UF,16V,10%,X7R,A
P3V3_STBY                C1T11            1        CAP_A_0402V-0.1UF,16V,10%,X7R,A
P3V3_STBY                C1T12            1        CAP_A_0402V-1.0UF,6.3V,10%,X6SA
P3V3_STBY                C1T13            1        CAP_0805-22UF,6.3V,20%,X6S,C95A
P3V3_STBY                C1T14            1        CAP_A_0402V-0.1UF,16V,10%,X7R,A
P3V3_STBY                C1T22            1        CAP_A_0402V-0.1UF,16V,10%,X7R,A
P3V3_STBY                C1T25            1        CAP_A_0402V-0.1UF,16V,10%,X7R,A
P3V3_STBY                C1T26            1        CAP_A_0402V-0.1UF,16V,10%,X7R,A
P3V3_STBY                C1T29            1        CAP_A_0402V-0.1UF,16V,10%,X7R,A
P3V3_STBY                C1T30            1        CAP_A_0402V-0.1UF,16V,10%,X7R,A
P3V3_STBY                C1T38            1        CAP_A_0402V-0.1UF,16V,10%,X7R,A
P3V3_STBY                C1T43            1        CAP_A_0402V-0.1UF,16V,10%,X7R,A
P3V3_STBY                C1T44            1        CAP_0603-4.7UF,6.3V,10%,X6S,E1A
P3V3_STBY                C1T45            1        CAP_A_0402V-0.1UF,16V,10%,X7R,A
P3V3_STBY                C1T47            1        CAP_A_0402V-0.1UF,16V,10%,X7R,A
P3V3_STBY                C1T50            1        CAP_A_0402V-0.1UF,16V,10%,X7R,A
P3V3_STBY                C1T52            1        CAP_A_0402V-0.1UF,16V,10%,X7R,A
P3V3_STBY                C1T56            1        CAP_A_0402V-0.1UF,16V,10%,X7R,A
P3V3_STBY                C1U2             1        CAP_0402LF-100.0PF,50V,5%,COG,A
P3V3_STBY                C1U3             1        CAP_A_0402V-0.1UF,16V,10%,X7R,A
P3V3_STBY                C1U4             1        CAP_A_0402V-0.1UF,16V,10%,X7R,A
P3V3_STBY                C1U5             1        CAP_A_0402V-0.1UF,16V,10%,X7R,A
P3V3_STBY                C1U8             1        CAP_A_0402V-1.0UF,6.3V,10%,X6SA
P3V3_STBY                C1U9             1        CAP_A_0402V-0.1UF,16V,10%,X7R,A
P3V3_STBY                C1U11            1        CAP_A_0402V-0.1UF,16V,10%,X7R,A
P3V3_STBY                C2M16            1        CAP_A_0402V-1.0UF,6.3V,10%,X6SA
P3V3_STBY                C2N14            1        CAP_0603-10UF,6.3V,20%,X6S,E15A
P3V3_STBY                C2N17            1        CAP_0603-10UF,6.3V,20%,X6S,E15A
P3V3_STBY                C2N18            1        CAP_A_0402V-1.0UF,6.3V,10%,X6SA
P3V3_STBY                C2N19            1        CAP_A_0402V-1.0UF,6.3V,10%,X6SA
P3V3_STBY                C2N20            1        CAP_A_0402V-1.0UF,6.3V,10%,X6SA
P3V3_STBY                C2N21            1        CAP_0603-10UF,6.3V,20%,X6S,E15A
P3V3_STBY                C2N22            1        CAP_0603-10UF,6.3V,20%,X6S,E15A
P3V3_STBY                C2N23            1        CAP_0603-10UF,6.3V,20%,X6S,E15A
P3V3_STBY                C2N24            1        CAP_0603-10UF,6.3V,20%,X6S,E15A
P3V3_STBY                C2N25            1        CAP_A_0402V-1.0UF,6.3V,10%,X6SA
P3V3_STBY                C2N26            1        CAP_A_0402V-1.0UF,6.3V,10%,X6SA
P3V3_STBY                C2P1             1        CAP_A_0402V-0.1UF,16V,10%,X7R,A
P3V3_STBY                C2P2             1        CAP_A_0402V-0.1UF,16V,10%,X7R,A
P3V3_STBY                C2P3             1        CAP_A_0402V-0.1UF,16V,10%,X7R,A
P3V3_STBY                C2P4             1        CAP_A_0402V-0.1UF,16V,10%,X7R,A
P3V3_STBY                C2P5             1        CAP_A_0402V-0.1UF,16V,10%,X7R,A
P3V3_STBY                C2P6             1        CAP_A_0402V-0.1UF,16V,10%,X7R,A
P3V3_STBY                C2P7             1        CAP_A_0402V-0.1UF,16V,10%,X7R,A
P3V3_STBY                C2P8             1        CAP_A_0402V-0.01UF,25V,10%,X7RA
P3V3_STBY                C2P9             1        CAP_A_0402V-0.1UF,16V,10%,X7R,A
P3V3_STBY                C2R1             1        CAP_A_0402V-0.1UF,16V,10%,X7R,A
P3V3_STBY                C2R2             1        CAP_A_0402V-0.1UF,16V,10%,X7R,A
P3V3_STBY                C2R3             1        CAP_A_0402V-0.1UF,16V,10%,X7R,A
P3V3_STBY                C2R4             1        CAP_A_0402V-0.1UF,16V,10%,X7R,A
P3V3_STBY                C2R5             1        CAP_A_0402V-0.1UF,16V,10%,X7R,A
P3V3_STBY                C2T1             1        CAP_A_0402V-0.1UF,16V,10%,X7R,A
P3V3_STBY                C2T3             1        CAP_A_0402V-0.1UF,16V,10%,X7R,A
P3V3_STBY                C2T6             1        CAP_0805-22UF,6.3V,20%,X6S,C95A
P3V3_STBY                C2T7             1        CAP_0805-22UF,6.3V,20%,X6S,C95A
P3V3_STBY                C2T8             1        CAP_A_0402V-0.1UF,16V,10%,X7R,A
P3V3_STBY                C2T9             1        CAP_0805-22UF,6.3V,20%,X6S,C95A
P3V3_STBY                C2T12            1        CAP_A_0402V-0.1UF,16V,10%,X7R,A
P3V3_STBY                C2T28            1        CAP_A_0402V-1.0UF,6.3V,10%,X6SA
P3V3_STBY                C2T35            1        CAP_A_0402V-0.1UF,16V,10%,X7R,A
P3V3_STBY                C2T36            1        CAP_A_0402V-0.1UF,16V,10%,X7R,A
P3V3_STBY                C2U1             1        CAP_0805-10UF,16V,10%,X6S,C953A
P3V3_STBY                C2U22            1        CAP_A_0402V-0.1UF,16V,10%,X7R,A
P3V3_STBY                C2U23            1        CAP_A_0402V-0.1UF,16V,10%,X7R,A
P3V3_STBY                C2U27            1        CAP_A_0402V-0.1UF,16V,10%,X7R,A
P3V3_STBY                C2U28            1        CAP_A_0402V-0.1UF,16V,10%,X7R,A
P3V3_STBY                C3N23            1        CAP_A_0402V-1.0UF,6.3V,10%,X6SA
P3V3_STBY                C3P42            1        CAP_A_0402V-1.0UF,6.3V,10%,X6SA
P3V3_STBY                C3P43            1        CAP_A_0402V-0.1UF,16V,10%,X7R,A
P3V3_STBY                C3P44            1        CAP_A_0402V-0.1UF,16V,10%,X7R,A
P3V3_STBY                C3P46            1        CAP_A_0402V-0.1UF,16V,10%,X7R,A
P3V3_STBY                C3P47            1        CAP_A_0402V-0.1UF,16V,10%,X7R,A
P3V3_STBY                C3P48            1        CAP_A_0402V-0.1UF,16V,10%,X7R,A
P3V3_STBY                C3P51            1        CAP_A_0402V-0.1UF,16V,10%,X7R,A
P3V3_STBY                C3P52            1        CAP_A_0402V-0.1UF,16V,10%,X7R,A
P3V3_STBY                C3R1             1        CAP_A_0402V-0.1UF,16V,10%,X7R,A
P3V3_STBY                C3R2             1        CAP_A_0402V-0.1UF,16V,10%,X7R,A
P3V3_STBY                C3R3             1        CAP_A_0402V-0.1UF,16V,10%,X7R,A
P3V3_STBY                C3T4             1        CAP_A_0402V-1.0UF,6.3V,10%,X6SA
P3V3_STBY                C3T5             1        CAP_A_0402V-0.01UF,25V,10%,X7RA
P3V3_STBY                C4C3             1        CAP_A_0402V-1.0UF,6.3V,10%,X6SA
P3V3_STBY                C7D1             1        CAP_A_0402V-0.1UF,16V,10%,X7R,A
P3V3_STBY                C7D2             1        CAP_0603-10UF,6.3V,20%,X6S,E15A
P3V3_STBY                C7E3             1        CAP_A_0402V-0.1UF,16V,10%,X7R,A
P3V3_STBY                C7E4             1        CAP_A_0402V-0.1UF,16V,10%,X7R,A
P3V3_STBY                C7F1             1        CAP_A_0402V-0.01UF,25V,10%,X7RA
P3V3_STBY                C7F2             1        CAP_A_0402V-1.0UF,6.3V,10%,X6SA
P3V3_STBY                C8A4             1        CAP_0603LF-0.1UF,25V,10%,X7R,6A
P3V3_STBY                C8A6             1        CAP_0603-10UF,6.3V,20%,X6S,E15A
P3V3_STBY                C8C3             1        CAP_0603-10UF,6.3V,20%,X6S,E15A
P3V3_STBY                C8C4             1        CAP_0603-10UF,6.3V,20%,X6S,E15A
P3V3_STBY                C8C5             1        CAP_0603-10UF,6.3V,20%,X6S,E15A
P3V3_STBY                C8C6             1        CAP_0603-10UF,6.3V,20%,X6S,E15A
P3V3_STBY                C8D1             1        CAP_A_0402V-0.1UF,16V,10%,X7R,A
P3V3_STBY                C8D2             1        CAP_A_0402V-0.1UF,16V,10%,X7R,A
P3V3_STBY                C8D4             1        CAP_A_0402V-0.1UF,16V,10%,X7R,A
P3V3_STBY                C8E1             1        CAP_A_0402V-0.1UF,16V,10%,X7R,A
P3V3_STBY                C8E2             1        CAP_A_0402V-0.1UF,16V,10%,X7R,A
P3V3_STBY                C8E5             1        CAP_A_0402V-0.1UF,16V,10%,X7R,A
P3V3_STBY                C8E8             1        CAP_A_0402V-0.1UF,16V,10%,X7R,A
P3V3_STBY                C8E18            1        CAP_A_0402V-0.1UF,16V,10%,X7R,A
P3V3_STBY                C8F4             1        CAP_A_0402V-1.0UF,6.3V,10%,X6SA
P3V3_STBY                C8F5             1        CAP_A_0402V-0.01UF,25V,10%,X7RA
P3V3_STBY                C8F8             1        CAPP_3018-470UF,6.3V,20%,POSCAA
P3V3_STBY                C8F14            1        CAPP_3018-470UF,6.3V,20%,POSCAA
P3V3_STBY                C8F16            1        CAP_A_0402V-0.1UF,16V,10%,X7R,A
P3V3_STBY                C9A3             1        CAP_A_0402V-0.1UF,16V,10%,X7R,A
P3V3_STBY                C9B7             1        CAP_A_0402V-0.1UF,16V,10%,X7R,A
P3V3_STBY                C9E11            1        CAP_0402-1.0UF,16V,10%,X6S,D97A
P3V3_STBY                C9F2             1        CAP_1210-47UF,16V,20%,EMPTY,D3A
P3V3_STBY                C9F5             1        CAP_A_0402V-0.1UF,16V,10%,X7R,A
P3V3_STBY                C9F11            1        CAP_A_0402V-0.1UF,16V,10%,X7R,A
P3V3_STBY                C9F19            1        CAP_A_0402V-0.1UF,16V,10%,X7R,A
P3V3_STBY                C9F23            1        CAP_A_0402V-0.1UF,16V,10%,X7R,A
P3V3_STBY                C9G2             1        CAP_0402LF-470PF,50V,10%,X7R,AA
P3V3_STBY                C9G7             1        CAP_A_0402V-0.1UF,16V,10%,X7R,A
P3V3_STBY                C9M7             1        CAP_A_0402V-0.1UF,16V,10%,X7R,A
P3V3_STBY                C9P11            1        CAP_A_0402V-0.1UF,16V,10%,X7R,A
P3V3_STBY                C9R13            1        CAP_A_0402V-0.1UF,16V,10%,X7R,A
P3V3_STBY                C9R14            1        CAP_A_0402V-0.1UF,16V,10%,X7R,A
P3V3_STBY                CR2U1            1        DIODE2A_DUAL_SMLF-BAS70-05,DIOA
P3V3_STBY                CR3U1            2        DIODE_SMLF-1N5819HW,IC,D55839-A
P3V3_STBY                EU2T1            5        SLG55021_SM-IC,G56246-001
P3V3_STBY                EU8A2            7        RT9059_DFN-IC,H65765-001
P3V3_STBY                EU8A2            8        RT9059_DFN-IC,H65765-001
P3V3_STBY                EU8A2            9        RT9059_DFN-IC,H65765-001
P3V3_STBY                EU8A2            10       RT9059_DFN-IC,H65765-001
P3V3_STBY                EU9E1            10       SPRINGVILLE_SM1-IC,G47144-004
P3V3_STBY                EU9E1            27       SPRINGVILLE_SM1-IC,G47144-004
P3V3_STBY                EU9E1            41       SPRINGVILLE_SM1-IC,G47144-004
P3V3_STBY                EU9E1            64       SPRINGVILLE_SM1-IC,G47144-004
P3V3_STBY                EU9F1            10       RT9059_DFN-IC,H65765-001
P3V3_STBY                EU9F2            7        RT9059_DFN-IC,H65765-001
P3V3_STBY                EU9F2            8        RT9059_DFN-IC,H65765-001
P3V3_STBY                EU9F2            9        RT9059_DFN-IC,H65765-001
P3V3_STBY                EU9F2            10       RT9059_DFN-IC,H65765-001
P3V3_STBY                EU9F3            29       PI7C9X1172_QFN-IC,H66899-001
P3V3_STBY                FB1T2            1        FERRITE_SMLF-300,FB,693286-046
P3V3_STBY                FB1U1            1        FERRITE_SMLF-300,FB,693286-046
P3V3_STBY                FB1U2            1        FERRITE_SMLF-60,FB,693286-001
P3V3_STBY                FB2T2            1        FERRITE_SMLF-600,FB,656554-043
P3V3_STBY                J1F3             1        CONN8_H62179001_PIP-CONN,H6217A
P3V3_STBY                J4B2             A11      SCONN120_H61426002_SM-CONN,H61A
P3V3_STBY                J4B2             B11      SCONN120_H61426002_SM-CONN,H61A
P3V3_STBY                J4B2             C11      SCONN120_H61426002_SM-CONN,H61A
P3V3_STBY                J6B1             A11      SCONN120_H61426002_SM-CONN,H61A
P3V3_STBY                J6B1             B11      SCONN120_H61426002_SM-CONN,H61A
P3V3_STBY                J6B1             C11      SCONN120_H61426002_SM-CONN,H61A
P3V3_STBY                J8E1             7        SCONN11_H67026001_SM-CONN,H670A
P3V3_STBY                J8G1             25       SCONN200_H68296001_SM-CONN,H68A
P3V3_STBY                J9B3             12       SCONN120_A28699018_SM-SCONN,A2A
P3V3_STBY                J9B3             13       SCONN120_A28699018_SM-SCONN,A2A
P3V3_STBY                JA9G1            L2       CONN17_H71061002_PIP1-CONN,H71A
P3V3_STBY                L8F1             2        INDUCTOR_SM-1.00UH,IND,E98679-A
P3V3_STBY                Q8G1             5        MOSFET_N_LCC3-BSZ019N03LS,NFETA
P3V3_STBY                R1B1             1        RES_0402-1.00K,1%,1/16W,CHIP,GA
P3V3_STBY                R1B2             1        RES_0402-1.00K,1%,1/16W,CHIP,GA
P3V3_STBY                R1B13            1        RES_0402-2.26K,1.0%,1/16W,EMPTA
P3V3_STBY                R1B21            1        RES_0402-4.75K,1%,1/16W,CHIP,GA
P3V3_STBY                R1B24            1        RES_0402-4.75K,1%,1/16W,CHIP,GA
P3V3_STBY                R1C14            1        RES_0402-0.0,5%,1/16W,CHIP,G21A
P3V3_STBY                R1C18            1        RES_0402-2.26K,1.0%,1/16W,EMPTA
P3V3_STBY                R1C28            1        RES_0402-1.00K,1%,1/16W,CHIP,GA
P3V3_STBY                R1C34            1        RES_0402-10.0K,1%,1/16W,CHIP,GA
P3V3_STBY                R1C35            1        RES_0402-3.32K,1%,1/16W,EMPTY,A
P3V3_STBY                R1D6             1        RES_0402-1.00K,1%,1/16W,CHIP,GA
P3V3_STBY                R1D7             1        RES_0402-2.26K,1.0%,1/16W,CHIPA
P3V3_STBY                R1D8             1        RES_0402-1.00K,1%,1/16W,CHIP,GA
P3V3_STBY                R1D10            1        RES_0402-10.0K,1%,1/16W,CHIP,GA
P3V3_STBY                R1D21            1        RES_0402-4.75K,1%,1/16W,CHIP,GA
P3V3_STBY                R1D22            1        RES_0402-10.0K,1%,1/16W,CHIP,GA
P3V3_STBY                R1D23            1        RES_0402-10.0K,1%,1/16W,CHIP,GA
P3V3_STBY                R1D35            1        RES_0402-4.75K,1%,1/16W,CHIP,GA
P3V3_STBY                R1D53            1        RES_0402-2.26K,1.0%,1/16W,EMPTA
P3V3_STBY                R1E9             1        RES_0402-1.00K,1%,1/16W,CHIP,GA
P3V3_STBY                R1E10            1        RES_0402-1.00K,1%,1/16W,CHIP,GA
P3V3_STBY                R1E11            1        RES_0402-10.0K,1%,1/16W,EMPTY,A
P3V3_STBY                R1F1             1        RES_0402-4.75K,1%,1/16W,CHIP,GA
P3V3_STBY                R1G6             1        RES_0402-2.26K,1.0%,1/16W,EMPTA
P3V3_STBY                R1G11            1        RES_0402-1.00K,1%,1/16W,CHIP,GA
P3V3_STBY                R1G16            1        RES_0402-1.00K,1%,1/16W,CHIP,GA
P3V3_STBY                R1L5             1        RES_0402-1.00K,1%,1/16W,CHIP,GA
P3V3_STBY                R1L7             1        RES_0402-4.75K,1%,1/16W,CHIP,GA
P3V3_STBY                R1L13            2        RES_0402-1.00K,1%,1/16W,CHIP,GA
P3V3_STBY                R1L19            1        RES_0402-4.75K,1%,1/16W,EMPTY,A
P3V3_STBY                R1L23            2        RES_0402-1.00K,1%,1/16W,CHIP,GA
P3V3_STBY                R1L27            1        RES_0402-4.75K,1%,1/16W,CHIP,GA
P3V3_STBY                R1L28            1        RES_0402-4.75K,1%,1/16W,CHIP,GA
P3V3_STBY                R1L33            2        RES_0402-221,1.0%,1/16W,CHIP,GA
P3V3_STBY                R1L36            1        RES_0402-1.00K,1%,1/16W,CHIP,GA
P3V3_STBY                R1L38            1        RES_0402-1.00K,1%,1/16W,CHIP,GA
P3V3_STBY                R1L43            2        RES_0402-330,5%,1/16W,CHIP,G21A
P3V3_STBY                R1L44            2        RES_0402-330,5%,1/16W,CHIP,G21A
P3V3_STBY                R1M24            1        RES_0402-10.0K,1%,1/16W,CHIP,GA
P3V3_STBY                R1R3             1        RES_0402-3.32K,1%,1/16W,CHIP,GA
P3V3_STBY                R1R4             1        RES_0402-10.0K,1%,1/16W,CHIP,GA
P3V3_STBY                R1R5             1        RES_0402-4.75K,1%,1/16W,CHIP,GA
P3V3_STBY                R1R7             1        RES_0402-20.0K,1%,1/16W,CHIP,GA
P3V3_STBY                R1R9             1        RES_0402-3.32K,1%,1/16W,CHIP,GA
P3V3_STBY                R1R10            1        RES_0402-10.0K,1%,1/16W,CHIP,GA
P3V3_STBY                R1R11            2        RES_0402-4.75K,1%,1/16W,CHIP,GA
P3V3_STBY                R1R13            1        RES_0402-10.0K,1%,1/16W,CHIP,GA
P3V3_STBY                R1R16            1        RES_0402-2.21K,1%,1/16W,CHIP,GA
P3V3_STBY                R1R17            1        RES_0402-2.21K,1%,1/16W,CHIP,GA
P3V3_STBY                R1R18            1        RES_0402-2.21K,1%,1/16W,CHIP,GA
P3V3_STBY                R1R19            1        RES_0402-2.21K,1%,1/16W,CHIP,GA
P3V3_STBY                R1R20            1        RES_0402-2.21K,1%,1/16W,CHIP,GA
P3V3_STBY                R1R21            1        RES_0402-2.21K,1%,1/16W,CHIP,GA
P3V3_STBY                R1R22            1        RES_0402-2.21K,1%,1/16W,CHIP,GA
P3V3_STBY                R1R23            1        RES_0402-2.21K,1%,1/16W,CHIP,GA
P3V3_STBY                R1T2             1        RES_0402-665,1.0%,1/16W,CHIP,GA
P3V3_STBY                R1T3             1        RES_0402-665,1.0%,1/16W,CHIP,GA
P3V3_STBY                R1T4             1        RES_0402-2.7K,1%,1/16W,CHIP,G2A
P3V3_STBY                R1T5             1        RES_0402-2.7K,1%,1/16W,EMPTY,GA
P3V3_STBY                R1T6             1        RES_0402-2.7K,1%,1/16W,EMPTY,GA
P3V3_STBY                R1T13            2        RES_0402-4.75K,1%,1/16W,EMPTY,A
P3V3_STBY                R1T14            2        RES_0402-4.75K,1%,1/16W,CHIP,GA
P3V3_STBY                R1T16            2        RES_0402-4.75K,1%,1/16W,EMPTY,A
P3V3_STBY                R1T17            2        RES_0402-4.75K,1%,1/16W,EMPTY,A
P3V3_STBY                R1T18            2        RES_0402-4.75K,1%,1/16W,EMPTY,A
P3V3_STBY                R1T19            2        RES_0402-4.75K,1%,1/16W,EMPTY,A
P3V3_STBY                R1T20            2        RES_0402-4.75K,1%,1/16W,EMPTY,A
P3V3_STBY                R1T21            2        RES_0402-4.75K,1%,1/16W,EMPTY,A
P3V3_STBY                R1T22            2        RES_0402-4.75K,1%,1/16W,EMPTY,A
P3V3_STBY                R1T34            1        RES_0603-0,5.0%,1/10W,CHIP,G22A
P3V3_STBY                R1U21            1        RES_0402-2.7K,1%,1/16W,CHIP,G2A
P3V3_STBY                R1U22            1        RES_0402-2.7K,1%,1/16W,CHIP,G2A
P3V3_STBY                R1U23            1        RES_0402-2.7K,1%,1/16W,EMPTY,GA
P3V3_STBY                R1U24            1        RES_0402-2.7K,1%,1/16W,EMPTY,GA
P3V3_STBY                R1U39            1        RES_0402-5.11K,1%,1/16W,CHIP,GA
P3V3_STBY                R1U49            1        RES_0402-2.7K,1%,1/16W,CHIP,G2A
P3V3_STBY                R1U52            1        RES_0402-1.5K,1%,1/16W,CHIP,G2A
P3V3_STBY                R2L4             1        RES_0402-2.0K,1%,1/16W,CHIP,G2A
P3V3_STBY                R2L5             1        RES_0402-2.0K,1%,1/16W,CHIP,G2A
P3V3_STBY                R2L6             1        RES_0402-2.0K,1%,1/16W,CHIP,G2A
P3V3_STBY                R2L11            1        RES_0402-2.0K,1%,1/16W,CHIP,G2A
P3V3_STBY                R2L12            1        RES_0402-2.0K,1%,1/16W,CHIP,G2A
P3V3_STBY                R2L14            1        RES_0402-0.0,5%,1/16W,CHIP,G21A
P3V3_STBY                R2L15            1        RES_0402-2.0K,1%,1/16W,CHIP,G2A
P3V3_STBY                R2L24            1        RES_0402-2.26K,1.0%,1/16W,EMPTA
P3V3_STBY                R2L25            1        RES_0402-100.0K,1%,1/16W,EMPTYA
P3V3_STBY                R2L26            1        RES_0402-100.0K,1%,1/16W,EMPTYA
P3V3_STBY                R2M2             1        RES_0402-4.75K,1%,1/16W,CHIP,GA
P3V3_STBY                R2M4             1        RES_0402-1.00K,1%,1/16W,CHIP,GA
P3V3_STBY                R2M5             1        RES_0402-4.75K,1%,1/16W,CHIP,GA
P3V3_STBY                R2M8             1        RES_0402-1.5K,1%,1/16W,CHIP,G2A
P3V3_STBY                R2N5             1        RES_0402-665,1.0%,1/16W,CHIP,GA
P3V3_STBY                R2N6             1        RES_0402-10.0K,1%,1/16W,CHIP,GA
P3V3_STBY                R2N7             1        RES_0402-4.75K,1%,1/16W,CHIP,GA
P3V3_STBY                R2N8             1        RES_0402-665,1.0%,1/16W,CHIP,GA
P3V3_STBY                R2N9             1        RES_0402-10.0K,1%,1/16W,CHIP,GA
P3V3_STBY                R2N10            1        RES_0402-4.75K,1%,1/16W,CHIP,GA
P3V3_STBY                R2N14            1        RES_0402-1.00K,1%,1/16W,EMPTY,A
P3V3_STBY                R2N16            1        RES_0402-10.0K,1%,1/16W,CHIP,GA
P3V3_STBY                R2N17            1        RES_0402-2.7K,1%,1/16W,EMPTY,GA
P3V3_STBY                R2N23            1        RES_0402-10.0K,1%,1/16W,CHIP,GA
P3V3_STBY                R2N28            1        RES_0402-10.0K,1%,1/16W,CHIP,GA
P3V3_STBY                R2N29            1        RES_0402-1.5K,1%,1/16W,CHIP,G2A
P3V3_STBY                R2N32            1        RES_0402-4.75K,1%,1/16W,CHIP,GA
P3V3_STBY                R2P3             1        RES_0402-4.75K,1%,1/16W,CHIP,GA
P3V3_STBY                R2P5             1        RES_0402-4.75K,1%,1/16W,CHIP,GA
P3V3_STBY                R2P8             1        RES_0402-560,5%,1/16W,CHIP,G21A
P3V3_STBY                R2P13            1        RES_0402-4.75K,1%,1/16W,CHIP,GA
P3V3_STBY                R2P16            1        RES_0402-10.0K,1%,1/16W,CHIP,GA
P3V3_STBY                R2P17            1        RES_0402-4.75K,1%,1/16W,CHIP,GA
P3V3_STBY                R2P18            1        RES_0402-10.0K,1%,1/16W,CHIP,GA
P3V3_STBY                R2P19            1        RES_0402-10.0K,1%,1/16W,CHIP,GA
P3V3_STBY                R2P21            1        RES_0402-10.0K,1%,1/16W,CHIP,GA
P3V3_STBY                R2P22            1        RES_0402-10.0K,1%,1/16W,CHIP,GA
P3V3_STBY                R2R1             1        RES_0402-10.0K,1%,1/16W,CHIP,GA
P3V3_STBY                R2R3             1        RES_0402-10.0K,1%,1/16W,CHIP,GA
P3V3_STBY                R2R5             1        RES_0402-1.00K,1%,1/16W,CHIP,GA
P3V3_STBY                R2R7             1        RES_0402-4.75K,1%,1/16W,CHIP,GA
P3V3_STBY                R2T3             1        RES_0402-4.75K,1%,1/16W,CHIP,GA
P3V3_STBY                R2T4             1        RES_0402-1.0K,0.1%,1/16W,CHIP,A
P3V3_STBY                R2T5             1        RES_0402-1.00K,1%,1/16W,CHIP,GA
P3V3_STBY                R2T6             1        RES_0402-4.75K,1%,1/16W,CHIP,GA
P3V3_STBY                R2T7             1        RES_0402-1.00K,1%,1/16W,CHIP,GA
P3V3_STBY                R2T8             1        RES_0402-10.0K,1%,1/16W,CHIP,GA
P3V3_STBY                R2T11            1        RES_0402-4.75K,1%,1/16W,CHIP,GA
P3V3_STBY                R2T22            1        RES_0402-10.0K,1%,1/16W,CHIP,GA
P3V3_STBY                R2T29            1        RES_0402-2.21K,1%,1/16W,CHIP,GA
P3V3_STBY                R2T34            1        RES_0402-4.75K,1%,1/16W,CHIP,GA
P3V3_STBY                R2T35            1        RES_0402-4.75K,1%,1/16W,CHIP,GA
P3V3_STBY                R2T53            1        RES_0402-665,1.0%,1/16W,CHIP,GA
P3V3_STBY                R2T54            1        RES_0402-665,1.0%,1/16W,CHIP,GA
P3V3_STBY                R2U2             1        RES_0402-4.75K,1%,1/16W,CHIP,GA
P3V3_STBY                R2U3             1        RES_0402-665,1.0%,1/16W,CHIP,GA
P3V3_STBY                R2U4             1        RES_0402-4.75K,1%,1/16W,CHIP,GA
P3V3_STBY                R2U5             1        RES_0402-2.26K,1.0%,1/16W,CHIPA
P3V3_STBY                R2U11            1        RES_0402-665,1.0%,1/16W,CHIP,GA
P3V3_STBY                R2U13            1        RES_0402-2.26K,1.0%,1/16W,CHIPA
P3V3_STBY                R2U30            1        RES_0402-4.75K,1%,1/16W,CHIP,GA
P3V3_STBY                R2U38            1        RES_0402-665,1.0%,1/16W,CHIP,GA
P3V3_STBY                R2U39            1        RES_0402-665,1.0%,1/16W,CHIP,GA
P3V3_STBY                R2U48            1        RES_0402-4.75K,1%,1/16W,CHIP,GA
P3V3_STBY                R3M1             1        RES_0402-0.0,5%,1/16W,CHIP,G21A
P3V3_STBY                R3M5             1        RES_0402-100.0K,1%,1/16W,EMPTYA
P3V3_STBY                R3N2             1        RES_0402-4.75K,1%,1/16W,EMPTY,A
P3V3_STBY                R3N10            1        RES_0402-10.0K,1%,1/16W,CHIP,GA
P3V3_STBY                R3N11            1        RES_0402-4.75K,1%,1/16W,CHIP,GA
P3V3_STBY                R3N12            1        RES_0402-4.75K,1%,1/16W,CHIP,GA
P3V3_STBY                R3N13            1        RES_0402-4.75K,1%,1/16W,CHIP,GA
P3V3_STBY                R3N17            1        RES_0402-1.00K,1%,1/16W,EMPTY,A
P3V3_STBY                R3N23            1        RES_0402-2.26K,1.0%,1/16W,EMPTA
P3V3_STBY                R3P18            1        RES_0402-1.00K,1%,1/16W,CHIP,GA
P3V3_STBY                R3P21            1        RES_0402-100.0K,1%,1/16W,EMPTYA
P3V3_STBY                R3P22            1        RES_0402-0.0,5%,1/16W,CHIP,G21A
P3V3_STBY                R3P25            1        RES_0402-1.00K,1%,1/16W,CHIP,GA
P3V3_STBY                R3P36            1        RES_0402-1.00K,1%,1/16W,CHIP,GA
P3V3_STBY                R3P44            1        RES_0402-4.75K,1%,1/16W,CHIP,GA
P3V3_STBY                R3P50            1        RES_0402-10.0K,1%,1/16W,EMPTY,A
P3V3_STBY                R3P54            1        RES_0402-3.32K,1%,1/16W,EMPTY,A
P3V3_STBY                R3P61            1        RES_0402-2.26K,1.0%,1/16W,CHIPA
P3V3_STBY                R3P62            1        RES_0402-4.75K,1%,1/16W,EMPTY,A
P3V3_STBY                R3R15            1        RES_0402-1.00K,1%,1/16W,CHIP,GA
P3V3_STBY                R3T3             1        RES_0402-4.75K,1%,1/16W,EMPTY,A
P3V3_STBY                R3T4             1        RES_0402-10.0K,1%,1/16W,CHIP,GA
P3V3_STBY                R3T5             1        RES_0402-4.75K,1%,1/16W,CHIP,GA
P3V3_STBY                R3T12            1        RES_0402-10.0K,1%,1/16W,CHIP,GA
P3V3_STBY                R3T13            1        RES_0402-0.0,5%,1/16W,CHIP,G21A
P3V3_STBY                R4B10            1        RES_0402-1.00K,1%,1/16W,CHIP,GA
P3V3_STBY                R4C8             1        RES_0402-1.00K,1%,1/16W,CHIP,GA
P3V3_STBY                R4D26            1        RES_0402-0.0,5%,1/16W,CHIP,G21A
P3V3_STBY                R4D31            1        RES_0402-2.26K,1.0%,1/16W,EMPTA
P3V3_STBY                R4D42            1        RES_0402-1.00K,1%,1/16W,CHIP,GA
P3V3_STBY                R4D47            1        RES_0402-0.0,5%,1/16W,CHIP,G21A
P3V3_STBY                R4D49            1        RES_0402-1.00K,1%,1/16W,CHIP,GA
P3V3_STBY                R4D58            1        RES_0402-1.00K,1%,1/16W,CHIP,GA
P3V3_STBY                R4E3             1        RES_0402-1.00K,1%,1/16W,CHIP,GA
P3V3_STBY                R4E4             1        RES_0402-2.26K,1.0%,1/16W,CHIPA
P3V3_STBY                R4E5             1        RES_0402-1.00K,1%,1/16W,CHIP,GA
P3V3_STBY                R4E20            1        RES_0402-2.26K,1.0%,1/16W,EMPTA
P3V3_STBY                R4G14            1        RES_0402-1.00K,1%,1/16W,CHIP,GA
P3V3_STBY                R4R5             1        RES_0402-4.75K,1%,1/16W,CHIP,GA
P3V3_STBY                R4U1             1        RES_0402-4.75K,1%,1/16W,CHIP,GA
P3V3_STBY                R5N1             1        RES_0402-10.0K,1%,1/16W,CHIP,GA
P3V3_STBY                R5N2             1        RES_0402-1.8K,1%,1/16W,CHIP,G2A
P3V3_STBY                R5N3             1        RES_0402-10.0K,1%,1/16W,CHIP,GA
P3V3_STBY                R5N4             1        RES_0402-1.8K,1%,1/16W,CHIP,G2A
P3V3_STBY                R5N5             1        RES_0402-10.0K,1%,1/16W,CHIP,GA
P3V3_STBY                R6P32            1        RES_0402-2.0K,1%,1/16W,EMPTY,GA
P3V3_STBY                R6P37            1        RES_0402-2.0K,1%,1/16W,EMPTY,GA
P3V3_STBY                R6P39            1        RES_0402-4.75K,1%,1/16W,CHIP,GA
P3V3_STBY                R6P40            1        RES_0402-100.0K,1%,1/16W,EMPTYA
P3V3_STBY                R6P49            1        RES_0402-2.26K,1.0%,1/16W,EMPTA
P3V3_STBY                R7A9             1        RES_0402-2.26K,1.0%,1/16W,EMPTA
P3V3_STBY                R7B4             1        RES_0402-1.00K,1%,1/16W,CHIP,GA
P3V3_STBY                R7B5             1        RES_0402-1.00K,1%,1/16W,CHIP,GA
P3V3_STBY                R7B6             1        RES_0402-10.0K,1%,1/16W,CHIP,GA
P3V3_STBY                R7B17            1        RES_0402-1.00K,1%,1/16W,CHIP,GA
P3V3_STBY                R7C5             1        RES_0402-10.0K,1%,1/16W,CHIP,GA
P3V3_STBY                R7C8             1        RES_0402-10.0K,1%,1/16W,CHIP,GA
P3V3_STBY                R7C13            1        RES_0402-10.0K,1%,1/16W,CHIP,GA
P3V3_STBY                R7C23            1        RES_0402-10.0K,1%,1/16W,CHIP,GA
P3V3_STBY                R7D2             1        RES_0402-1.00K,1%,1/16W,CHIP,GA
P3V3_STBY                R7D3             1        RES_0402-4.75K,1%,1/16W,CHIP,GA
P3V3_STBY                R7D4             1        RES_0402-10.0K,1%,1/16W,CHIP,GA
P3V3_STBY                R7D5             1        RES_0402-2.26K,1.0%,1/16W,CHIPA
P3V3_STBY                R7D6             1        RES_0402-4.75K,1%,1/16W,CHIP,GA
P3V3_STBY                R7D7             1        RES_0402-1.00K,1%,1/16W,CHIP,GA
P3V3_STBY                R7D8             1        RES_0402-10.0K,1%,1/16W,CHIP,GA
P3V3_STBY                R7D9             1        RES_0402-2.26K,1.0%,1/16W,CHIPA
P3V3_STBY                R7D10            1        RES_0402-10.0K,1%,1/16W,CHIP,GA
P3V3_STBY                R7D12            1        RES_0402-10.0K,1%,1/16W,CHIP,GA
P3V3_STBY                R7D13            1        RES_0402-8.2K,1%,1/16W,EMPTY,GA
P3V3_STBY                R7D30            1        RES_0402-4.75K,1%,1/16W,CHIP,GA
P3V3_STBY                R7D42            1        RES_0402-4.75K,1%,1/16W,CHIP,GA
P3V3_STBY                R7E5             1        RES_0402-10.0K,1%,1/16W,CHIP,GA
P3V3_STBY                R7E6             1        RES_0402-10.0K,1%,1/16W,CHIP,GA
P3V3_STBY                R7E18            1        RES_0402-4.75K,1%,1/16W,CHIP,GA
P3V3_STBY                R7E19            1        RES_0402-1.00K,1%,1/16W,EMPTY,A
P3V3_STBY                R7F5             1        RES_0402-4.75K,1%,1/16W,CHIP,GA
P3V3_STBY                R7F6             1        RES_0402-4.75K,1%,1/16W,EMPTY,A
P3V3_STBY                R7F19            1        RES_0402-1.00K,1%,1/16W,CHIP,GA
P3V3_STBY                R7F20            1        RES_0402-100.0K,1%,1/16W,EMPTYA
P3V3_STBY                R7F22            1        RES_0402-1.00K,1%,1/16W,CHIP,GA
P3V3_STBY                R7F27            1        RES_0402-1.00K,1%,1/16W,CHIP,GA
P3V3_STBY                R7F28            1        RES_0402-10.0K,1%,1/16W,CHIP,GA
P3V3_STBY                R7F32            1        RES_0402-10.0K,1%,1/16W,CHIP,GA
P3V3_STBY                R7F36            1        RES_0402-2.26K,1.0%,1/16W,EMPTA
P3V3_STBY                R7G22            1        RES_0402-10.0K,1%,1/16W,CHIP,GA
P3V3_STBY                R7G23            1        RES_0402-10.0K,1%,1/16W,CHIP,GA
P3V3_STBY                R7G26            1        RES_0402-10.0K,1%,1/16W,CHIP,GA
P3V3_STBY                R7G27            1        RES_0402-1.00K,1%,1/16W,CHIP,GA
P3V3_STBY                R7G31            1        RES_0402-1.00K,1%,1/16W,CHIP,GA
P3V3_STBY                R8A5             1        RES_0402-1.00K,1%,1/16W,CHIP,GA
P3V3_STBY                R8A6             1        RES_0402-1.00K,1%,1/16W,CHIP,GA
P3V3_STBY                R8A7             1        RES_0402-100.0K,1%,1/16W,EMPTYA
P3V3_STBY                R8A10            1        RES_0402-5.11K,1%,1/16W,CHIP,GA
P3V3_STBY                R8B23            1        RES_0402-1.00K,1%,1/16W,CHIP,GA
P3V3_STBY                R8B24            1        RES_0402-3.3K,5%,1/16W,CHIP,G2A
P3V3_STBY                R8B25            1        RES_0402-4.75K,1%,1/16W,CHIP,GA
P3V3_STBY                R8B26            1        RES_0402-3.3K,5%,1/16W,CHIP,G2A
P3V3_STBY                R8B30            1        RES_0402-1.00K,1%,1/16W,CHIP,GA
P3V3_STBY                R8B31            1        RES_0402-4.75K,1%,1/16W,CHIP,GA
P3V3_STBY                R8C1             1        RES_0402-4.75K,1%,1/16W,CHIP,GA
P3V3_STBY                R8C2             1        RES_0402-4.75K,1%,1/16W,CHIP,GA
P3V3_STBY                R8C4             1        RES_0402-1.00K,1%,1/16W,CHIP,GA
P3V3_STBY                R8C6             1        RES_0402-4.75K,1%,1/16W,CHIP,GA
P3V3_STBY                R8C7             1        RES_0402-4.75K,1%,1/16W,CHIP,GA
P3V3_STBY                R8C9             1        RES_0402-4.75K,1%,1/16W,CHIP,GA
P3V3_STBY                R8C15            1        RES_0402-2.0K,1%,1/16W,CHIP,G2A
P3V3_STBY                R8C16            1        RES_0402-2.0K,1%,1/16W,CHIP,G2A
P3V3_STBY                R8C18            1        RES_0402-1.00K,1%,1/16W,CHIP,GA
P3V3_STBY                R8C25            1        RES_0402-4.75K,1%,1/16W,CHIP,GA
P3V3_STBY                R8D13            1        RES_0402-10.0K,1%,1/16W,CHIP,GA
P3V3_STBY                R8D14            1        RES_0402-4.75K,1%,1/16W,CHIP,GA
P3V3_STBY                R8D15            1        RES_0402-1.37K,1%,1/16W,CHIP,GA
P3V3_STBY                R8D16            1        RES_0402-10.0K,1%,1/16W,EMPTY,A
P3V3_STBY                R8D17            1        RES_0402-1.37K,1%,1/16W,CHIP,GA
P3V3_STBY                R8D21            1        RES_0402-1.00K,1%,1/16W,CHIP,GA
P3V3_STBY                R8D25            1        RES_0402-4.75K,1%,1/16W,CHIP,GA
P3V3_STBY                R8D26            1        RES_0402-4.75K,1%,1/16W,CHIP,GA
P3V3_STBY                R8D28            1        RES_0402-1.00K,1%,1/16W,CHIP,GA
P3V3_STBY                R8D29            1        RES_0402-4.75K,1%,1/16W,CHIP,GA
P3V3_STBY                R8D31            1        RES_0402-4.75K,1%,1/16W,CHIP,GA
P3V3_STBY                R8D41            1        RES_0402-10.0K,1%,1/16W,CHIP,GA
P3V3_STBY                R8D44            1        RES_0402-10.0K,1%,1/16W,CHIP,GA
P3V3_STBY                R8E3             1        RES_0402-10.0K,1%,1/16W,CHIP,GA
P3V3_STBY                R8E6             1        RES_0402-1.00K,1%,1/16W,EMPTY,A
P3V3_STBY                R8E12            1        RES_0402-4.75K,1%,1/16W,EMPTY,A
P3V3_STBY                R8E14            1        RES_0402-4.75K,1%,1/16W,CHIP,GA
P3V3_STBY                R8E19            1        RES_0402-4.75K,1%,1/16W,EMPTY,A
P3V3_STBY                R8E22            1        RES_0402-4.75K,1%,1/16W,CHIP,GA
P3V3_STBY                R8E23            2        RES_0402-4.75K,1%,1/16W,CHIP,GA
P3V3_STBY                R8E25            1        RES_0402-0.0,5%,1/16W,CHIP,G21A
P3V3_STBY                R8E30            1        RES_0402-10.0K,1%,1/16W,CHIP,GA
P3V3_STBY                R8E32            1        RES_0402-4.75K,1%,1/16W,CHIP,GA
P3V3_STBY                R8E36            1        RES_0402-10.0K,1%,1/16W,CHIP,GA
P3V3_STBY                R8E40            1        RES_0402-100.0K,1%,1/16W,EMPTYA
P3V3_STBY                R8F5             1        RES_0402-1.00K,1%,1/16W,CHIP,GA
P3V3_STBY                R8F13            1        RES_0402-4.75K,1%,1/16W,CHIP,GA
P3V3_STBY                R8F14            1        RES_0402-4.75K,1%,1/16W,CHIP,GA
P3V3_STBY                R8F16            1        RES_0402-4.75K,1%,1/16W,EMPTY,A
P3V3_STBY                R8F23            1        RES_0402-2.21K,1%,1/16W,CHIP,GA
P3V3_STBY                R8F24            1        RES_0402-4.75K,1%,1/16W,CHIP,GA
P3V3_STBY                R8F26            1        RES_0402-10.0K,1%,1/16W,CHIP,GA
P3V3_STBY                R8F32            1        RES_0402-10.0K,1%,1/16W,CHIP,GA
P3V3_STBY                R8F34            1        RES_0402-4.75K,1%,1/16W,CHIP,GA
P3V3_STBY                R8G2             1        RES_0402-4.75K,1%,1/16W,CHIP,GA
P3V3_STBY                R8G3             1        RES_0402-2.26K,1.0%,1/16W,EMPTA
P3V3_STBY                R8G6             1        RES_0402-2.26K,1.0%,1/16W,EMPTA
P3V3_STBY                R8G20            1        RES_0402-10.0K,1%,1/16W,CHIP,GA
P3V3_STBY                R8N1             1        RES_0402-1.8K,1%,1/16W,CHIP,G2A
P3V3_STBY                R8N2             1        RES_0402-10.0K,1%,1/16W,CHIP,GA
P3V3_STBY                R8N3             1        RES_0402-10.0K,1%,1/16W,CHIP,GA
P3V3_STBY                R8N4             1        RES_0402-1.8K,1%,1/16W,CHIP,G2A
P3V3_STBY                R8N5             1        RES_0402-10.0K,1%,1/16W,CHIP,GA
P3V3_STBY                R9A7             1        RES_0402-2.21K,1%,1/16W,CHIP,GA
P3V3_STBY                R9A12            2        RES_0402-2.21K,1%,1/16W,CHIP,GA
P3V3_STBY                R9A14            2        RES_0402-1.00K,1%,1/16W,CHIP,GA
P3V3_STBY                R9A16            2        RES_0402-2.21K,1%,1/16W,CHIP,GA
P3V3_STBY                R9A18            1        RES_0402-4.75K,1%,1/16W,CHIP,GA
P3V3_STBY                R9A20            2        RES_0402-221,1.0%,1/16W,CHIP,GA
P3V3_STBY                R9A21            1        RES_0402-4.75K,1%,1/16W,CHIP,GA
P3V3_STBY                R9B6             1        RES_0402-1.00K,1%,1/16W,CHIP,GA
P3V3_STBY                R9E1             1        RES_0402-10.0K,1%,1/16W,CHIP,GA
P3V3_STBY                R9E2             1        RES_0402-10.0K,1%,1/16W,CHIP,GA
P3V3_STBY                R9E3             1        RES_0402-10.0K,1%,1/16W,CHIP,GA
P3V3_STBY                R9E4             1        RES_0402-10.0K,1%,1/16W,CHIP,GA
P3V3_STBY                R9E7             1        RES_0402-3.32K,1%,1/16W,CHIP,GA
P3V3_STBY                R9E21            1        RES_0402-4.75K,1%,1/16W,CHIP,GA
P3V3_STBY                R9E22            2        RES_0402-10.0K,1%,1/16W,CHIP,GA
P3V3_STBY                R9E24            2        RES_0402-221,1.0%,1/16W,CHIP,GA
P3V3_STBY                R9F3             1        RES_0402-4.75K,1%,1/16W,CHIP,GA
P3V3_STBY                R9F5             1        RES_0402-3.32K,1%,1/16W,CHIP,GA
P3V3_STBY                R9F9             2        RES_0402-4.75K,1%,1/16W,CHIP,GA
P3V3_STBY                R9F10            2        RES_0402-4.75K,1%,1/16W,EMPTY,A
P3V3_STBY                R9F12            1        RES_0402-10.0K,1%,1/16W,CHIP,GA
P3V3_STBY                R9F13            1        RES_0402-10.0K,1%,1/16W,CHIP,GA
P3V3_STBY                R9F14            2        RES_0402-4.75K,1%,1/16W,CHIP,GA
P3V3_STBY                R9F15            2        RES_0402-4.75K,1%,1/16W,CHIP,GA
P3V3_STBY                R9F16            2        RES_0402-4.75K,1%,1/16W,CHIP,GA
P3V3_STBY                R9F17            2        RES_0402-4.75K,1%,1/16W,EMPTY,A
P3V3_STBY                R9F18            2        RES_0402-4.75K,1%,1/16W,EMPTY,A
P3V3_STBY                R9F19            2        RES_0402-4.75K,1%,1/16W,EMPTY,A
P3V3_STBY                R9F28            1        RES_0402-221,1.0%,1/16W,CHIP,GA
P3V3_STBY                R9F30            1        RES_0402-4.75K,1%,1/16W,CHIP,GA
P3V3_STBY                R9F35            2        RES_0402-4.75K,1%,1/16W,CHIP,GA
P3V3_STBY                R9F36            2        RES_0402-4.75K,1%,1/16W,EMPTY,A
P3V3_STBY                R9F37            2        RES_0402-4.75K,1%,1/16W,EMPTY,A
P3V3_STBY                R9F38            2        RES_0402-4.75K,1%,1/16W,EMPTY,A
P3V3_STBY                R9F39            2        RES_0402-4.75K,1%,1/16W,EMPTY,A
P3V3_STBY                R9F40            2        RES_0402-4.75K,1%,1/16W,CHIP,GA
P3V3_STBY                R9F47            1        RES_0402-4.75K,1%,1/16W,CHIP,GA
P3V3_STBY                R9F48            1        RES_0402-4.75K,1%,1/16W,EMPTY,A
P3V3_STBY                R9F49            1        RES_0402-4.75K,1%,1/16W,EMPTY,A
P3V3_STBY                R9F52            1        RES_0402-4.75K,1%,1/16W,CHIP,GA
P3V3_STBY                R9F55            1        RES_0402-4.75K,1%,1/16W,CHIP,GA
P3V3_STBY                R9F61            1        RES_0402-10.0K,1%,1/16W,CHIP,GA
P3V3_STBY                R9G4             2        RES_0402-0.0,5%,1/16W,CHIP,G21A
P3V3_STBY                R9G21            1        RES_0402-4.75K,1%,1/16W,CHIP,GA
P3V3_STBY                R9G23            1        RES_0402-4.75K,1%,1/16W,EMPTY,A
P3V3_STBY                R9G25            1        RES_0402-4.75K,1%,1/16W,EMPTY,A
P3V3_STBY                R9G35            1        RES_0402-2.7K,1%,1/16W,CHIP,G2A
P3V3_STBY                R9M3             1        RES_0402-0.0,5%,1/16W,CHIP,G21A
P3V3_STBY                R9M5             1        RES_0402-100.0K,1%,1/16W,EMPTYA
P3V3_STBY                R9M16            1        RES_0402-2.0K,1%,1/16W,CHIP,G2A
P3V3_STBY                R9M17            1        RES_0402-2.0K,1%,1/16W,CHIP,G2A
P3V3_STBY                R9P4             1        RES_0402-2.7K,1%,1/16W,CHIP,G2A
P3V3_STBY                R9P5             1        RES_0402-10.0K,1%,1/16W,CHIP,GA
P3V3_STBY                R9P6             1        RES_0402-10.0K,1%,1/16W,CHIP,GA
P3V3_STBY                R9P10            1        RES_0402-10.0K,1%,1/16W,CHIP,GA
P3V3_STBY                R9P20            1        RES_0402-2.7K,1%,1/16W,CHIP,G2A
P3V3_STBY                R9T5             1        RES_0402-4.75K,1%,1/16W,CHIP,GA
P3V3_STBY                R9U8             1        RES_0402-100.0K,1%,1/16W,EMPTYA
P3V3_STBY                R9U10            1        RES_0402-0.0,5%,1/16W,CHIP,G21A
P3V3_STBY                U1B2             8        PCA9517_SM-IC,G77073-001-GND=GA
P3V3_STBY                U1E1             8        TMP421_TSSOP-IC,G62962-001
P3V3_STBY                U1M2             5        NC7SB3157_SMLF-IC,C99406-001
P3V3_STBY                U1M7             5        NC7SB3157_SMLF-IC,C99406-001
P3V3_STBY                U2D1             CY55     SKX_EXT_B_BGA1-IC,TBD
P3V3_STBY                U2M1             5        NC7SB3157_SMLF-IC,C99406-001
P3V3_STBY                U2T1             16       PI3B3257A_TSSOPLF-IC,E16801-001
P3V3_STBY                U3P1             14       GTL2014_SM-IC,D66151-001
P3V3_STBY                U3T1             2        W25Q256_XSOI-IC,H25002-001
P3V3_STBY                U4C2             14       GTL2014_SM-IC,D66151-001
P3V3_STBY                U5D1             CY55     SKX_EXT_B_BGA1-IC,TBD
P3V3_STBY                U7C1             AD24     LBG_CORE_QAT_EXT_D_BGA1-IC,H91A
P3V3_STBY                U7C1             AG29     LBG_CORE_QAT_EXT_D_BGA1-IC,H91A
P3V3_STBY                U7C1             AH24     LBG_CORE_QAT_EXT_D_BGA1-IC,H91A
P3V3_STBY                U7C1             AN24     LBG_CORE_QAT_EXT_D_BGA1-IC,H91A
P3V3_STBY                U7C1             AR24     LBG_CORE_QAT_EXT_D_BGA1-IC,H91A
P3V3_STBY                U7C1             AU24     LBG_CORE_QAT_EXT_D_BGA1-IC,H91A
P3V3_STBY                U7C1             AU27     LBG_CORE_QAT_EXT_D_BGA1-IC,H91A
P3V3_STBY                U7C1             AW24     LBG_CORE_QAT_EXT_D_BGA1-IC,H91A
P3V3_STBY                U7C1             BA24     LBG_CORE_QAT_EXT_D_BGA1-IC,H91A
P3V3_STBY                U7C1             BA26     LBG_CORE_QAT_EXT_D_BGA1-IC,H91A
P3V3_STBY                U7C1             BA43     LBG_CORE_QAT_EXT_D_BGA1-IC,H91A
P3V3_STBY                U7C1             BA45     LBG_CORE_QAT_EXT_D_BGA1-IC,H91A
P3V3_STBY                U7C1             BA46     LBG_CORE_QAT_EXT_D_BGA1-IC,H91A
P3V3_STBY                U7C1             BA48     LBG_CORE_QAT_EXT_D_BGA1-IC,H91A
P3V3_STBY                U7C1             BB26     LBG_CORE_QAT_EXT_D_BGA1-IC,H91A
P3V3_STBY                U7C1             BE26     LBG_CORE_QAT_EXT_D_BGA1-IC,H91A
P3V3_STBY                U7C1             BE40     LBG_CORE_QAT_EXT_D_BGA1-IC,H91A
P3V3_STBY                U7C1             BE44     LBG_CORE_QAT_EXT_D_BGA1-IC,H91A
P3V3_STBY                U7D3             6        ADM1085_SMT-IC,H46130-001
P3V3_STBY                U7F1             2        W25Q256_XSOI-IC,H25002-001
P3V3_STBY                U8D7             A1       LCMXO2_A_256BGA-IC,H63395-001
P3V3_STBY                U8D7             A16      LCMXO2_A_256BGA-IC,H63395-001
P3V3_STBY                U8D7             D5       LCMXO2_A_256BGA-IC,H63395-001
P3V3_STBY                U8D7             D12      LCMXO2_A_256BGA-IC,H63395-001
P3V3_STBY                U8D7             E4       LCMXO2_A_256BGA-IC,H63395-001
P3V3_STBY                U8D7             E13      LCMXO2_A_256BGA-IC,H63395-001
P3V3_STBY                U8D7             G7       LCMXO2_A_256BGA-IC,H63395-001
P3V3_STBY                U8D7             G8       LCMXO2_A_256BGA-IC,H63395-001
P3V3_STBY                U8D7             G9       LCMXO2_A_256BGA-IC,H63395-001
P3V3_STBY                U8D7             G10      LCMXO2_A_256BGA-IC,H63395-001
P3V3_STBY                U8D7             H7       LCMXO2_A_256BGA-IC,H63395-001
P3V3_STBY                U8D7             H10      LCMXO2_A_256BGA-IC,H63395-001
P3V3_STBY                U8D7             J7       LCMXO2_A_256BGA-IC,H63395-001
P3V3_STBY                U8D7             J10      LCMXO2_A_256BGA-IC,H63395-001
P3V3_STBY                U8D7             K7       LCMXO2_A_256BGA-IC,H63395-001
P3V3_STBY                U8D7             K8       LCMXO2_A_256BGA-IC,H63395-001
P3V3_STBY                U8D7             K9       LCMXO2_A_256BGA-IC,H63395-001
P3V3_STBY                U8D7             K10      LCMXO2_A_256BGA-IC,H63395-001
P3V3_STBY                U8D7             M4       LCMXO2_A_256BGA-IC,H63395-001
P3V3_STBY                U8D7             M13      LCMXO2_A_256BGA-IC,H63395-001
P3V3_STBY                U8D7             N5       LCMXO2_A_256BGA-IC,H63395-001
P3V3_STBY                U8D7             N12      LCMXO2_A_256BGA-IC,H63395-001
P3V3_STBY                U8D7             T1       LCMXO2_A_256BGA-IC,H63395-001
P3V3_STBY                U8D7             T16      LCMXO2_A_256BGA-IC,H63395-001
P3V3_STBY                U8D8             2        TPS3700_SM-IC,H69492-001
P3V3_STBY                U8F1             16       PI3B3257A_TSSOPLF-IC,E16801-001
P3V3_STBY                U8F2             2        W25Q128_SKT16-IC,H12709-001
P3V3_STBY                U9B4             8        TMP421_TSSOP-IC,G62962-001
P3V3_STBY                U9E1             8        M25PE16_SM-IC,H77797-001
P3V3_STBY                U9F1             8        FSA3357_SM-IC,C63273-001
P3V3_STBY                U9F2             8        FSA3357_SM-IC,C63273-001
P3V3_STBY                U9F4             F8       AST1250_BGA-IC,G85138-002
P3V3_STBY                U9F4             F9       AST1250_BGA-IC,G85138-002
P3V3_STBY                U9F4             F10      AST1250_BGA-IC,G85138-002
P3V3_STBY                U9F4             F11      AST1250_BGA-IC,G85138-002
P3V3_STBY                U9F4             F12      AST1250_BGA-IC,G85138-002
P3V3_STBY                U9F4             F13      AST1250_BGA-IC,G85138-002
P3V3_STBY                U9F4             H6       AST1250_BGA-IC,G85138-002
P3V3_STBY                U9F4             H17      AST1250_BGA-IC,G85138-002
P3V3_STBY                U9F4             J6       AST1250_BGA-IC,G85138-002
P3V3_STBY                U9F4             J17      AST1250_BGA-IC,G85138-002
P3V3_STBY                U9F4             M6       AST1250_BGA-IC,G85138-002
P3V3_STBY                U9F4             M17      AST1250_BGA-IC,G85138-002
P3V3_STBY                U9F4             N6       AST1250_BGA-IC,G85138-002
P3V3_STBY                U9F4             N17      AST1250_BGA-IC,G85138-002
P3V3_STBY                U9F4             P1       AST1250_BGA-IC,G85138-002
P3V3_STBY                U9F4             T3       AST1250_BGA-IC,G85138-002
P3V3_STBY                U9F4             U8       AST1250_BGA-IC,G85138-002
P3V3_STBY                U9F4             U9       AST1250_BGA-IC,G85138-002
P3V3_STBY                U9F4             W18      AST1250_BGA-IC,G85138-002
P3V3_STBY                U9P2             2        TPS3700_SM-IC,H69492-001
P3V3_STBY                Y9F2             4        OSC_C_SM4-24MHZ,OSC,D34520-021
P3V3_STBY_BMC_ADCAV33    C1U17            1        CAP_0402LF-100.0PF,50V,5%,COG,A
P3V3_STBY_BMC_ADCAV33    C1U18            1        CAP_A_0402V-1.0UF,6.3V,10%,X6SA
P3V3_STBY_BMC_ADCAV33    C9G11            1        CAP_A_0402V-0.1UF,16V,10%,EMPTA
P3V3_STBY_BMC_ADCAV33    FB1U1            2        FERRITE_SMLF-300,FB,693286-046
P3V3_STBY_BMC_ADCAV33    U9F4             P3       AST1250_BGA-IC,G85138-002
P3V3_STBY_BMC_ADCVREFN   C9G8             2        CAP_A_0402V-0.1UF,16V,10%,EMPTA
P3V3_STBY_BMC_ADCVREFN   C9G10            2        CAP_A_0402V-0.1UF,16V,10%,EMPTA
P3V3_STBY_BMC_ADCVREFN   U9F4             K2       AST1250_BGA-IC,G85138-002
P3V3_STBY_BMC_ADCVREFP   C9G8             1        CAP_A_0402V-0.1UF,16V,10%,EMPTA
P3V3_STBY_BMC_ADCVREFP   C9G11            2        CAP_A_0402V-0.1UF,16V,10%,EMPTA
P3V3_STBY_BMC_ADCVREFP   U9F4             K1       AST1250_BGA-IC,G85138-002
P3V3_STBY_BMC_HPLLAV33   C1T19            1        CAP_A_0402V-1.0UF,6.3V,10%,X6SA
P3V3_STBY_BMC_HPLLAV33   C1T20            1        CAP_0402LF-100.0PF,50V,5%,COG,A
P3V3_STBY_BMC_HPLLAV33   C1T23            1        CAP_A_0402V-0.1UF,16V,10%,X7R,A
P3V3_STBY_BMC_HPLLAV33   FB1T2            2        FERRITE_SMLF-300,FB,693286-046
P3V3_STBY_BMC_HPLLAV33   U9F4             AB19     AST1250_BGA-IC,G85138-002
P3V3_STBY_BMC_HPLLAV33   U9F4             V17      AST1250_BGA-IC,G85138-002
P3V3_STBY_MNG            C2T17            1        CAP_A_0402V-0.1UF,16V,10%,X7R,A
P3V3_STBY_MNG            C2T22            1        CAP_0805-10UF,16V,10%,X6S,C953A
P3V3_STBY_MNG            C2T25            1        CAP_A_0402V-0.1UF,16V,10%,X7R,A
P3V3_STBY_MNG            C2T30            1        CAP_A_0402V-0.1UF,16V,10%,X7R,A
P3V3_STBY_MNG            C2T34            1        CAP_A_0402V-0.1UF,16V,10%,X7R,A
P3V3_STBY_MNG            EU8F2            2        ICS9FGP204_MLFP-IC,E95226-001
P3V3_STBY_MNG            EU8F2            12       ICS9FGP204_MLFP-IC,E95226-001
P3V3_STBY_MNG            EU8F2            15       ICS9FGP204_MLFP-IC,E95226-001
P3V3_STBY_MNG            EU8F2            23       ICS9FGP204_MLFP-IC,E95226-001
P3V3_STBY_MNG            FB2T2            2        FERRITE_SMLF-600,FB,656554-043
P3V3_STBY_MNG            R2T21            1        RES_0603-2.2,1.0%,1/10W,CHIP,GA
P3V3_STBY_MNG            R2T23            1        RES_0603-2.2,1.0%,1/10W,CHIP,GA
P3V3_STBY_MNG            R2T52            1        RES_0603-2.2,1.0%,1/10W,CHIP,GA
P3V3_STBY_MNG_CPU        C2T18            1        CAP_A_0402V-0.01UF,25V,10%,X7RA
P3V3_STBY_MNG_CPU        C2T19            1        CAP_A_0402V-1.0UF,6.3V,10%,X6SA
P3V3_STBY_MNG_CPU        EU8F2            9        ICS9FGP204_MLFP-IC,E95226-001
P3V3_STBY_MNG_CPU        R2T21            2        RES_0603-2.2,1.0%,1/10W,CHIP,GA
P3V3_STBY_MNG_RGMII      C2T27            1        CAP_A_0402V-0.01UF,25V,10%,X7RA
P3V3_STBY_MNG_RGMII      C2T31            1        CAP_A_0402V-1.0UF,6.3V,10%,X6SA
P3V3_STBY_MNG_RGMII      EU8F2            34       ICS9FGP204_MLFP-IC,E95226-001
P3V3_STBY_MNG_RGMII      R2T23            2        RES_0603-2.2,1.0%,1/10W,CHIP,GA
P3V3_STBY_MNG_RMII       C2T37            1        CAP_A_0402V-0.01UF,25V,10%,X7RA
P3V3_STBY_MNG_RMII       C2T38            1        CAP_A_0402V-1.0UF,6.3V,10%,X6SA
P3V3_STBY_MNG_RMII       EU8F2            26       ICS9FGP204_MLFP-IC,E95226-001
P3V3_STBY_MNG_RMII       EU8F2            31       ICS9FGP204_MLFP-IC,E95226-001
P3V3_STBY_MNG_RMII       R2T52            2        RES_0603-2.2,1.0%,1/10W,CHIP,GA
P3V3_STBY_P1V5_LAN_I210  EU9E1            51       SPRINGVILLE_SM1-IC,G47144-004
P3V3_STBY_P1V5_LAN_I210  R1T33            2        RES_0603-0,5.0%,1/10W,EMPTY,G2A
P3V3_STBY_P1V5_LAN_I210  R1T34            2        RES_0603-0,5.0%,1/10W,CHIP,G22A
P3V3_STBY_PLD_D          CR3U1            1        DIODE_SMLF-1N5819HW,IC,D55839-A
P3V3_STBY_PLD_D          J7G2             1        CONN8_C77962004_PIP-CONN,C7796A
P3V3_SWITCH_G            EU2T1            7        SLG55021_SM-IC,G56246-001
P3V3_SWITCH_G            Q8G1             4        MOSFET_N_LCC3-BSZ019N03LS,NFETA
P3V_BAT_SOURCE           R2U43            1        RES_0402-1.00K,1%,1/16W,CHIP,GA
P3V_BAT_SOURCE           XBT8G1           1        VERT_BATT_3PIN_PIP-3PVERT,C686A
P3V_BAT_SOURCE           XBT8G1           2        VERT_BATT_3PIN_PIP-3PVERT,C686A
P3V_BAT_SOURCE_R         Q9G1             3        FET_N_DUAL_SMLF-NTJD4001N,FET,A
P3V_BAT_SOURCE_R         R1U50            2        RES_0402-200.0K,1%,1/16W,CHIP,A
P5V                      C1M38            1        CAP_A_0402V-0.1UF,16V,10%,X7R,A
P5V                      C8B6             1        CAP_0805-10UF,16V,10%,X6S,C953A
P5V                      C8B7             1        CAP_A_0402V-0.1UF,16V,10%,X7R,A
P5V                      EU8B1            6        SLG55021_SM-IC,G56246-001
P5V                      F8B1             1        FUSE_SMLF-IC,C94311-006
P5V                      Q8B1             1        MOSFET_N_LCC3-BSZ019N03LS,NFETA
P5V                      R1U29            1        RES_0402-5.11K,1%,1/16W,CHIP,GA
P5V                      R8D39            1        RES_0402-49.9K,1%,1/16W,CHIP,GA
P5V                      U1M3             5        TPS2061_SM-IC,H66405-001
P5V_HDD_SATA             C9B1             1        CAP_0805-10UF,16V,10%,X6S,C953A
P5V_HDD_SATA             F8B1             2        FUSE_SMLF-IC,C94311-006
P5V_HDD_SATA             J2L1             1        CONN4_H73295001_PIP-CONN,H7329A
P5V_HDD_SATA             J8A4             1        CONN4_H73295001_PIP-EMPTY,H732A
P5V_STBY                 C1A2             1        CAP_A_0402V-1.0UF,6.3V,10%,X6SA
P5V_STBY                 C1A11            1        CAP_A_0402V-1.0UF,6.3V,10%,X6SA
P5V_STBY                 C1A13            1        CAP_0402-0.22UF,16V,10%,X7R,A3A
P5V_STBY                 C1B21            1        CAP_0402-0.22UF,16V,10%,X7R,A3A
P5V_STBY                 C1C3             1        CAP_A_0402V-1.0UF,6.3V,10%,X6SA
P5V_STBY                 C1C4             1        CAP_0402-0.22UF,16V,10%,X7R,A3A
P5V_STBY                 C1C18            1        CAP_A_0402V-1.0UF,6.3V,10%,X6SA
P5V_STBY                 C1D5             1        CAP_A_0402V-1.0UF,6.3V,10%,X6SA
P5V_STBY                 C1D6             1        CAP_0402-0.22UF,16V,10%,X7R,A3A
P5V_STBY                 C1D15            1        CAP_A_0402V-1.0UF,6.3V,10%,X6SA
P5V_STBY                 C1D16            1        CAP_0402-0.22UF,16V,10%,X7R,A3A
P5V_STBY                 C1D33            1        CAP_0402-0.22UF,16V,10%,X7R,A3A
P5V_STBY                 C1E6             1        CAP_A_0402V-1.0UF,6.3V,10%,X6SA
P5V_STBY                 C1E7             1        CAP_0402-0.22UF,16V,10%,X7R,A3A
P5V_STBY                 C1E23            1        CAP_A_0402V-1.0UF,6.3V,10%,X6SA
P5V_STBY                 C1E25            1        CAP_0402-0.22UF,16V,10%,X7R,A3A
P5V_STBY                 C1F21            1        CAP_A_0402V-1.0UF,6.3V,10%,X6SA
P5V_STBY                 C1G4             1        CAP_A_0402V-1.0UF,6.3V,10%,X6SA
P5V_STBY                 C1G5             1        CAP_0402-0.22UF,16V,10%,X7R,A3A
P5V_STBY                 C1G29            1        CAP_0402-0.22UF,16V,10%,X7R,A3A
P5V_STBY                 C1L4             1        CAP_A_0402V-0.1UF,16V,10%,X7R,A
P5V_STBY                 C2R11            1        CAP_0603-4.7UF,6.3V,10%,X6S,E1A
P5V_STBY                 C3L1             1        CAP_A_0402V-1.0UF,6.3V,10%,X6SA
P5V_STBY                 C3L29            1        CAP_A_0402V-1.0UF,6.3V,10%,X6SA
P5V_STBY                 C4C4             1        CAP_A_0402V-1.0UF,6.3V,10%,X6SA
P5V_STBY                 C4C5             1        CAP_0402-0.22UF,16V,10%,X7R,A3A
P5V_STBY                 C4C14            1        CAP_A_0402V-1.0UF,6.3V,10%,X6SA
P5V_STBY                 C4D5             1        CAP_0402-0.22UF,16V,10%,X7R,A3A
P5V_STBY                 C4D6             1        CAP_A_0402V-1.0UF,6.3V,10%,X6SA
P5V_STBY                 C4D13            1        CAP_0402-0.22UF,16V,10%,X7R,A3A
P5V_STBY                 C4D14            1        CAP_A_0402V-1.0UF,6.3V,10%,X6SA
P5V_STBY                 C4D47            1        CAP_0402-0.22UF,16V,10%,X7R,A3A
P5V_STBY                 C4E5             1        CAP_0402-0.22UF,16V,10%,X7R,A3A
P5V_STBY                 C4E6             1        CAP_A_0402V-1.0UF,6.3V,10%,X6SA
P5V_STBY                 C4E23            1        CAP_0402-0.22UF,16V,10%,X7R,A3A
P5V_STBY                 C4E25            1        CAP_A_0402V-1.0UF,6.3V,10%,X6SA
P5V_STBY                 C4E27            1        CAP_0402-0.22UF,16V,10%,X7R,A3A
P5V_STBY                 C4E28            1        CAP_A_0402V-1.0UF,6.3V,10%,X6SA
P5V_STBY                 C7A8             1        CAP_0402-0.22UF,16V,10%,X7R,A3A
P5V_STBY                 C7A17            1        CAP_0402-0.22UF,16V,10%,X7R,A3A
P5V_STBY                 C7A18            1        CAP_A_0402V-1.0UF,6.3V,10%,X6SA
P5V_STBY                 C7A25            1        CAP_0402-0.22UF,16V,10%,X7R,A3A
P5V_STBY                 C7A26            1        CAP_A_0402V-1.0UF,6.3V,10%,X6SA
P5V_STBY                 C7A41            1        CAP_0402-0.22UF,16V,10%,X7R,A3A
P5V_STBY                 C7C18            1        CAP_0402-0.22UF,16V,10%,X7R,A3A
P5V_STBY                 C7C20            1        CAP_A_0402V-1.0UF,6.3V,10%,X6SA
P5V_STBY                 C7G34            1        CAP_0402-0.22UF,16V,10%,X7R,A3A
P5V_STBY                 C7G35            1        CAP_A_0402V-1.0UF,6.3V,10%,X6SA
P5V_STBY                 C7G41            1        CAP_0402-0.22UF,16V,10%,X7R,A3A
P5V_STBY                 C7G42            1        CAP_A_0402V-1.0UF,6.3V,10%,X6SA
P5V_STBY                 C8B5             1        CAP_A_0402V-0.1UF,16V,10%,X7R,A
P5V_STBY                 C8B8             1        CAP_A_0402V-0.1UF,16V,10%,X7R,A
P5V_STBY                 C8B12            1        CAP_0805-10UF,16V,10%,X6S,C953A
P5V_STBY                 C8E4             1        CAPP_3018-470UF,6.3V,20%,POSCAA
P5V_STBY                 C8E7             1        CAP_0805-22UF,6.3V,20%,X6S,C95A
P5V_STBY                 C8E9             1        CAP_0805-22UF,6.3V,20%,X6S,C95A
P5V_STBY                 C8E19            1        CAP_A_0402V-0.1UF,16V,10%,X7R,A
P5V_STBY                 C8F17            1        CAP_A_0402V-0.1UF,16V,10%,X7R,A
P5V_STBY                 C9B9             1        CAP_A_0402V-1.0UF,6.3V,10%,X6SA
P5V_STBY                 C9B10            1        CAP_A_0402V-0.1UF,16V,10%,X7R,A
P5V_STBY                 C9M6             1        CAP_A_0402V-0.1UF,16V,10%,X7R,A
P5V_STBY                 CR1B1            1        DIODE_SM-SDMK0340L,EMPTY,H7179A
P5V_STBY                 CR1E1            1        DIODE_SM-SDMK0340L,EMPTY,H7179A
P5V_STBY                 EU1A1            4        IR354XX_SM-IR35411,IC,H73688-0A
P5V_STBY                 EU1A1            35       IR354XX_SM-IR35411,IC,H73688-0A
P5V_STBY                 EU1A2            4        IR354XX_SM-IR35411,IC,H73688-0A
P5V_STBY                 EU1A2            35       IR354XX_SM-IR35411,IC,H73688-0A
P5V_STBY                 EU1C1            4        IR354XX_SM-IR35412,IC,H73684-0A
P5V_STBY                 EU1C1            35       IR354XX_SM-IR35412,IC,H73684-0A
P5V_STBY                 EU1C3            4        IR354XX_SM-IR35411,IC,H73688-0A
P5V_STBY                 EU1C3            35       IR354XX_SM-IR35411,IC,H73688-0A
P5V_STBY                 EU1D1            4        IR354XX_SM-IR35411,IC,H73688-0A
P5V_STBY                 EU1D1            35       IR354XX_SM-IR35411,IC,H73688-0A
P5V_STBY                 EU1D3            4        IR354XX_SM-IR35411,IC,H73688-0A
P5V_STBY                 EU1D3            35       IR354XX_SM-IR35411,IC,H73688-0A
P5V_STBY                 EU1D4            4        IR354XX_SM-IR35411,IC,H73688-0A
P5V_STBY                 EU1D4            35       IR354XX_SM-IR35411,IC,H73688-0A
P5V_STBY                 EU1E2            4        IR354XX_SM-IR35411,IC,H73688-0A
P5V_STBY                 EU1E2            35       IR354XX_SM-IR35411,IC,H73688-0A
P5V_STBY                 EU1F1            4        IR354XX_SM-IR35411,IC,H73688-0A
P5V_STBY                 EU1F1            35       IR354XX_SM-IR35411,IC,H73688-0A
P5V_STBY                 EU1G1            4        IR354XX_SM-IR35411,IC,H73688-0A
P5V_STBY                 EU1G1            35       IR354XX_SM-IR35411,IC,H73688-0A
P5V_STBY                 EU2T1            1        SLG55021_SM-IC,G56246-001
P5V_STBY                 EU2T1            3        SLG55021_SM-IC,G56246-001
P5V_STBY                 EU4C1            4        IR354XX_SM-IR35412,IC,H73684-0A
P5V_STBY                 EU4C1            35       IR354XX_SM-IR35412,IC,H73684-0A
P5V_STBY                 EU4C2            4        IR354XX_SM-IR35411,IC,H73688-0A
P5V_STBY                 EU4C2            35       IR354XX_SM-IR35411,IC,H73688-0A
P5V_STBY                 EU4D1            4        IR354XX_SM-IR35411,IC,H73688-0A
P5V_STBY                 EU4D1            35       IR354XX_SM-IR35411,IC,H73688-0A
P5V_STBY                 EU4D3            4        IR354XX_SM-IR35411,IC,H73688-0A
P5V_STBY                 EU4D3            35       IR354XX_SM-IR35411,IC,H73688-0A
P5V_STBY                 EU4D6            4        IR354XX_SM-IR35411,IC,H73688-0A
P5V_STBY                 EU4D6            35       IR354XX_SM-IR35411,IC,H73688-0A
P5V_STBY                 EU4E1            4        IR354XX_SM-IR35411,IC,H73688-0A
P5V_STBY                 EU4E1            35       IR354XX_SM-IR35411,IC,H73688-0A
P5V_STBY                 EU4E2            4        IR354XX_SM-IR35412,IC,H73684-0A
P5V_STBY                 EU4E2            35       IR354XX_SM-IR35412,IC,H73684-0A
P5V_STBY                 EU7A1            4        IR354XX_SM-IR35411,IC,H73688-0A
P5V_STBY                 EU7A1            35       IR354XX_SM-IR35411,IC,H73688-0A
P5V_STBY                 EU7A2            4        IR354XX_SM-IR35412,IC,H73684-0A
P5V_STBY                 EU7A2            35       IR354XX_SM-IR35412,IC,H73684-0A
P5V_STBY                 EU7A3            4        IR354XX_SM-IR35412,IC,H73684-0A
P5V_STBY                 EU7A3            35       IR354XX_SM-IR35412,IC,H73684-0A
P5V_STBY                 EU7A4            4        IR354XX_SM-IR35411,IC,H73688-0A
P5V_STBY                 EU7A4            35       IR354XX_SM-IR35411,IC,H73688-0A
P5V_STBY                 EU7C1            4        IR354XX_SM-IR35412,IC,H73684-0A
P5V_STBY                 EU7C1            35       IR354XX_SM-IR35412,IC,H73684-0A
P5V_STBY                 EU7E1            1        SLG55021_SM-IC,G56246-001
P5V_STBY                 EU7E1            3        SLG55021_SM-IC,G56246-001
P5V_STBY                 EU7G2            4        IR354XX_SM-IR35411,IC,H73688-0A
P5V_STBY                 EU7G2            35       IR354XX_SM-IR35411,IC,H73688-0A
P5V_STBY                 EU7G3            4        IR354XX_SM-IR35411,IC,H73688-0A
P5V_STBY                 EU7G3            35       IR354XX_SM-IR35411,IC,H73688-0A
P5V_STBY                 EU8B1            1        SLG55021_SM-IC,G56246-001
P5V_STBY                 EU8B1            3        SLG55021_SM-IC,G56246-001
P5V_STBY                 EU8B1            5        SLG55021_SM-IC,G56246-001
P5V_STBY                 EU8F1            5        RT8240_QFN-IC,H66262-001
P5V_STBY                 EU9M1            1        SLG55021_SM-IC,G56246-001
P5V_STBY                 EU9M1            3        SLG55021_SM-IC,G56246-001
P5V_STBY                 J4B2             A13      SCONN120_H61426002_SM-CONN,H61A
P5V_STBY                 J4B2             B13      SCONN120_H61426002_SM-CONN,H61A
P5V_STBY                 J4B2             C13      SCONN120_H61426002_SM-CONN,H61A
P5V_STBY                 J6B1             A13      SCONN120_H61426002_SM-CONN,H61A
P5V_STBY                 J6B1             B13      SCONN120_H61426002_SM-CONN,H61A
P5V_STBY                 J6B1             C13      SCONN120_H61426002_SM-CONN,H61A
P5V_STBY                 J9B3             3        SCONN120_A28699018_SM-SCONN,A2A
P5V_STBY                 J9B3             5        SCONN120_A28699018_SM-SCONN,A2A
P5V_STBY                 J9B3             7        SCONN120_A28699018_SM-SCONN,A2A
P5V_STBY                 L8E1             2        INDUCTOR_SM-2.2UH,IND,E98761-0A
P5V_STBY                 Q1L2             6        FET_N_DUAL_SMLF-NTJD4001N,FET,A
P5V_STBY                 Q8B1             5        MOSFET_N_LCC3-BSZ019N03LS,NFETA
P5V_STBY                 R1E12            1        RES_0402-4.75K,1%,1/16W,CHIP,GA
P5V_STBY                 R1L8             1        RES_0402-470.0,5%,1/16W,CHIP,GA
P5V_STBY                 R1L37            1        RES_0402-301.0,1%,1/16W,CHIP,GA
P5V_STBY                 R1U47            1        RES_0402-5.11K,1%,1/16W,CHIP,GA
P5V_STBY                 R3L1             2        RES_0402-1.0,1%,1/16W,CHIP,G21A
P5V_STBY                 R3L4             2        RES_0402-1.0,1%,1/16W,CHIP,G21A
P5V_STBY                 R3L6             2        RES_0402-1.0,1%,1/16W,CHIP,G21A
P5V_STBY                 R3L8             2        RES_0402-1.0,1%,1/16W,CHIP,G21A
P5V_STBY                 R3N7             2        RES_0402-1.0,1%,1/16W,CHIP,G21A
P5V_STBY                 R3U6             2        RES_0402-1.0,1%,1/16W,CHIP,G21A
P5V_STBY                 R3U9             2        RES_0402-1.0,1%,1/16W,CHIP,G21A
P5V_STBY                 R6N3             2        RES_0402-1.0,1%,1/16W,CHIP,G21A
P5V_STBY                 R6P10            2        RES_0402-1.0,1%,1/16W,CHIP,G21A
P5V_STBY                 R6P19            2        RES_0402-1.0,1%,1/16W,CHIP,G21A
P5V_STBY                 R6P47            2        RES_0402-1.0,1%,1/16W,CHIP,G21A
P5V_STBY                 R6R2             2        RES_0402-1.0,1%,1/16W,CHIP,G21A
P5V_STBY                 R6R5             2        RES_0402-1.0,1%,1/16W,CHIP,G21A
P5V_STBY                 R6R6             2        RES_0402-1.0,1%,1/16W,CHIP,G21A
P5V_STBY                 R7E12            1        RES_0402-1.00K,1%,1/16W,CHIP,GA
P5V_STBY                 R7F33            1        RES_0402-4.75K,1%,1/16W,CHIP,GA
P5V_STBY                 R8E18            1        RES_0402-1.0K,0.1%,1/16W,CHIP,A
P5V_STBY                 R8E37            2        RES_0402-0.0,5%,1/16W,CHIP,G21A
P5V_STBY                 R9A5             1        RES_0402-20.0K,1%,1/16W,CHIP,GA
P5V_STBY                 R9A6             1        RES_0402-20.0K,1%,1/16W,EMPTY,A
P5V_STBY                 R9L4             2        RES_0402-1.0,1%,1/16W,CHIP,G21A
P5V_STBY                 R9L9             2        RES_0402-1.0,1%,1/16W,CHIP,G21A
P5V_STBY                 R9N3             2        RES_0402-1.0,1%,1/16W,CHIP,G21A
P5V_STBY                 R9P8             2        RES_0402-1.0,1%,1/16W,CHIP,G21A
P5V_STBY                 R9P22            2        RES_0402-1.0,1%,1/16W,CHIP,G21A
P5V_STBY                 R9P32            2        RES_0402-1.0,1%,1/16W,CHIP,G21A
P5V_STBY                 R9R2             2        RES_0402-1.0,1%,1/16W,CHIP,G21A
P5V_STBY                 R9R11            2        RES_0402-1.0,1%,1/16W,CHIP,G21A
P5V_STBY                 R9U1             2        RES_0402-1.0,1%,1/16W,CHIP,G21A
P5V_STBY                 R9U12            2        RES_0402-1.0,1%,1/16W,CHIP,G21A
P5V_STBY_DBG             F1L1             1        FUSE_SMT-IC,H45581-001
P5V_STBY_DBG             Q1L2             1        FET_N_DUAL_SMLF-NTJD4001N,FET,A
P5V_STBY_DGB_FS          C9A1             1        CAP_A_0402V-0.1UF,16V,10%,X7R,A
P5V_STBY_DGB_FS          F1L1             2        FUSE_SMT-IC,H45581-001
P5V_STBY_DGB_FS          J9A2             14       CONN14_H54902001_PIP-CONN,H549A
P5V_SWITCH_G             EU8B1            7        SLG55021_SM-IC,G56246-001
P5V_SWITCH_G             Q8B1             4        MOSFET_N_LCC3-BSZ019N03LS,NFETA
P5V_USB                  C9B8             1        CAPP_7343HLF-330UF,10V,20%,POSA
P5V_USB                  J9B1             1        CONN9_H51826001_PIP2-CONN,H518A
P5V_USB                  U1M3             1        TPS2061_SM-IC,H66405-001
PD_ADCREXT               R9G7             1        RES_0402-49.9K,1%,1/16W,CHIP,GA
PD_ADCREXT               U9F4             P2       AST1250_BGA-IC,G85138-002
PD_CKMNG_OE              EU8F2            5        ICS9FGP204_MLFP-IC,E95226-001
PD_CKMNG_OE              EU8F2            6        ICS9FGP204_MLFP-IC,E95226-001
PD_CKMNG_OE              R2T25            1        RES_0402-1.00K,1%,1/16W,CHIP,GA
PD_CPU0_BIST_ENABLE      R4P1             2        RES_0402-240,1.0%,1/16W,EMPTY,A
PD_CPU0_BIST_ENABLE      U5D1             BA20     SKX_EXT_B_BGA1-IC,TBD
PD_CPU0_DMIMODE_OVERRIDE R4P6             2        RES_0402-240,1.0%,1/16W,EMPTY,A
PD_CPU0_DMIMODE_OVERRIDE U5D1             AW12     SKX_EXT_B_BGA1-IC,TBD
PD_CPU0_KSFC_DIS         R4P7             2        RES_0402-240,1.0%,1/16W,EMPTY,A
PD_CPU0_KSFC_DIS         U5D1             AW14     SKX_EXT_B_BGA1-IC,TBD
PD_CPU0_MCP01_DMON       R4P5             2        RES_0402-10.0K,1%,1/16W,CHIP,GA
PD_CPU0_MCP01_DMON       U5D1             CN28     SKX_EXT_B_BGA1-IC,TBD
PD_CPU0_RSVD_TEST_1      R5R1             1        RES_0402-49.9,1%,1/16W,CHIP,G2A
PD_CPU0_RSVD_TEST_1      U5D1             AF45     SKX_EXT_B_BGA1-IC,TBD
PD_CPU0_RSVD_TEST_2      R5P4             1        RES_0402-49.9,1%,1/16W,CHIP,G2A
PD_CPU0_RSVD_TEST_2      U5D1             AG46     SKX_EXT_B_BGA1-IC,TBD
PD_CPU0_TEST12           R6D5             1        RES_0402-49.9,1%,1/16W,CHIP,G2A
PD_CPU0_TEST12           U5D1             AY19     SKX_EXT_B_BGA1-IC,TBD
PD_CPU0_TEST13           R5P3             1        RES_0402-49.9,1%,1/16W,CHIP,G2A
PD_CPU0_TEST13           U5D1             DB51     SKX_EXT_B_BGA1-IC,TBD
PD_CPU0_TEST14           R5P2             1        RES_0402-49.9,1%,1/16W,CHIP,G2A
PD_CPU0_TEST14           U5D1             DC50     SKX_EXT_B_BGA1-IC,TBD
PD_CPU0_TXT_PLTEN        R6D6             2        RES_0402-240,1.0%,1/16W,CHIP,GA
PD_CPU0_TXT_PLTEN        U5D1             AV15     SKX_EXT_B_BGA1-IC,TBD
PD_CPU1_BIST_ENABLE      R3D13            2        RES_0402-240,1.0%,1/16W,EMPTY,A
PD_CPU1_BIST_ENABLE      U2D1             BA20     SKX_EXT_B_BGA1-IC,TBD
PD_CPU1_DMIMODE_OVERRIDE R7P14            2        RES_0402-240,1.0%,1/16W,CHIP,GA
PD_CPU1_DMIMODE_OVERRIDE U2D1             AW12     SKX_EXT_B_BGA1-IC,TBD
PD_CPU1_KSFC_DIS         R7P15            2        RES_0402-240,1.0%,1/16W,EMPTY,A
PD_CPU1_KSFC_DIS         U2D1             AW14     SKX_EXT_B_BGA1-IC,TBD
PD_CPU1_MCP01_DMON       R7P13            2        RES_0402-10.0K,1%,1/16W,CHIP,GA
PD_CPU1_MCP01_DMON       U2D1             CN28     SKX_EXT_B_BGA1-IC,TBD
PD_CPU1_RSVD_TEST_1      R8R1             1        RES_0402-49.9,1%,1/16W,CHIP,G2A
PD_CPU1_RSVD_TEST_1      U2D1             AF45     SKX_EXT_B_BGA1-IC,TBD
PD_CPU1_RSVD_TEST_2      R8P3             1        RES_0402-49.9,1%,1/16W,CHIP,G2A
PD_CPU1_RSVD_TEST_2      U2D1             AG46     SKX_EXT_B_BGA1-IC,TBD
PD_CPU1_TEST12           R3D9             1        RES_0402-49.9,1%,1/16W,CHIP,G2A
PD_CPU1_TEST12           U2D1             AY19     SKX_EXT_B_BGA1-IC,TBD
PD_CPU1_TEST13           R8P2             1        RES_0402-49.9,1%,1/16W,CHIP,G2A
PD_CPU1_TEST13           U2D1             DB51     SKX_EXT_B_BGA1-IC,TBD
PD_CPU1_TEST14           R8P1             1        RES_0402-49.9,1%,1/16W,CHIP,G2A
PD_CPU1_TEST14           U2D1             DC50     SKX_EXT_B_BGA1-IC,TBD
PD_CPU1_TXT_PLTEN        R3D12            2        RES_0402-240,1.0%,1/16W,CHIP,GA
PD_CPU1_TXT_PLTEN        U2D1             AV15     SKX_EXT_B_BGA1-IC,TBD
PD_DIR_2                 R1U30            1        RES_0402-1.00K,1%,1/16W,CHIP,GA
PD_DIR_2                 U9G1             1        GTL2014_SM-IC,D66151-001
PD_FRU_WP                R8D27            1        RES_0402-1.00K,1%,1/16W,CHIP,GA
PD_FRU_WP                U8D4             7        AT24C64_SOICLF-IC,C47049-001-GA
PD_GTL2014_1_VREF        R3P32            2        RES_0402-1.00K,1%,1/16W,CHIP,GA
PD_GTL2014_1_VREF        U3P1             4        GTL2014_SM-IC,D66151-001
PD_GTL2014_2_VREF        R4C9             2        RES_0402-1.00K,1%,1/16W,CHIP,GA
PD_GTL2014_2_VREF        U4C2             4        GTL2014_SM-IC,D66151-001
PD_GTL2104_4_DIR         R2T50            1        RES_0402-1.00K,1%,1/16W,CHIP,GA
PD_GTL2104_4_DIR         U2T4             1        GTL2014_SM-IC,D66151-001
PD_GTL2104_DIR_0         R7D26            1        RES_0402-1.00K,1%,1/16W,CHIP,GA
PD_GTL2104_DIR_0         U7D2             1        GTL2014_SM-IC,D66151-001
PD_GTL2104_DIR_1         R3R1             1        RES_0402-1.00K,1%,1/16W,CHIP,GA
PD_GTL2104_DIR_1         U3P2             1        GTL2014_SM-IC,D66151-001
PD_HSC_RETRY_N           EU1D2            17       ADM1278_SM-IC,G99251-001
PD_HSC_RETRY_N           R1D28            1        RES_0402-100.0,1%,1/16W,EMPTY,A
PD_IE_DEBUG_MODE         J9G1             11       CONN12_C73564003_PIP-CONN,C735A
PD_IE_DEBUG_MODE         R1U64            1        RES_0402-1.00K,1%,1/16W,CHIP,GA
PD_ME_RCVR_N             J7G3             5        CONN12_C73564003_PIP-CONN,C735A
PD_ME_RCVR_N             R7G28            1        RES_0402-1.00K,1%,1/16W,CHIP,GA
PD_PASSWORD_CLEAR        J7G3             11       CONN12_C73564003_PIP-CONN,C735A
PD_PASSWORD_CLEAR        R7G29            1        RES_0402-1.00K,1%,1/16W,CHIP,GA
PD_PEREXT                R2T12            1        RES_0402-10.0K,1%,1/16W,EMPTY,A
PD_PEREXT                U9F4             D20      AST1250_BGA-IC,G85138-002
PD_PIROM_CPU0_ADDR0      R6N14            2        RES_0402-1.00K,1%,1/16W,CHIP,GA
PD_PIROM_CPU0_ADDR0      U5D1             CU58     SKX_EXT_B_BGA1-IC,TBD
PD_PIROM_CPU0_ADDR1      R6N13            2        RES_0402-1.00K,1%,1/16W,CHIP,GA
PD_PIROM_CPU0_ADDR1      U5D1             CV57     SKX_EXT_B_BGA1-IC,TBD
PD_PIROM_CPU0_ADDR2      R6N15            2        RES_0402-1.00K,1%,1/16W,CHIP,GA
PD_PIROM_CPU0_ADDR2      U5D1             CW56     SKX_EXT_B_BGA1-IC,TBD
PD_PIROM_CPU1_ADDR1      R1C33            2        RES_0402-1.00K,1%,1/16W,CHIP,GA
PD_PIROM_CPU1_ADDR1      U2D1             CV57     SKX_EXT_B_BGA1-IC,TBD
PD_PIROM_CPU1_ADDR2      R1C32            2        RES_0402-1.00K,1%,1/16W,CHIP,GA
PD_PIROM_CPU1_ADDR2      U2D1             CW56     SKX_EXT_B_BGA1-IC,TBD
PD_RST_RTCRST_N          J9G1             6        CONN12_C73564003_PIP-CONN,C735A
PD_RST_RTCRST_N          R1U63            1        RES_0402-1.00K,1%,1/16W,CHIP,GA
PD_SATA0_CONTROLLER_TYPE_R J8A1             1D2      CONN72_G97614002_A_CP-CONN,G97A
PD_SATA0_CONTROLLER_TYPE_R R2L18            1        RES_0402-1.00K,1%,1/16W,CHIP,GA
PD_SATA1_CONTROLLER_TYPE_R J8A1             2D2      CONN72_G97614002_A_CP-CONN,G97A
PD_SATA1_CONTROLLER_TYPE_R R2L22            1        RES_0402-1.00K,1%,1/16W,CHIP,GA
PD_SATA2_CONTROLLER_TYPE J8A2             D2       CONN36_G97614001_CP-CONN,G9761A
PD_SATA2_CONTROLLER_TYPE R1L3             1        RES_0402-1.00K,1%,1/16W,CHIP,GA
PD_SPRV_RSET             EU9E1            48       SPRINGVILLE_SM1-IC,G47144-004
PD_SPRV_RSET             R9E23            1        RES_0402-4.99K,1%,1/16W,CHIP,GA
PD_SP_ENTEST             R1U7             2        RES_0402-10.0K,1%,1/16W,CHIP,GA
PD_SP_ENTEST             U9F4             E4       AST1250_BGA-IC,G85138-002
PD_TMP421_1_A0           R9B8             1        RES_0402-1.00K,1%,1/16W,CHIP,GA
PD_TMP421_1_A0           U9B4             4        TMP421_TSSOP-IC,G62962-001
PD_TMP421_2_A1           R1E10            2        RES_0402-1.00K,1%,1/16W,CHIP,GA
PD_TMP421_2_A1           U1E1             3        TMP421_TSSOP-IC,G62962-001
PD_USB_BMC_P1_DN         R9G5             1        RES_0402-0.0,5%,1/16W,EMPTY,G2A
PD_USB_BMC_P1_DN         U9F4             J2       AST1250_BGA-IC,G85138-002
PD_USB_BMC_P1_DP         R9G6             1        RES_0402-0.0,5%,1/16W,EMPTY,G2A
PD_USB_BMC_P1_DP         U9F4             J1       AST1250_BGA-IC,G85138-002
PECI_BMC                 R7C17            2        RES_0402-4.75K,1%,1/16W,CHIP,GA
PECI_BMC                 R7C18            1        RES_0402-0.0,5%,1/16W,EMPTY,G2A
PECI_BMC                 R9F20            1        RES_0402-348,1%,1/16W,EMPTY,G2A
PECI_BMC                 R9F33            1        RES_0402-0.0,5%,1/16W,CHIP,G21A
PECI_BMC_R               R9F33            2        RES_0402-0.0,5%,1/16W,CHIP,G21A
PECI_BMC_R               U9F4             AA21     AST1250_BGA-IC,G85138-002
PECI_CPU_G               R7C18            2        RES_0402-0.0,5%,1/16W,EMPTY,G2A
PECI_CPU_G               R7C19            2        RES_0402-0.0,5%,1/16W,CHIP,G21A
PECI_CPU_G               R7D15            1        RES_0402-348,1%,1/16W,CHIP,G21A
PECI_CPU_G               U2D1             AU12     SKX_EXT_B_BGA1-IC,TBD
PECI_CPU_G               U5D1             AU12     SKX_EXT_B_BGA1-IC,TBD
PECI_PCH                 R7C19            1        RES_0402-0.0,5%,1/16W,CHIP,G21A
PECI_PCH                 R7C22            2        RES_0402-4.75K,1%,1/16W,EMPTY,A
PECI_PCH                 U7C1             U9       LBG_CORE_QAT_EXT_D_BGA1-IC,H91A
PE_PCH_SPRV_RX_C_DN      C9E5             2        CAP_A_0402V-0.1UF,16V,10%,X7R,A
PE_PCH_SPRV_RX_C_DN      U7C1             AM69     LBG_CORE_QAT_EXT_D_BGA1-IC,H91A
PE_PCH_SPRV_RX_C_DP      C9E4             2        CAP_A_0402V-0.1UF,16V,10%,X7R,A
PE_PCH_SPRV_RX_C_DP      U7C1             AM71     LBG_CORE_QAT_EXT_D_BGA1-IC,H91A
PE_PCH_SPRV_RX_DN        C9E5             1        CAP_A_0402V-0.1UF,16V,10%,X7R,A
PE_PCH_SPRV_RX_DN        EU9E1            20       SPRINGVILLE_SM1-IC,G47144-004
PE_PCH_SPRV_RX_DP        C9E4             1        CAP_A_0402V-0.1UF,16V,10%,X7R,A
PE_PCH_SPRV_RX_DP        EU9E1            21       SPRINGVILLE_SM1-IC,G47144-004
PE_PCH_SPRV_TX_C_DN      C2M24            2        CAP_A_0402V-0.1UF,16V,10%,X7R,A
PE_PCH_SPRV_TX_C_DN      EU9E1            23       SPRINGVILLE_SM1-IC,G47144-004
PE_PCH_SPRV_TX_C_DP      C2M23            2        CAP_A_0402V-0.1UF,16V,10%,X7R,A
PE_PCH_SPRV_TX_C_DP      EU9E1            24       SPRINGVILLE_SM1-IC,G47144-004
PE_PCH_SPRV_TX_DN        C2M24            1        CAP_A_0402V-0.1UF,16V,10%,X7R,A
PE_PCH_SPRV_TX_DN        U7C1             BH65     LBG_CORE_QAT_EXT_D_BGA1-IC,H91A
PE_PCH_SPRV_TX_DP        C2M23            1        CAP_A_0402V-0.1UF,16V,10%,X7R,A
PE_PCH_SPRV_TX_DP        U7C1             BJ63     LBG_CORE_QAT_EXT_D_BGA1-IC,H91A
PU_10GBE_LOM_PCI_DISABLE_N R2N9             2        RES_0402-10.0K,1%,1/16W,CHIP,GA
PU_10GBE_LOM_PCI_DISABLE_N U7C1             BW22     LBG_CORE_QAT_EXT_D_BGA1-IC,H91A
PU_24M_OSC_OE            R9F61            2        RES_0402-10.0K,1%,1/16W,CHIP,GA
PU_24M_OSC_OE            Y9F2             1        OSC_C_SM4-24MHZ,OSC,D34520-021
PU_ADR_TIMER_HOLD_OFF_N  R8D5             1        RES_0402-1.00K,1%,1/16W,EMPTY,A
PU_ADR_TIMER_HOLD_OFF_N  R8D13            2        RES_0402-10.0K,1%,1/16W,CHIP,GA
PU_ADR_TIMER_HOLD_OFF_N  U7C1             BB3      LBG_CORE_QAT_EXT_D_BGA1-IC,H91A
PU_AT24C64_A2            R8D28            2        RES_0402-1.00K,1%,1/16W,CHIP,GA
PU_AT24C64_A2            U8D4             3        AT24C64_SOICLF-IC,C47049-001-GA
PU_BIOS_RECOVER_BOOT     J7G3             12       CONN12_C73564003_PIP-CONN,C735A
PU_BIOS_RECOVER_BOOT     R7G31            2        RES_0402-1.00K,1%,1/16W,CHIP,GA
PU_BIOS_SPI_HOLD0_N      R7F3             2        RES_0402-33.2,1%,1/16W,CHIP,G2A
PU_BIOS_SPI_HOLD0_N      R7F32            2        RES_0402-10.0K,1%,1/16W,CHIP,GA
PU_BIOS_SPI_HOLD0_N      U7F1             1        W25Q256_XSOI-IC,H25002-001
PU_BIOS_SPI_HOLD1_N      R3T1             2        RES_0402-33.2,1%,1/16W,CHIP,G2A
PU_BIOS_SPI_HOLD1_N      R3T4             2        RES_0402-10.0K,1%,1/16W,CHIP,GA
PU_BIOS_SPI_HOLD1_N      U3T1             1        W25Q256_XSOI-IC,H25002-001
PU_BIOS_SPI_WP0_N        R7F28            2        RES_0402-10.0K,1%,1/16W,CHIP,GA
PU_BIOS_SPI_WP0_N        R7F30            1        RES_0402-10.0K,1%,1/16W,EMPTY,A
PU_BIOS_SPI_WP0_N        R7F37            2        RES_0402-33.2,1%,1/16W,CHIP,G2A
PU_BIOS_SPI_WP0_N        U7F1             9        W25Q256_XSOI-IC,H25002-001
PU_BIOS_SPI_WP1_N        R3T9             1        RES_0402-10.0K,1%,1/16W,EMPTY,A
PU_BIOS_SPI_WP1_N        R3T12            2        RES_0402-10.0K,1%,1/16W,CHIP,GA
PU_BIOS_SPI_WP1_N        R3U1             2        RES_0402-33.2,1%,1/16W,CHIP,G2A
PU_BIOS_SPI_WP1_N        U3T1             9        W25Q256_XSOI-IC,H25002-001
PU_BIOS_USB_RECOVERY     J7G3             6        CONN12_C73564003_PIP-CONN,C735A
PU_BIOS_USB_RECOVERY     R7G27            2        RES_0402-1.00K,1%,1/16W,CHIP,GA
PU_CPU0_EAR_N            R6D14            2        RES_0402-240,1.0%,1/16W,EMPTY,A
PU_CPU0_EAR_N            U5D1             AJ14     SKX_EXT_B_BGA1-IC,TBD
PU_CPU0_FRMAGENT         R5D3             2        RES_0402-240,1.0%,1/16W,CHIP,GA
PU_CPU0_FRMAGENT         U5D1             AV17     SKX_EXT_B_BGA1-IC,TBD
PU_CPU0_LEGACY_SKT       R4P14            2        RES_0402-240,1.0%,1/16W,CHIP,GA
PU_CPU0_LEGACY_SKT       U5D1             AE20     SKX_EXT_B_BGA1-IC,TBD
PU_CPU0_SAFE_MODE_BOOT   R6D13            2        RES_0402-240,1.0%,1/16W,EMPTY,A
PU_CPU0_SAFE_MODE_BOOT   U5D1             AR18     SKX_EXT_B_BGA1-IC,TBD
PU_CPU0_SOCKET_ID_0      R6D15            2        RES_0402-240,1.0%,1/16W,EMPTY,A
PU_CPU0_SOCKET_ID_0      U5D1             AU22     SKX_EXT_B_BGA1-IC,TBD
PU_CPU0_SOCKET_ID_1      R6D10            2        RES_0402-240,1.0%,1/16W,EMPTY,A
PU_CPU0_SOCKET_ID_1      U5D1             AU16     SKX_EXT_B_BGA1-IC,TBD
PU_CPU0_TSC_SYNC         R4P21            2        RES_0402-240,1.0%,1/16W,CHIP,GA
PU_CPU0_TSC_SYNC         U5D1             AM11     SKX_EXT_B_BGA1-IC,TBD
PU_CPU0_TXT_AGENT        R5D4             2        RES_0402-240,1.0%,1/16W,EMPTY,A
PU_CPU0_TXT_AGENT        U5D1             AW18     SKX_EXT_B_BGA1-IC,TBD
PU_CPU1_EAR_N            R3D25            2        RES_0402-240,1.0%,1/16W,EMPTY,A
PU_CPU1_EAR_N            U2D1             AJ14     SKX_EXT_B_BGA1-IC,TBD
PU_CPU1_FRMAGENT         R3D22            2        RES_0402-240,1.0%,1/16W,EMPTY,A
PU_CPU1_FRMAGENT         U2D1             AV17     SKX_EXT_B_BGA1-IC,TBD
PU_CPU1_LEGACY_SKT       R7P22            2        RES_0402-240,1.0%,1/16W,EMPTY,A
PU_CPU1_LEGACY_SKT       U2D1             AE20     SKX_EXT_B_BGA1-IC,TBD
PU_CPU1_SAFE_MODE_BOOT   R3D26            2        RES_0402-240,1.0%,1/16W,EMPTY,A
PU_CPU1_SAFE_MODE_BOOT   U2D1             AR18     SKX_EXT_B_BGA1-IC,TBD
PU_CPU1_SOCKET_ID_0      R3D24            2        RES_0402-240,1.0%,1/16W,CHIP,GA
PU_CPU1_SOCKET_ID_0      U2D1             AU22     SKX_EXT_B_BGA1-IC,TBD
PU_CPU1_SOCKET_ID_1      R3D17            2        RES_0402-240,1.0%,1/16W,EMPTY,A
PU_CPU1_SOCKET_ID_1      U2D1             AU16     SKX_EXT_B_BGA1-IC,TBD
PU_CPU1_TSC_SYNC         R4C10            2        RES_0402-240,1.0%,1/16W,CHIP,GA
PU_CPU1_TSC_SYNC         U2D1             AM11     SKX_EXT_B_BGA1-IC,TBD
PU_CPU1_TXT_AGENT        R3D23            2        RES_0402-240,1.0%,1/16W,EMPTY,A
PU_CPU1_TXT_AGENT        U2D1             AW18     SKX_EXT_B_BGA1-IC,TBD
PU_DATAIN1_SATA_0_R      J8A1             1D1      CONN72_G97614002_A_CP-CONN,G97A
PU_DATAIN1_SATA_0_R      R2L21            2        RES_0402-2.0K,1%,1/16W,CHIP,G2A
PU_DATAIN1_SATA_1_R      J8A1             2D1      CONN72_G97614002_A_CP-CONN,G97A
PU_DATAIN1_SATA_1_R      R2L23            2        RES_0402-2.0K,1%,1/16W,CHIP,G2A
PU_DATAIN1_SATA_2        J8A2             D1       CONN36_G97614001_CP-CONN,G9761A
PU_DATAIN1_SATA_2        R1L1             2        RES_0402-2.0K,1%,1/16W,CHIP,G2A
PU_FAB2_MARKER_CPLD      R7D42            2        RES_0402-4.75K,1%,1/16W,CHIP,GA
PU_FAB2_MARKER_CPLD      U8D7             K16      LCMXO2_A_256BGA-IC,H63395-001
PU_FM_RCIN_N             R7D2             2        RES_0402-1.00K,1%,1/16W,CHIP,GA
PU_FM_RCIN_N             U7C1             N3       LBG_CORE_QAT_EXT_D_BGA1-IC,H91A
PU_GTL2014_1_DIR         R3P36            2        RES_0402-1.00K,1%,1/16W,CHIP,GA
PU_GTL2014_1_DIR         U3P1             1        GTL2014_SM-IC,D66151-001
PU_GTL2014_2_DIR         R4C8             2        RES_0402-1.00K,1%,1/16W,CHIP,GA
PU_GTL2014_2_DIR         U4C2             1        GTL2014_SM-IC,D66151-001
PU_IRQ_PCH_SCI_WHEA_N    R7D4             2        RES_0402-10.0K,1%,1/16W,CHIP,GA
PU_IRQ_PCH_SCI_WHEA_N    U7C1             R1       LBG_CORE_QAT_EXT_D_BGA1-IC,H91A
PU_IRQ_VRALERT_N         R2N16            2        RES_0402-10.0K,1%,1/16W,CHIP,GA
PU_IRQ_VRALERT_N         U7C1             BN15     LBG_CORE_QAT_EXT_D_BGA1-IC,H91A
PU_JTAG_SPRV_TCK         EU9E1            19       SPRINGVILLE_SM1-IC,G47144-004
PU_JTAG_SPRV_TCK         R9E2             2        RES_0402-10.0K,1%,1/16W,CHIP,GA
PU_JTAG_SPRV_TDI         EU9E1            29       SPRINGVILLE_SM1-IC,G47144-004
PU_JTAG_SPRV_TDI         R9E1             2        RES_0402-10.0K,1%,1/16W,CHIP,GA
PU_JTAG_SPRV_TDO         EU9E1            4        SPRINGVILLE_SM1-IC,G47144-004
PU_JTAG_SPRV_TDO         R9E22            1        RES_0402-10.0K,1%,1/16W,CHIP,GA
PU_JTAG_SPRV_TMS         EU9E1            18       SPRINGVILLE_SM1-IC,G47144-004
PU_JTAG_SPRV_TMS         R9E3             2        RES_0402-10.0K,1%,1/16W,CHIP,GA
PU_KEY_CONN_PIN2_R       J9A1             2        CONN4_D42317002_PIP-CONN,D4231A
PU_KEY_CONN_PIN2_R       R9A16            1        RES_0402-2.21K,1%,1/16W,CHIP,GA
PU_LPC_CLKRUN_N          R7D8             2        RES_0402-10.0K,1%,1/16W,CHIP,GA
PU_LPC_CLKRUN_N          U7C1             AB1      LBG_CORE_QAT_EXT_D_BGA1-IC,H91A
PU_LPC_PME_N             R7D10            2        RES_0402-10.0K,1%,1/16W,CHIP,GA
PU_LPC_PME_N             U7C1             AC2      LBG_CORE_QAT_EXT_D_BGA1-IC,H91A
PU_M2_CLK_REQ_N          J8F1             52       SCONN75K_H17033002_SMT1-SCONN,A
PU_M2_CLK_REQ_N          R8F36            2        RES_0402-10.0K,1%,1/16W,CHIP,GA
PU_NV_HOLD_N             R1R9             2        RES_0402-3.32K,1%,1/16W,CHIP,GA
PU_NV_HOLD_N             U9E1             7        M25PE16_SM-IC,H77797-001
PU_NV_WP_N               R1R3             2        RES_0402-3.32K,1%,1/16W,CHIP,GA
PU_NV_WP_N               U9E1             3        M25PE16_SM-IC,H77797-001
PU_PCH_TLS_ENABLE_STRAP  R8C17            1        RES_0402-1.00K,1%,1/16W,EMPTY,A
PU_PCH_TLS_ENABLE_STRAP  R8C18            2        RES_0402-1.00K,1%,1/16W,CHIP,GA
PU_PCH_TLS_ENABLE_STRAP  U7C1             BY27     LBG_CORE_QAT_EXT_D_BGA1-IC,H91A
PU_PI7C9X1172_I2C_SPI_N  EU9F3            32       PI7C9X1172_QFN-IC,H66899-001
PU_PI7C9X1172_I2C_SPI_N  R9F47            2        RES_0402-4.75K,1%,1/16W,CHIP,GA
PU_PIROM_CPU1_ADDR0      R1C34            2        RES_0402-10.0K,1%,1/16W,CHIP,GA
PU_PIROM_CPU1_ADDR0      U2D1             CU58     SKX_EXT_B_BGA1-IC,TBD
PU_RST_PERST_BIT0        R2R1             2        RES_0402-10.0K,1%,1/16W,CHIP,GA
PU_RST_PERST_BIT0        U8D7             F4       LCMXO2_A_256BGA-IC,H63395-001
PU_RST_PERST_BIT1        R7E6             2        RES_0402-10.0K,1%,1/16W,CHIP,GA
PU_RST_PERST_BIT1        U8D7             B9       LCMXO2_A_256BGA-IC,H63395-001
PU_SPI0_RST              R7F6             2        RES_0402-4.75K,1%,1/16W,EMPTY,A
PU_SPI0_RST              U7F1             3        W25Q256_XSOI-IC,H25002-001
PU_SPI1_RST              R3T3             2        RES_0402-4.75K,1%,1/16W,EMPTY,A
PU_SPI1_RST              U3T1             3        W25Q256_XSOI-IC,H25002-001
PU_SPI_BMC_BT_HOLD_N     R8F14            2        RES_0402-4.75K,1%,1/16W,CHIP,GA
PU_SPI_BMC_BT_HOLD_N     U8F2             1        W25Q128_SKT16-IC,H12709-001
PU_SPI_BMC_BT_WP_N       R8F34            2        RES_0402-4.75K,1%,1/16W,CHIP,GA
PU_SPI_BMC_BT_WP_N       R8F35            1        RES_0402-1.00K,1%,1/16W,EMPTY,A
PU_SPI_BMC_BT_WP_N       U8F2             9        W25Q128_SKT16-IC,H12709-001
PU_SPI_FLASH_RESET_2_N   R8F16            2        RES_0402-4.75K,1%,1/16W,EMPTY,A
PU_SPI_FLASH_RESET_2_N   U8F2             3        W25Q128_SKT16-IC,H12709-001
PU_SPRV_LAN_PWR_GOOD     EU9E1            1        SPRINGVILLE_SM1-IC,G47144-004
PU_SPRV_LAN_PWR_GOOD     R9F5             2        RES_0402-3.32K,1%,1/16W,CHIP,GA
PU_THERMTRIP_FORCE_N     R7E5             2        RES_0402-10.0K,1%,1/16W,CHIP,GA
PU_THERMTRIP_FORCE_N     U8D7             A12      LCMXO2_A_256BGA-IC,H63395-001
PU_TMP421_1_A1           R9B6             2        RES_0402-1.00K,1%,1/16W,CHIP,GA
PU_TMP421_1_A1           U9B4             3        TMP421_TSSOP-IC,G62962-001
PU_TMP421_2_A0           R1E9             2        RES_0402-1.00K,1%,1/16W,CHIP,GA
PU_TMP421_2_A0           U1E1             4        TMP421_TSSOP-IC,G62962-001
PU_TRI_STATE_EN          R8E23            1        RES_0402-4.75K,1%,1/16W,CHIP,GA
PU_TRI_STATE_EN          U8E4             1        TTL1G126_A_SOT-74HC1G126,IC,A7B
PU_VR_PVCCIN_CPU0_FLT1_SMBALT_N EU4D4            20       PXE1610B_QFN-IC,H79206-001
PU_VR_PVCCIN_CPU0_FLT1_SMBALT_N R4E20            2        RES_0402-2.26K,1.0%,1/16W,EMPTA
PU_VR_PVCCIN_CPU0_IMON   EU4D4            39       PXE1610B_QFN-IC,H79206-001
PU_VR_PVCCIN_CPU0_IMON   R4D31            2        RES_0402-2.26K,1.0%,1/16W,EMPTA
PU_VR_PVCCIN_CPU1_FLT1_SMBALT_N EU1C2            20       PXE1610B_QFN-IC,H79206-001
PU_VR_PVCCIN_CPU1_FLT1_SMBALT_N R1D53            2        RES_0402-2.26K,1.0%,1/16W,EMPTA
PU_VR_PVCCIN_CPU1_IMON   EU1C2            39       PXE1610B_QFN-IC,H79206-001
PU_VR_PVCCIN_CPU1_IMON   R1C18            2        RES_0402-2.26K,1.0%,1/16W,EMPTA
PU_VR_PVCCIO_CPU0_FAULT1 EU3P1            32       PXE1110B_QFN-IC,H89187-001
PU_VR_PVCCIO_CPU0_FAULT1 R3N23            2        RES_0402-2.26K,1.0%,1/16W,EMPTA
PU_VR_PVCCIO_CPU1_FAULT1 EU4D5            32       PXE1110B_QFN-IC,H89187-001
PU_VR_PVCCIO_CPU1_FAULT1 R6P49            2        RES_0402-2.26K,1.0%,1/16W,EMPTA
PU_VR_PVDDQ_ABC_FAULT1   EU7G1            13       PXM1310B_QFN-IC,H89186-001
PU_VR_PVDDQ_ABC_FAULT1   R7F36            2        RES_0402-2.26K,1.0%,1/16W,EMPTA
PU_VR_PVDDQ_DEF_FAULT1   EU7A5            13       PXM1310B_QFN-IC,H89186-001
PU_VR_PVDDQ_DEF_FAULT1   R7A9             2        RES_0402-2.26K,1.0%,1/16W,EMPTA
PU_VR_PVDDQ_GHJ_FAULT1   EU1G2            13       PXM1310B_QFN-IC,H89186-001
PU_VR_PVDDQ_GHJ_FAULT1   R1G6             2        RES_0402-2.26K,1.0%,1/16W,EMPTA
PU_VR_PVDDQ_KLM_FAULT1   EU1B1            13       PXM1310B_QFN-IC,H89186-001
PU_VR_PVDDQ_KLM_FAULT1   R1B13            2        RES_0402-2.26K,1.0%,1/16W,EMPTA
PU_VR_PVNN_PCH_FAULT1    EU8A1            32       PXE1110B_QFN-IC,H89187-001
PU_VR_PVNN_PCH_FAULT1    R2L24            2        RES_0402-2.26K,1.0%,1/16W,EMPTA
PVCCIN_CPU0              C4D4             1        CAP_A_0603V-22.0UF,4V,20%,X6S,A
PVCCIN_CPU0              C4D12            1        CAP_A_0603V-22.0UF,4V,20%,X6S,A
PVCCIN_CPU0              C4D34            1        CAP_A_0603V-22.0UF,4V,20%,X6S,A
PVCCIN_CPU0              C4E3             1        CAP_A_0603V-22.0UF,4V,20%,X6S,A
PVCCIN_CPU0              C4E11            1        CAP_A_0603V-22.0UF,4V,20%,X6S,A
PVCCIN_CPU0              C5D1             1        CAP_A_0603V-22.0UF,4V,20%,X6S,A
PVCCIN_CPU0              C5D2             1        CAP_A_0603V-22.0UF,4V,20%,X6S,A
PVCCIN_CPU0              C5D3             1        CAP_A_0603V-22.0UF,4V,20%,X6S,A
PVCCIN_CPU0              C5D4             1        CAP_A_0603V-22.0UF,4V,20%,X6S,A
PVCCIN_CPU0              C5D5             1        CAP_A_0603V-22.0UF,4V,20%,X6S,A
PVCCIN_CPU0              C5D14            1        CAP_A_0603V-22.0UF,4V,20%,X6S,A
PVCCIN_CPU0              C5D15            1        CAP_A_0603V-22.0UF,4V,20%,X6S,A
PVCCIN_CPU0              C5D16            1        CAP_A_0603V-22.0UF,4V,20%,X6S,A
PVCCIN_CPU0              C5D17            1        CAP_A_0603V-22.0UF,4V,20%,X6S,A
PVCCIN_CPU0              C5D18            1        CAP_A_0603V-22.0UF,4V,20%,X6S,A
PVCCIN_CPU0              C5D19            1        CAP_A_0603V-22.0UF,4V,20%,X6S,A
PVCCIN_CPU0              C5D24            1        CAP_A_0603V-22.0UF,4V,20%,X6S,A
PVCCIN_CPU0              C5D25            1        CAP_A_0603V-22.0UF,4V,20%,X6S,A
PVCCIN_CPU0              C5D26            1        CAP_A_0603V-22.0UF,4V,20%,X6S,A
PVCCIN_CPU0              C5D27            1        CAP_A_0603V-22.0UF,4V,20%,X6S,A
PVCCIN_CPU0              C5D28            1        CAP_A_0603V-22.0UF,4V,20%,X6S,A
PVCCIN_CPU0              C5D29            1        CAP_A_0603V-22.0UF,4V,20%,X6S,A
PVCCIN_CPU0              C5D30            1        CAP_A_0603V-22.0UF,4V,20%,X6S,A
PVCCIN_CPU0              C5D31            1        CAP_A_0603V-22.0UF,4V,20%,X6S,A
PVCCIN_CPU0              C5D32            1        CAP_A_0603V-22.0UF,4V,20%,X6S,A
PVCCIN_CPU0              C5D39            1        CAP_A_0603V-22.0UF,4V,20%,X6S,A
PVCCIN_CPU0              C5D40            1        CAP_A_0603V-22.0UF,4V,20%,X6S,A
PVCCIN_CPU0              C5D41            1        CAP_A_0603V-22.0UF,4V,20%,X6S,A
PVCCIN_CPU0              C5D42            1        CAP_A_0603V-22.0UF,4V,20%,X6S,A
PVCCIN_CPU0              C5D43            1        CAP_A_0603V-22.0UF,4V,20%,X6S,A
PVCCIN_CPU0              C5D44            1        CAP_A_0603V-22.0UF,4V,20%,X6S,A
PVCCIN_CPU0              C5D45            1        CAP_A_0603V-22.0UF,4V,20%,X6S,A
PVCCIN_CPU0              C5D46            1        CAP_A_0603V-22.0UF,4V,20%,X6S,A
PVCCIN_CPU0              C5D47            1        CAP_A_0603V-22.0UF,4V,20%,X6S,A
PVCCIN_CPU0              C5D58            1        CAP_A_0603V-22.0UF,4V,20%,X6S,A
PVCCIN_CPU0              C5D59            1        CAP_A_0603V-22.0UF,4V,20%,X6S,A
PVCCIN_CPU0              C5D60            1        CAP_A_0603V-22.0UF,4V,20%,X6S,A
PVCCIN_CPU0              C5D61            1        CAP_A_0603V-22.0UF,4V,20%,X6S,A
PVCCIN_CPU0              C5P3             1        CAP_0805-47UF,4V,20%,X6S,C9533A
PVCCIN_CPU0              C5P4             1        CAP_0805-47UF,4V,20%,X6S,C9533A
PVCCIN_CPU0              C5P5             1        CAP_0805-47UF,4V,20%,X6S,C9533A
PVCCIN_CPU0              C5P6             1        CAP_0805-47UF,4V,20%,X6S,C9533A
PVCCIN_CPU0              C5P14            1        CAP_0805-47UF,4V,20%,X6S,C9533A
PVCCIN_CPU0              C5P15            1        CAP_0805-47UF,4V,20%,X6S,C9533A
PVCCIN_CPU0              C5P16            1        CAP_0805-47UF,4V,20%,X6S,C9533A
PVCCIN_CPU0              C5P17            1        CAP_0805-47UF,4V,20%,X6S,C9533A
PVCCIN_CPU0              C5P22            1        CAP_0805-47UF,4V,20%,X6S,C9533A
PVCCIN_CPU0              C5P23            1        CAP_0805-47UF,4V,20%,X6S,C9533A
PVCCIN_CPU0              C5P24            1        CAP_0805-47UF,4V,20%,X6S,C9533A
PVCCIN_CPU0              C5P25            1        CAP_0805-47UF,4V,20%,X6S,C9533A
PVCCIN_CPU0              C5P26            1        CAP_0805-47UF,4V,20%,X6S,C9533A
PVCCIN_CPU0              C5P27            1        CAP_0805-47UF,4V,20%,X6S,C9533A
PVCCIN_CPU0              C5P32            1        CAP_0805-47UF,4V,20%,X6S,C9533A
PVCCIN_CPU0              C5P33            1        CAP_0805-47UF,4V,20%,X6S,C9533A
PVCCIN_CPU0              C5P34            1        CAP_0805-47UF,4V,20%,X6S,C9533A
PVCCIN_CPU0              C5P35            1        CAP_0805-47UF,4V,20%,X6S,C9533A
PVCCIN_CPU0              C5P36            1        CAP_0805-47UF,4V,20%,X6S,C9533A
PVCCIN_CPU0              C5P37            1        CAP_0805-47UF,4V,20%,X6S,C9533A
PVCCIN_CPU0              C5P40            1        CAP_0805-47UF,4V,20%,X6S,C9533A
PVCCIN_CPU0              C5P41            1        CAP_0805-47UF,4V,20%,X6S,C9533A
PVCCIN_CPU0              C5P42            1        CAP_0805-47UF,4V,20%,X6S,C9533A
PVCCIN_CPU0              C5P43            1        CAP_0805-47UF,4V,20%,X6S,C9533A
PVCCIN_CPU0              C5P44            1        CAP_0805-47UF,4V,20%,X6S,C9533A
PVCCIN_CPU0              C6N9             1        CAPP_3018-470UF,2.5V,20%,ALUM,A
PVCCIN_CPU0              C6P3             1        CAP_A_0603V-22.0UF,4V,20%,X6S,A
PVCCIN_CPU0              C6P8             1        CAPP_3018-470UF,2.5V,20%,ALUM,A
PVCCIN_CPU0              C6P14            1        CAPP_3018-470UF,2.5V,20%,ALUM,A
PVCCIN_CPU0              C6P16            1        CAP_A_0603V-22.0UF,4V,20%,X6S,A
PVCCIN_CPU0              C6P18            1        CAPP_3018-470UF,2.5V,20%,ALUM,A
PVCCIN_CPU0              C6P21            1        CAP_A_0603V-22.0UF,4V,20%,X6S,A
PVCCIN_CPU0              C6P23            1        CAPP_3018-470UF,2.5V,20%,ALUM,A
PVCCIN_CPU0              C6R2             1        CAP_A_0603V-22.0UF,4V,20%,X6S,A
PVCCIN_CPU0              C6R3             1        CAPP_3018-470UF,2.5V,20%,ALUM,A
PVCCIN_CPU0              C6R7             1        CAP_A_0603V-22.0UF,4V,20%,X6S,A
PVCCIN_CPU0              C6R9             1        CAPP_3018-470UF,2.5V,20%,ALUM,A
PVCCIN_CPU0              EU4C2            1        IR354XX_SM-IR35411,IC,H73688-0A
PVCCIN_CPU0              EU4D1            1        IR354XX_SM-IR35411,IC,H73688-0A
PVCCIN_CPU0              EU4D3            1        IR354XX_SM-IR35411,IC,H73688-0A
PVCCIN_CPU0              EU4D6            1        IR354XX_SM-IR35411,IC,H73688-0A
PVCCIN_CPU0              EU4E1            1        IR354XX_SM-IR35411,IC,H73688-0A
PVCCIN_CPU0              L4C3             2        INDUCTOR_SM-0.12UH,IND,D92183-A
PVCCIN_CPU0              L4D1             2        INDUCTOR_SM-0.12UH,IND,D92183-A
PVCCIN_CPU0              L4D2             2        INDUCTOR_SM-0.12UH,IND,D92183-A
PVCCIN_CPU0              L4D3             2        INDUCTOR_SM-0.12UH,IND,D92183-A
PVCCIN_CPU0              L4E1             2        INDUCTOR_SM-0.12UH,IND,D92183-A
PVCCIN_CPU0              R4E13            1        RES_0603-100.0,1%,1/10W,CHIP,GA
PVCCIN_CPU0              R4E14            2        RES_0402-100.0,1%,1/16W,CHIP,GA
PVCCIN_CPU0              R5P1             1        RES_0603-100.0K,1%,1/10W,CHIP,A
PVCCIN_CPU0              U5D1             AF43     SKX_EXT_B_BGA1-IC,TBD
PVCCIN_CPU0              U5D1             AG38     SKX_EXT_B_BGA1-IC,TBD
PVCCIN_CPU0              U5D1             AG40     SKX_EXT_B_BGA1-IC,TBD
PVCCIN_CPU0              U5D1             AG42     SKX_EXT_B_BGA1-IC,TBD
PVCCIN_CPU0              U5D1             AH37     SKX_EXT_B_BGA1-IC,TBD
PVCCIN_CPU0              U5D1             AH39     SKX_EXT_B_BGA1-IC,TBD
PVCCIN_CPU0              U5D1             AH41     SKX_EXT_B_BGA1-IC,TBD
PVCCIN_CPU0              U5D1             AJ36     SKX_EXT_B_BGA1-IC,TBD
PVCCIN_CPU0              U5D1             AK35     SKX_EXT_B_BGA1-IC,TBD
PVCCIN_CPU0              U5D1             AK45     SKX_EXT_B_BGA1-IC,TBD
PVCCIN_CPU0              U5D1             AK47     SKX_EXT_B_BGA1-IC,TBD
PVCCIN_CPU0              U5D1             AK49     SKX_EXT_B_BGA1-IC,TBD
PVCCIN_CPU0              U5D1             AK51     SKX_EXT_B_BGA1-IC,TBD
PVCCIN_CPU0              U5D1             AK53     SKX_EXT_B_BGA1-IC,TBD
PVCCIN_CPU0              U5D1             AL34     SKX_EXT_B_BGA1-IC,TBD
PVCCIN_CPU0              U5D1             AL46     SKX_EXT_B_BGA1-IC,TBD
PVCCIN_CPU0              U5D1             AL48     SKX_EXT_B_BGA1-IC,TBD
PVCCIN_CPU0              U5D1             AL50     SKX_EXT_B_BGA1-IC,TBD
PVCCIN_CPU0              U5D1             AL52     SKX_EXT_B_BGA1-IC,TBD
PVCCIN_CPU0              U5D1             AL54     SKX_EXT_B_BGA1-IC,TBD
PVCCIN_CPU0              U5D1             AM33     SKX_EXT_B_BGA1-IC,TBD
PVCCIN_CPU0              U5D1             AM53     SKX_EXT_B_BGA1-IC,TBD
PVCCIN_CPU0              U5D1             AM55     SKX_EXT_B_BGA1-IC,TBD
PVCCIN_CPU0              U5D1             AN32     SKX_EXT_B_BGA1-IC,TBD
PVCCIN_CPU0              U5D1             AN54     SKX_EXT_B_BGA1-IC,TBD
PVCCIN_CPU0              U5D1             AN56     SKX_EXT_B_BGA1-IC,TBD
PVCCIN_CPU0              U5D1             AP55     SKX_EXT_B_BGA1-IC,TBD
PVCCIN_CPU0              U5D1             AP57     SKX_EXT_B_BGA1-IC,TBD
PVCCIN_CPU0              U5D1             AR56     SKX_EXT_B_BGA1-IC,TBD
PVCCIN_CPU0              U5D1             AR58     SKX_EXT_B_BGA1-IC,TBD
PVCCIN_CPU0              U5D1             AT57     SKX_EXT_B_BGA1-IC,TBD
PVCCIN_CPU0              U5D1             AT59     SKX_EXT_B_BGA1-IC,TBD
PVCCIN_CPU0              U5D1             AU58     SKX_EXT_B_BGA1-IC,TBD
PVCCIN_CPU0              U5D1             AU60     SKX_EXT_B_BGA1-IC,TBD
PVCCIN_CPU0              U5D1             AV59     SKX_EXT_B_BGA1-IC,TBD
PVCCIN_CPU0              U5D1             AV61     SKX_EXT_B_BGA1-IC,TBD
PVCCIN_CPU0              U5D1             AW60     SKX_EXT_B_BGA1-IC,TBD
PVCCIN_CPU0              U5D1             AY61     SKX_EXT_B_BGA1-IC,TBD
PVCCIN_CPU0              U5D1             BA60     SKX_EXT_B_BGA1-IC,TBD
PVCCIN_CPU0              U5D1             BB61     SKX_EXT_B_BGA1-IC,TBD
PVCCIN_CPU0              U5D1             BB85     SKX_EXT_B_BGA1-IC,TBD
PVCCIN_CPU0              U5D1             BC60     SKX_EXT_B_BGA1-IC,TBD
PVCCIN_CPU0              U5D1             BC62     SKX_EXT_B_BGA1-IC,TBD
PVCCIN_CPU0              U5D1             BC84     SKX_EXT_B_BGA1-IC,TBD
PVCCIN_CPU0              U5D1             BD61     SKX_EXT_B_BGA1-IC,TBD
PVCCIN_CPU0              U5D1             BD73     SKX_EXT_B_BGA1-IC,TBD
PVCCIN_CPU0              U5D1             BD75     SKX_EXT_B_BGA1-IC,TBD
PVCCIN_CPU0              U5D1             BD77     SKX_EXT_B_BGA1-IC,TBD
PVCCIN_CPU0              U5D1             BD79     SKX_EXT_B_BGA1-IC,TBD
PVCCIN_CPU0              U5D1             BD81     SKX_EXT_B_BGA1-IC,TBD
PVCCIN_CPU0              U5D1             BD83     SKX_EXT_B_BGA1-IC,TBD
PVCCIN_CPU0              U5D1             BD85     SKX_EXT_B_BGA1-IC,TBD
PVCCIN_CPU0              U5D1             BE60     SKX_EXT_B_BGA1-IC,TBD
PVCCIN_CPU0              U5D1             BE62     SKX_EXT_B_BGA1-IC,TBD
PVCCIN_CPU0              U5D1             BE72     SKX_EXT_B_BGA1-IC,TBD
PVCCIN_CPU0              U5D1             BE74     SKX_EXT_B_BGA1-IC,TBD
PVCCIN_CPU0              U5D1             BE76     SKX_EXT_B_BGA1-IC,TBD
PVCCIN_CPU0              U5D1             BE78     SKX_EXT_B_BGA1-IC,TBD
PVCCIN_CPU0              U5D1             BE80     SKX_EXT_B_BGA1-IC,TBD
PVCCIN_CPU0              U5D1             BE82     SKX_EXT_B_BGA1-IC,TBD
PVCCIN_CPU0              U5D1             BE84     SKX_EXT_B_BGA1-IC,TBD
PVCCIN_CPU0              U5D1             BF61     SKX_EXT_B_BGA1-IC,TBD
PVCCIN_CPU0              U5D1             BF73     SKX_EXT_B_BGA1-IC,TBD
PVCCIN_CPU0              U5D1             BF75     SKX_EXT_B_BGA1-IC,TBD
PVCCIN_CPU0              U5D1             BF77     SKX_EXT_B_BGA1-IC,TBD
PVCCIN_CPU0              U5D1             BF79     SKX_EXT_B_BGA1-IC,TBD
PVCCIN_CPU0              U5D1             BF81     SKX_EXT_B_BGA1-IC,TBD
PVCCIN_CPU0              U5D1             BF83     SKX_EXT_B_BGA1-IC,TBD
PVCCIN_CPU0              U5D1             BF85     SKX_EXT_B_BGA1-IC,TBD
PVCCIN_CPU0              U5D1             BG60     SKX_EXT_B_BGA1-IC,TBD
PVCCIN_CPU0              U5D1             BG62     SKX_EXT_B_BGA1-IC,TBD
PVCCIN_CPU0              U5D1             BG64     SKX_EXT_B_BGA1-IC,TBD
PVCCIN_CPU0              U5D1             BG66     SKX_EXT_B_BGA1-IC,TBD
PVCCIN_CPU0              U5D1             BG68     SKX_EXT_B_BGA1-IC,TBD
PVCCIN_CPU0              U5D1             BG70     SKX_EXT_B_BGA1-IC,TBD
PVCCIN_CPU0              U5D1             BG84     SKX_EXT_B_BGA1-IC,TBD
PVCCIN_CPU0              U5D1             BH61     SKX_EXT_B_BGA1-IC,TBD
PVCCIN_CPU0              U5D1             BH63     SKX_EXT_B_BGA1-IC,TBD
PVCCIN_CPU0              U5D1             BH65     SKX_EXT_B_BGA1-IC,TBD
PVCCIN_CPU0              U5D1             BH67     SKX_EXT_B_BGA1-IC,TBD
PVCCIN_CPU0              U5D1             BH69     SKX_EXT_B_BGA1-IC,TBD
PVCCIN_CPU0              U5D1             BH71     SKX_EXT_B_BGA1-IC,TBD
PVCCIN_CPU0              U5D1             BH73     SKX_EXT_B_BGA1-IC,TBD
PVCCIN_CPU0              U5D1             BH75     SKX_EXT_B_BGA1-IC,TBD
PVCCIN_CPU0              U5D1             BH77     SKX_EXT_B_BGA1-IC,TBD
PVCCIN_CPU0              U5D1             BH79     SKX_EXT_B_BGA1-IC,TBD
PVCCIN_CPU0              U5D1             BH81     SKX_EXT_B_BGA1-IC,TBD
PVCCIN_CPU0              U5D1             BH83     SKX_EXT_B_BGA1-IC,TBD
PVCCIN_CPU0              U5D1             BJ60     SKX_EXT_B_BGA1-IC,TBD
PVCCIN_CPU0              U5D1             BJ62     SKX_EXT_B_BGA1-IC,TBD
PVCCIN_CPU0              U5D1             BJ64     SKX_EXT_B_BGA1-IC,TBD
PVCCIN_CPU0              U5D1             BJ66     SKX_EXT_B_BGA1-IC,TBD
PVCCIN_CPU0              U5D1             BJ68     SKX_EXT_B_BGA1-IC,TBD
PVCCIN_CPU0              U5D1             BJ70     SKX_EXT_B_BGA1-IC,TBD
PVCCIN_CPU0              U5D1             BJ72     SKX_EXT_B_BGA1-IC,TBD
PVCCIN_CPU0              U5D1             BJ74     SKX_EXT_B_BGA1-IC,TBD
PVCCIN_CPU0              U5D1             BJ76     SKX_EXT_B_BGA1-IC,TBD
PVCCIN_CPU0              U5D1             BJ78     SKX_EXT_B_BGA1-IC,TBD
PVCCIN_CPU0              U5D1             BJ80     SKX_EXT_B_BGA1-IC,TBD
PVCCIN_CPU0              U5D1             BJ82     SKX_EXT_B_BGA1-IC,TBD
PVCCIN_CPU0              U5D1             BJ84     SKX_EXT_B_BGA1-IC,TBD
PVCCIN_CPU0              U5D1             BK61     SKX_EXT_B_BGA1-IC,TBD
PVCCIN_CPU0              U5D1             BK63     SKX_EXT_B_BGA1-IC,TBD
PVCCIN_CPU0              U5D1             BK65     SKX_EXT_B_BGA1-IC,TBD
PVCCIN_CPU0              U5D1             BK67     SKX_EXT_B_BGA1-IC,TBD
PVCCIN_CPU0              U5D1             BK69     SKX_EXT_B_BGA1-IC,TBD
PVCCIN_CPU0              U5D1             BK71     SKX_EXT_B_BGA1-IC,TBD
PVCCIN_CPU0              U5D1             BK73     SKX_EXT_B_BGA1-IC,TBD
PVCCIN_CPU0              U5D1             BK75     SKX_EXT_B_BGA1-IC,TBD
PVCCIN_CPU0              U5D1             BK77     SKX_EXT_B_BGA1-IC,TBD
PVCCIN_CPU0              U5D1             BK79     SKX_EXT_B_BGA1-IC,TBD
PVCCIN_CPU0              U5D1             BK81     SKX_EXT_B_BGA1-IC,TBD
PVCCIN_CPU0              U5D1             BK83     SKX_EXT_B_BGA1-IC,TBD
PVCCIN_CPU0              U5D1             BL60     SKX_EXT_B_BGA1-IC,TBD
PVCCIN_CPU0              U5D1             BL62     SKX_EXT_B_BGA1-IC,TBD
PVCCIN_CPU0              U5D1             BL84     SKX_EXT_B_BGA1-IC,TBD
PVCCIN_CPU0              U5D1             BM61     SKX_EXT_B_BGA1-IC,TBD
PVCCIN_CPU0              U5D1             BM63     SKX_EXT_B_BGA1-IC,TBD
PVCCIN_CPU0              U5D1             BM65     SKX_EXT_B_BGA1-IC,TBD
PVCCIN_CPU0              U5D1             BM67     SKX_EXT_B_BGA1-IC,TBD
PVCCIN_CPU0              U5D1             BM69     SKX_EXT_B_BGA1-IC,TBD
PVCCIN_CPU0              U5D1             BM71     SKX_EXT_B_BGA1-IC,TBD
PVCCIN_CPU0              U5D1             BM73     SKX_EXT_B_BGA1-IC,TBD
PVCCIN_CPU0              U5D1             BM75     SKX_EXT_B_BGA1-IC,TBD
PVCCIN_CPU0              U5D1             BM77     SKX_EXT_B_BGA1-IC,TBD
PVCCIN_CPU0              U5D1             BM79     SKX_EXT_B_BGA1-IC,TBD
PVCCIN_CPU0              U5D1             BM81     SKX_EXT_B_BGA1-IC,TBD
PVCCIN_CPU0              U5D1             BM83     SKX_EXT_B_BGA1-IC,TBD
PVCCIN_CPU0              U5D1             BN60     SKX_EXT_B_BGA1-IC,TBD
PVCCIN_CPU0              U5D1             BN62     SKX_EXT_B_BGA1-IC,TBD
PVCCIN_CPU0              U5D1             BN64     SKX_EXT_B_BGA1-IC,TBD
PVCCIN_CPU0              U5D1             BN66     SKX_EXT_B_BGA1-IC,TBD
PVCCIN_CPU0              U5D1             BN68     SKX_EXT_B_BGA1-IC,TBD
PVCCIN_CPU0              U5D1             BN70     SKX_EXT_B_BGA1-IC,TBD
PVCCIN_CPU0              U5D1             BN72     SKX_EXT_B_BGA1-IC,TBD
PVCCIN_CPU0              U5D1             BN74     SKX_EXT_B_BGA1-IC,TBD
PVCCIN_CPU0              U5D1             BN76     SKX_EXT_B_BGA1-IC,TBD
PVCCIN_CPU0              U5D1             BN78     SKX_EXT_B_BGA1-IC,TBD
PVCCIN_CPU0              U5D1             BN80     SKX_EXT_B_BGA1-IC,TBD
PVCCIN_CPU0              U5D1             BN82     SKX_EXT_B_BGA1-IC,TBD
PVCCIN_CPU0              U5D1             BN84     SKX_EXT_B_BGA1-IC,TBD
PVCCIN_CPU0              U5D1             BP61     SKX_EXT_B_BGA1-IC,TBD
PVCCIN_CPU0              U5D1             BP63     SKX_EXT_B_BGA1-IC,TBD
PVCCIN_CPU0              U5D1             BP65     SKX_EXT_B_BGA1-IC,TBD
PVCCIN_CPU0              U5D1             BP67     SKX_EXT_B_BGA1-IC,TBD
PVCCIN_CPU0              U5D1             BP69     SKX_EXT_B_BGA1-IC,TBD
PVCCIN_CPU0              U5D1             BP71     SKX_EXT_B_BGA1-IC,TBD
PVCCIN_CPU0              U5D1             BP73     SKX_EXT_B_BGA1-IC,TBD
PVCCIN_CPU0              U5D1             BP75     SKX_EXT_B_BGA1-IC,TBD
PVCCIN_CPU0              U5D1             BP77     SKX_EXT_B_BGA1-IC,TBD
PVCCIN_CPU0              U5D1             BP79     SKX_EXT_B_BGA1-IC,TBD
PVCCIN_CPU0              U5D1             BP81     SKX_EXT_B_BGA1-IC,TBD
PVCCIN_CPU0              U5D1             BP83     SKX_EXT_B_BGA1-IC,TBD
PVCCIN_CPU0              U5D1             BR60     SKX_EXT_B_BGA1-IC,TBD
PVCCIN_CPU0              U5D1             BR62     SKX_EXT_B_BGA1-IC,TBD
PVCCIN_CPU0              U5D1             BR84     SKX_EXT_B_BGA1-IC,TBD
PVCCIN_CPU0              U5D1             BT61     SKX_EXT_B_BGA1-IC,TBD
PVCCIN_CPU0              U5D1             BT63     SKX_EXT_B_BGA1-IC,TBD
PVCCIN_CPU0              U5D1             BT65     SKX_EXT_B_BGA1-IC,TBD
PVCCIN_CPU0              U5D1             BT67     SKX_EXT_B_BGA1-IC,TBD
PVCCIN_CPU0              U5D1             BT69     SKX_EXT_B_BGA1-IC,TBD
PVCCIN_CPU0              U5D1             BT71     SKX_EXT_B_BGA1-IC,TBD
PVCCIN_CPU0              U5D1             BT73     SKX_EXT_B_BGA1-IC,TBD
PVCCIN_CPU0              U5D1             BT75     SKX_EXT_B_BGA1-IC,TBD
PVCCIN_CPU0              U5D1             BT77     SKX_EXT_B_BGA1-IC,TBD
PVCCIN_CPU0              U5D1             BT79     SKX_EXT_B_BGA1-IC,TBD
PVCCIN_CPU0              U5D1             BT81     SKX_EXT_B_BGA1-IC,TBD
PVCCIN_CPU0              U5D1             BT83     SKX_EXT_B_BGA1-IC,TBD
PVCCIN_CPU0              U5D1             BU60     SKX_EXT_B_BGA1-IC,TBD
PVCCIN_CPU0              U5D1             BU62     SKX_EXT_B_BGA1-IC,TBD
PVCCIN_CPU0              U5D1             BU64     SKX_EXT_B_BGA1-IC,TBD
PVCCIN_CPU0              U5D1             BU66     SKX_EXT_B_BGA1-IC,TBD
PVCCIN_CPU0              U5D1             BU68     SKX_EXT_B_BGA1-IC,TBD
PVCCIN_CPU0              U5D1             BU70     SKX_EXT_B_BGA1-IC,TBD
PVCCIN_CPU0              U5D1             BU72     SKX_EXT_B_BGA1-IC,TBD
PVCCIN_CPU0              U5D1             BU74     SKX_EXT_B_BGA1-IC,TBD
PVCCIN_CPU0              U5D1             BU76     SKX_EXT_B_BGA1-IC,TBD
PVCCIN_CPU0              U5D1             BU78     SKX_EXT_B_BGA1-IC,TBD
PVCCIN_CPU0              U5D1             BU80     SKX_EXT_B_BGA1-IC,TBD
PVCCIN_CPU0              U5D1             BU82     SKX_EXT_B_BGA1-IC,TBD
PVCCIN_CPU0              U5D1             BU84     SKX_EXT_B_BGA1-IC,TBD
PVCCIN_CPU0              U5D1             BV61     SKX_EXT_B_BGA1-IC,TBD
PVCCIN_CPU0              U5D1             BV63     SKX_EXT_B_BGA1-IC,TBD
PVCCIN_CPU0              U5D1             BV65     SKX_EXT_B_BGA1-IC,TBD
PVCCIN_CPU0              U5D1             BV67     SKX_EXT_B_BGA1-IC,TBD
PVCCIN_CPU0              U5D1             BV69     SKX_EXT_B_BGA1-IC,TBD
PVCCIN_CPU0              U5D1             BV71     SKX_EXT_B_BGA1-IC,TBD
PVCCIN_CPU0              U5D1             BV73     SKX_EXT_B_BGA1-IC,TBD
PVCCIN_CPU0              U5D1             BV75     SKX_EXT_B_BGA1-IC,TBD
PVCCIN_CPU0              U5D1             BV77     SKX_EXT_B_BGA1-IC,TBD
PVCCIN_CPU0              U5D1             BV79     SKX_EXT_B_BGA1-IC,TBD
PVCCIN_CPU0              U5D1             BV81     SKX_EXT_B_BGA1-IC,TBD
PVCCIN_CPU0              U5D1             BV83     SKX_EXT_B_BGA1-IC,TBD
PVCCIN_CPU0              U5D1             BW60     SKX_EXT_B_BGA1-IC,TBD
PVCCIN_CPU0              U5D1             BW62     SKX_EXT_B_BGA1-IC,TBD
PVCCIN_CPU0              U5D1             BW64     SKX_EXT_B_BGA1-IC,TBD
PVCCIN_CPU0              U5D1             BW66     SKX_EXT_B_BGA1-IC,TBD
PVCCIN_CPU0              U5D1             BW68     SKX_EXT_B_BGA1-IC,TBD
PVCCIN_CPU0              U5D1             BW70     SKX_EXT_B_BGA1-IC,TBD
PVCCIN_CPU0              U5D1             BW84     SKX_EXT_B_BGA1-IC,TBD
PVCCIN_CPU0              U5D1             BY61     SKX_EXT_B_BGA1-IC,TBD
PVCCIN_CPU0              U5D1             BY73     SKX_EXT_B_BGA1-IC,TBD
PVCCIN_CPU0              U5D1             BY75     SKX_EXT_B_BGA1-IC,TBD
PVCCIN_CPU0              U5D1             BY77     SKX_EXT_B_BGA1-IC,TBD
PVCCIN_CPU0              U5D1             BY79     SKX_EXT_B_BGA1-IC,TBD
PVCCIN_CPU0              U5D1             BY81     SKX_EXT_B_BGA1-IC,TBD
PVCCIN_CPU0              U5D1             BY83     SKX_EXT_B_BGA1-IC,TBD
PVCCIN_CPU0              U5D1             CA60     SKX_EXT_B_BGA1-IC,TBD
PVCCIN_CPU0              U5D1             CA62     SKX_EXT_B_BGA1-IC,TBD
PVCCIN_CPU0              U5D1             CA72     SKX_EXT_B_BGA1-IC,TBD
PVCCIN_CPU0              U5D1             CA74     SKX_EXT_B_BGA1-IC,TBD
PVCCIN_CPU0              U5D1             CA76     SKX_EXT_B_BGA1-IC,TBD
PVCCIN_CPU0              U5D1             CA78     SKX_EXT_B_BGA1-IC,TBD
PVCCIN_CPU0              U5D1             CA80     SKX_EXT_B_BGA1-IC,TBD
PVCCIN_CPU0              U5D1             CA82     SKX_EXT_B_BGA1-IC,TBD
PVCCIN_CPU0              U5D1             CA84     SKX_EXT_B_BGA1-IC,TBD
PVCCIN_CPU0              U5D1             CB61     SKX_EXT_B_BGA1-IC,TBD
PVCCIN_CPU0              U5D1             CB73     SKX_EXT_B_BGA1-IC,TBD
PVCCIN_CPU0              U5D1             CB75     SKX_EXT_B_BGA1-IC,TBD
PVCCIN_CPU0              U5D1             CB77     SKX_EXT_B_BGA1-IC,TBD
PVCCIN_CPU0              U5D1             CB79     SKX_EXT_B_BGA1-IC,TBD
PVCCIN_CPU0              U5D1             CB81     SKX_EXT_B_BGA1-IC,TBD
PVCCIN_CPU0              U5D1             CB83     SKX_EXT_B_BGA1-IC,TBD
PVCCIN_CPU0              U5D1             CC60     SKX_EXT_B_BGA1-IC,TBD
PVCCIN_CPU0              U5D1             CC62     SKX_EXT_B_BGA1-IC,TBD
PVCCIN_CPU0              U5D1             CC84     SKX_EXT_B_BGA1-IC,TBD
PVCCIN_CPU0              U5D1             CD61     SKX_EXT_B_BGA1-IC,TBD
PVCCIN_CPU0              U5D1             CD83     SKX_EXT_B_BGA1-IC,TBD
PVCCIN_CPU0              U5D1             CD85     SKX_EXT_B_BGA1-IC,TBD
PVCCIN_CPU0              U5D1             CE60     SKX_EXT_B_BGA1-IC,TBD
PVCCIN_CPU0              U5D1             CE84     SKX_EXT_B_BGA1-IC,TBD
PVCCIN_CPU0              U5D1             CF61     SKX_EXT_B_BGA1-IC,TBD
PVCCIN_CPU0              U5D1             CF85     SKX_EXT_B_BGA1-IC,TBD
PVCCIN_CPU0              U5D1             CG60     SKX_EXT_B_BGA1-IC,TBD
PVCCIN_CPU0              U5D1             CG84     SKX_EXT_B_BGA1-IC,TBD
PVCCIN_CPU0              U5D1             CH61     SKX_EXT_B_BGA1-IC,TBD
PVCCIN_CPU0              U5D1             CH85     SKX_EXT_B_BGA1-IC,TBD
PVCCIN_CPU0              U5D1             CJ60     SKX_EXT_B_BGA1-IC,TBD
PVCCIN_CPU0              U5D1             CK59     SKX_EXT_B_BGA1-IC,TBD
PVCCIN_CPU0              U5D1             CK61     SKX_EXT_B_BGA1-IC,TBD
PVCCIN_CPU0              U5D1             CL58     SKX_EXT_B_BGA1-IC,TBD
PVCCIN_CPU0              U5D1             CL60     SKX_EXT_B_BGA1-IC,TBD
PVCCIN_CPU0              U5D1             CM57     SKX_EXT_B_BGA1-IC,TBD
PVCCIN_CPU0              U5D1             CM59     SKX_EXT_B_BGA1-IC,TBD
PVCCIN_CPU0              U5D1             CN56     SKX_EXT_B_BGA1-IC,TBD
PVCCIN_CPU0              U5D1             CN58     SKX_EXT_B_BGA1-IC,TBD
PVCCIN_CPU0              U5D1             CP33     SKX_EXT_B_BGA1-IC,TBD
PVCCIN_CPU0              U5D1             CP55     SKX_EXT_B_BGA1-IC,TBD
PVCCIN_CPU0              U5D1             CP57     SKX_EXT_B_BGA1-IC,TBD
PVCCIN_CPU0              U5D1             CR34     SKX_EXT_B_BGA1-IC,TBD
PVCCIN_CPU0              U5D1             CR54     SKX_EXT_B_BGA1-IC,TBD
PVCCIN_CPU0              U5D1             CR56     SKX_EXT_B_BGA1-IC,TBD
PVCCIN_CPU0              U5D1             CT37     SKX_EXT_B_BGA1-IC,TBD
PVCCIN_CPU0              U5D1             CT39     SKX_EXT_B_BGA1-IC,TBD
PVCCIN_CPU0              U5D1             CT41     SKX_EXT_B_BGA1-IC,TBD
PVCCIN_CPU0              U5D1             CT53     SKX_EXT_B_BGA1-IC,TBD
PVCCIN_CPU0              U5D1             CT55     SKX_EXT_B_BGA1-IC,TBD
PVCCIN_CPU0              U5D1             CU38     SKX_EXT_B_BGA1-IC,TBD
PVCCIN_CPU0              U5D1             CU40     SKX_EXT_B_BGA1-IC,TBD
PVCCIN_CPU0              U5D1             CU42     SKX_EXT_B_BGA1-IC,TBD
PVCCIN_CPU0              U5D1             CU52     SKX_EXT_B_BGA1-IC,TBD
PVCCIN_CPU0              U5D1             CU54     SKX_EXT_B_BGA1-IC,TBD
PVCCIN_CPU0              U5D1             CV51     SKX_EXT_B_BGA1-IC,TBD
PVCCIN_CPU0              U5D1             CW46     SKX_EXT_B_BGA1-IC,TBD
PVCCIN_CPU0              U5D1             CW48     SKX_EXT_B_BGA1-IC,TBD
PVCCIN_CPU0              U5D1             CW50     SKX_EXT_B_BGA1-IC,TBD
PVCCIN_CPU0              U5D1             CY47     SKX_EXT_B_BGA1-IC,TBD
PVCCIN_CPU0              U5D1             CY49     SKX_EXT_B_BGA1-IC,TBD
PVCCIN_CPU1              C1D3             1        CAP_A_0603V-22.0UF,4V,20%,X6S,A
PVCCIN_CPU1              C1D14            1        CAP_A_0603V-22.0UF,4V,20%,X6S,A
PVCCIN_CPU1              C1D24            1        CAP_A_0603V-22.0UF,4V,20%,X6S,A
PVCCIN_CPU1              C1E3             1        CAP_A_0603V-22.0UF,4V,20%,X6S,A
PVCCIN_CPU1              C1E9             1        CAP_A_0603V-22.0UF,4V,20%,X6S,A
PVCCIN_CPU1              C2D1             1        CAP_A_0603V-22.0UF,4V,20%,X6S,A
PVCCIN_CPU1              C2D2             1        CAP_A_0603V-22.0UF,4V,20%,X6S,A
PVCCIN_CPU1              C2D3             1        CAP_A_0603V-22.0UF,4V,20%,X6S,A
PVCCIN_CPU1              C2D12            1        CAP_A_0603V-22.0UF,4V,20%,X6S,A
PVCCIN_CPU1              C2D13            1        CAP_A_0603V-22.0UF,4V,20%,X6S,A
PVCCIN_CPU1              C2D14            1        CAP_A_0603V-22.0UF,4V,20%,X6S,A
PVCCIN_CPU1              C2D15            1        CAP_A_0603V-22.0UF,4V,20%,X6S,A
PVCCIN_CPU1              C2D16            1        CAP_A_0603V-22.0UF,4V,20%,X6S,A
PVCCIN_CPU1              C2D17            1        CAP_A_0603V-22.0UF,4V,20%,X6S,A
PVCCIN_CPU1              C2D19            1        CAP_A_0603V-22.0UF,4V,20%,X6S,A
PVCCIN_CPU1              C2D20            1        CAP_A_0603V-22.0UF,4V,20%,X6S,A
PVCCIN_CPU1              C2D21            1        CAP_A_0603V-22.0UF,4V,20%,X6S,A
PVCCIN_CPU1              C2D22            1        CAP_A_0603V-22.0UF,4V,20%,X6S,A
PVCCIN_CPU1              C2D23            1        CAP_A_0603V-22.0UF,4V,20%,X6S,A
PVCCIN_CPU1              C2D24            1        CAP_A_0603V-22.0UF,4V,20%,X6S,A
PVCCIN_CPU1              C2D25            1        CAP_A_0603V-22.0UF,4V,20%,X6S,A
PVCCIN_CPU1              C2D26            1        CAP_A_0603V-22.0UF,4V,20%,X6S,A
PVCCIN_CPU1              C2D27            1        CAP_A_0603V-22.0UF,4V,20%,X6S,A
PVCCIN_CPU1              C2D30            1        CAP_A_0603V-22.0UF,4V,20%,X6S,A
PVCCIN_CPU1              C2D31            1        CAP_A_0603V-22.0UF,4V,20%,X6S,A
PVCCIN_CPU1              C2D32            1        CAP_A_0603V-22.0UF,4V,20%,X6S,A
PVCCIN_CPU1              C2D33            1        CAP_A_0603V-22.0UF,4V,20%,X6S,A
PVCCIN_CPU1              C2D34            1        CAP_A_0603V-22.0UF,4V,20%,X6S,A
PVCCIN_CPU1              C2D35            1        CAP_A_0603V-22.0UF,4V,20%,X6S,A
PVCCIN_CPU1              C2D36            1        CAP_A_0603V-22.0UF,4V,20%,X6S,A
PVCCIN_CPU1              C2D37            1        CAP_A_0603V-22.0UF,4V,20%,X6S,A
PVCCIN_CPU1              C2D38            1        CAP_A_0603V-22.0UF,4V,20%,X6S,A
PVCCIN_CPU1              C2D45            1        CAP_A_0603V-22.0UF,4V,20%,X6S,A
PVCCIN_CPU1              C2D46            1        CAP_A_0603V-22.0UF,4V,20%,X6S,A
PVCCIN_CPU1              C2D47            1        CAP_A_0603V-22.0UF,4V,20%,X6S,A
PVCCIN_CPU1              C3D1             1        CAP_A_0603V-22.0UF,4V,20%,X6S,A
PVCCIN_CPU1              C3D2             1        CAP_A_0603V-22.0UF,4V,20%,X6S,A
PVCCIN_CPU1              C3D25            1        CAP_A_0603V-22.0UF,4V,20%,X6S,A
PVCCIN_CPU1              C7P1             1        CAP_0805-47UF,4V,20%,X6S,C9533A
PVCCIN_CPU1              C7P2             1        CAP_0805-47UF,4V,20%,X6S,C9533A
PVCCIN_CPU1              C7P19            1        CAP_0805-47UF,4V,20%,X6S,C9533A
PVCCIN_CPU1              C7P20            1        CAP_0805-47UF,4V,20%,X6S,C9533A
PVCCIN_CPU1              C8P3             1        CAP_0805-47UF,4V,20%,X6S,C9533A
PVCCIN_CPU1              C8P4             1        CAP_0805-47UF,4V,20%,X6S,C9533A
PVCCIN_CPU1              C8P10            1        CAP_0805-47UF,4V,20%,X6S,C9533A
PVCCIN_CPU1              C8P11            1        CAP_0805-47UF,4V,20%,X6S,C9533A
PVCCIN_CPU1              C8P12            1        CAP_0805-47UF,4V,20%,X6S,C9533A
PVCCIN_CPU1              C8P13            1        CAP_0805-47UF,4V,20%,X6S,C9533A
PVCCIN_CPU1              C8P16            1        CAP_0805-47UF,4V,20%,X6S,C9533A
PVCCIN_CPU1              C8P17            1        CAP_0805-47UF,4V,20%,X6S,C9533A
PVCCIN_CPU1              C8P18            1        CAP_0805-47UF,4V,20%,X6S,C9533A
PVCCIN_CPU1              C8P19            1        CAP_0805-47UF,4V,20%,X6S,C9533A
PVCCIN_CPU1              C8P20            1        CAP_0805-47UF,4V,20%,X6S,C9533A
PVCCIN_CPU1              C8P21            1        CAP_0805-47UF,4V,20%,X6S,C9533A
PVCCIN_CPU1              C8P24            1        CAP_0805-47UF,4V,20%,X6S,C9533A
PVCCIN_CPU1              C8P25            1        CAP_0805-47UF,4V,20%,X6S,C9533A
PVCCIN_CPU1              C8P26            1        CAP_0805-47UF,4V,20%,X6S,C9533A
PVCCIN_CPU1              C8P27            1        CAP_0805-47UF,4V,20%,X6S,C9533A
PVCCIN_CPU1              C8P28            1        CAP_0805-47UF,4V,20%,X6S,C9533A
PVCCIN_CPU1              C8P29            1        CAP_0805-47UF,4V,20%,X6S,C9533A
PVCCIN_CPU1              C8P32            1        CAP_0805-47UF,4V,20%,X6S,C9533A
PVCCIN_CPU1              C8P33            1        CAP_0805-47UF,4V,20%,X6S,C9533A
PVCCIN_CPU1              C8P34            1        CAP_0805-47UF,4V,20%,X6S,C9533A
PVCCIN_CPU1              C9N24            1        CAPP_3018-470UF,2.5V,20%,ALUM,A
PVCCIN_CPU1              C9P3             1        CAP_A_0603V-22.0UF,4V,20%,X6S,A
PVCCIN_CPU1              C9P5             1        CAPP_3018-470UF,2.5V,20%,ALUM,A
PVCCIN_CPU1              C9P8             1        CAPP_3018-470UF,2.5V,20%,ALUM,A
PVCCIN_CPU1              C9P10            1        CAP_A_0603V-22.0UF,4V,20%,X6S,A
PVCCIN_CPU1              C9P18            1        CAPP_3018-470UF,2.5V,20%,ALUM,A
PVCCIN_CPU1              C9P20            1        CAP_A_0603V-22.0UF,4V,20%,X6S,A
PVCCIN_CPU1              C9P23            1        CAPP_3018-470UF,2.5V,20%,ALUM,A
PVCCIN_CPU1              C9R2             1        CAP_A_0603V-22.0UF,4V,20%,X6S,A
PVCCIN_CPU1              C9R3             1        CAPP_3018-470UF,2.5V,20%,ALUM,A
PVCCIN_CPU1              C9R8             1        CAP_A_0603V-22.0UF,4V,20%,X6S,A
PVCCIN_CPU1              C9R9             1        CAPP_3018-470UF,2.5V,20%,ALUM,A
PVCCIN_CPU1              EU1C3            1        IR354XX_SM-IR35411,IC,H73688-0A
PVCCIN_CPU1              EU1D1            1        IR354XX_SM-IR35411,IC,H73688-0A
PVCCIN_CPU1              EU1D3            1        IR354XX_SM-IR35411,IC,H73688-0A
PVCCIN_CPU1              EU1D4            1        IR354XX_SM-IR35411,IC,H73688-0A
PVCCIN_CPU1              EU1E2            1        IR354XX_SM-IR35411,IC,H73688-0A
PVCCIN_CPU1              L1C2             2        INDUCTOR_SM-0.12UH,IND,D92183-A
PVCCIN_CPU1              L1D1             2        INDUCTOR_SM-0.12UH,IND,D92183-A
PVCCIN_CPU1              L1D2             2        INDUCTOR_SM-0.12UH,IND,D92183-A
PVCCIN_CPU1              L1D3             2        INDUCTOR_SM-0.12UH,IND,D92183-A
PVCCIN_CPU1              L1E1             2        INDUCTOR_SM-0.12UH,IND,D92183-A
PVCCIN_CPU1              R1E3             1        RES_0603-100.0,1%,1/10W,CHIP,GA
PVCCIN_CPU1              R1E4             2        RES_0402-100.0,1%,1/16W,CHIP,GA
PVCCIN_CPU1              RT8P1            1        RES_0603-100.0K,1%,1/10W,CHIP,A
PVCCIN_CPU1              U2D1             AF43     SKX_EXT_B_BGA1-IC,TBD
PVCCIN_CPU1              U2D1             AG38     SKX_EXT_B_BGA1-IC,TBD
PVCCIN_CPU1              U2D1             AG40     SKX_EXT_B_BGA1-IC,TBD
PVCCIN_CPU1              U2D1             AG42     SKX_EXT_B_BGA1-IC,TBD
PVCCIN_CPU1              U2D1             AH37     SKX_EXT_B_BGA1-IC,TBD
PVCCIN_CPU1              U2D1             AH39     SKX_EXT_B_BGA1-IC,TBD
PVCCIN_CPU1              U2D1             AH41     SKX_EXT_B_BGA1-IC,TBD
PVCCIN_CPU1              U2D1             AJ36     SKX_EXT_B_BGA1-IC,TBD
PVCCIN_CPU1              U2D1             AK35     SKX_EXT_B_BGA1-IC,TBD
PVCCIN_CPU1              U2D1             AK45     SKX_EXT_B_BGA1-IC,TBD
PVCCIN_CPU1              U2D1             AK47     SKX_EXT_B_BGA1-IC,TBD
PVCCIN_CPU1              U2D1             AK49     SKX_EXT_B_BGA1-IC,TBD
PVCCIN_CPU1              U2D1             AK51     SKX_EXT_B_BGA1-IC,TBD
PVCCIN_CPU1              U2D1             AK53     SKX_EXT_B_BGA1-IC,TBD
PVCCIN_CPU1              U2D1             AL34     SKX_EXT_B_BGA1-IC,TBD
PVCCIN_CPU1              U2D1             AL46     SKX_EXT_B_BGA1-IC,TBD
PVCCIN_CPU1              U2D1             AL48     SKX_EXT_B_BGA1-IC,TBD
PVCCIN_CPU1              U2D1             AL50     SKX_EXT_B_BGA1-IC,TBD
PVCCIN_CPU1              U2D1             AL52     SKX_EXT_B_BGA1-IC,TBD
PVCCIN_CPU1              U2D1             AL54     SKX_EXT_B_BGA1-IC,TBD
PVCCIN_CPU1              U2D1             AM33     SKX_EXT_B_BGA1-IC,TBD
PVCCIN_CPU1              U2D1             AM53     SKX_EXT_B_BGA1-IC,TBD
PVCCIN_CPU1              U2D1             AM55     SKX_EXT_B_BGA1-IC,TBD
PVCCIN_CPU1              U2D1             AN32     SKX_EXT_B_BGA1-IC,TBD
PVCCIN_CPU1              U2D1             AN54     SKX_EXT_B_BGA1-IC,TBD
PVCCIN_CPU1              U2D1             AN56     SKX_EXT_B_BGA1-IC,TBD
PVCCIN_CPU1              U2D1             AP55     SKX_EXT_B_BGA1-IC,TBD
PVCCIN_CPU1              U2D1             AP57     SKX_EXT_B_BGA1-IC,TBD
PVCCIN_CPU1              U2D1             AR56     SKX_EXT_B_BGA1-IC,TBD
PVCCIN_CPU1              U2D1             AR58     SKX_EXT_B_BGA1-IC,TBD
PVCCIN_CPU1              U2D1             AT57     SKX_EXT_B_BGA1-IC,TBD
PVCCIN_CPU1              U2D1             AT59     SKX_EXT_B_BGA1-IC,TBD
PVCCIN_CPU1              U2D1             AU58     SKX_EXT_B_BGA1-IC,TBD
PVCCIN_CPU1              U2D1             AU60     SKX_EXT_B_BGA1-IC,TBD
PVCCIN_CPU1              U2D1             AV59     SKX_EXT_B_BGA1-IC,TBD
PVCCIN_CPU1              U2D1             AV61     SKX_EXT_B_BGA1-IC,TBD
PVCCIN_CPU1              U2D1             AW60     SKX_EXT_B_BGA1-IC,TBD
PVCCIN_CPU1              U2D1             AY61     SKX_EXT_B_BGA1-IC,TBD
PVCCIN_CPU1              U2D1             BA60     SKX_EXT_B_BGA1-IC,TBD
PVCCIN_CPU1              U2D1             BB61     SKX_EXT_B_BGA1-IC,TBD
PVCCIN_CPU1              U2D1             BB85     SKX_EXT_B_BGA1-IC,TBD
PVCCIN_CPU1              U2D1             BC60     SKX_EXT_B_BGA1-IC,TBD
PVCCIN_CPU1              U2D1             BC62     SKX_EXT_B_BGA1-IC,TBD
PVCCIN_CPU1              U2D1             BC84     SKX_EXT_B_BGA1-IC,TBD
PVCCIN_CPU1              U2D1             BD61     SKX_EXT_B_BGA1-IC,TBD
PVCCIN_CPU1              U2D1             BD73     SKX_EXT_B_BGA1-IC,TBD
PVCCIN_CPU1              U2D1             BD75     SKX_EXT_B_BGA1-IC,TBD
PVCCIN_CPU1              U2D1             BD77     SKX_EXT_B_BGA1-IC,TBD
PVCCIN_CPU1              U2D1             BD79     SKX_EXT_B_BGA1-IC,TBD
PVCCIN_CPU1              U2D1             BD81     SKX_EXT_B_BGA1-IC,TBD
PVCCIN_CPU1              U2D1             BD83     SKX_EXT_B_BGA1-IC,TBD
PVCCIN_CPU1              U2D1             BD85     SKX_EXT_B_BGA1-IC,TBD
PVCCIN_CPU1              U2D1             BE60     SKX_EXT_B_BGA1-IC,TBD
PVCCIN_CPU1              U2D1             BE62     SKX_EXT_B_BGA1-IC,TBD
PVCCIN_CPU1              U2D1             BE72     SKX_EXT_B_BGA1-IC,TBD
PVCCIN_CPU1              U2D1             BE74     SKX_EXT_B_BGA1-IC,TBD
PVCCIN_CPU1              U2D1             BE76     SKX_EXT_B_BGA1-IC,TBD
PVCCIN_CPU1              U2D1             BE78     SKX_EXT_B_BGA1-IC,TBD
PVCCIN_CPU1              U2D1             BE80     SKX_EXT_B_BGA1-IC,TBD
PVCCIN_CPU1              U2D1             BE82     SKX_EXT_B_BGA1-IC,TBD
PVCCIN_CPU1              U2D1             BE84     SKX_EXT_B_BGA1-IC,TBD
PVCCIN_CPU1              U2D1             BF61     SKX_EXT_B_BGA1-IC,TBD
PVCCIN_CPU1              U2D1             BF73     SKX_EXT_B_BGA1-IC,TBD
PVCCIN_CPU1              U2D1             BF75     SKX_EXT_B_BGA1-IC,TBD
PVCCIN_CPU1              U2D1             BF77     SKX_EXT_B_BGA1-IC,TBD
PVCCIN_CPU1              U2D1             BF79     SKX_EXT_B_BGA1-IC,TBD
PVCCIN_CPU1              U2D1             BF81     SKX_EXT_B_BGA1-IC,TBD
PVCCIN_CPU1              U2D1             BF83     SKX_EXT_B_BGA1-IC,TBD
PVCCIN_CPU1              U2D1             BF85     SKX_EXT_B_BGA1-IC,TBD
PVCCIN_CPU1              U2D1             BG60     SKX_EXT_B_BGA1-IC,TBD
PVCCIN_CPU1              U2D1             BG62     SKX_EXT_B_BGA1-IC,TBD
PVCCIN_CPU1              U2D1             BG64     SKX_EXT_B_BGA1-IC,TBD
PVCCIN_CPU1              U2D1             BG66     SKX_EXT_B_BGA1-IC,TBD
PVCCIN_CPU1              U2D1             BG68     SKX_EXT_B_BGA1-IC,TBD
PVCCIN_CPU1              U2D1             BG70     SKX_EXT_B_BGA1-IC,TBD
PVCCIN_CPU1              U2D1             BG84     SKX_EXT_B_BGA1-IC,TBD
PVCCIN_CPU1              U2D1             BH61     SKX_EXT_B_BGA1-IC,TBD
PVCCIN_CPU1              U2D1             BH63     SKX_EXT_B_BGA1-IC,TBD
PVCCIN_CPU1              U2D1             BH65     SKX_EXT_B_BGA1-IC,TBD
PVCCIN_CPU1              U2D1             BH67     SKX_EXT_B_BGA1-IC,TBD
PVCCIN_CPU1              U2D1             BH69     SKX_EXT_B_BGA1-IC,TBD
PVCCIN_CPU1              U2D1             BH71     SKX_EXT_B_BGA1-IC,TBD
PVCCIN_CPU1              U2D1             BH73     SKX_EXT_B_BGA1-IC,TBD
PVCCIN_CPU1              U2D1             BH75     SKX_EXT_B_BGA1-IC,TBD
PVCCIN_CPU1              U2D1             BH77     SKX_EXT_B_BGA1-IC,TBD
PVCCIN_CPU1              U2D1             BH79     SKX_EXT_B_BGA1-IC,TBD
PVCCIN_CPU1              U2D1             BH81     SKX_EXT_B_BGA1-IC,TBD
PVCCIN_CPU1              U2D1             BH83     SKX_EXT_B_BGA1-IC,TBD
PVCCIN_CPU1              U2D1             BJ60     SKX_EXT_B_BGA1-IC,TBD
PVCCIN_CPU1              U2D1             BJ62     SKX_EXT_B_BGA1-IC,TBD
PVCCIN_CPU1              U2D1             BJ64     SKX_EXT_B_BGA1-IC,TBD
PVCCIN_CPU1              U2D1             BJ66     SKX_EXT_B_BGA1-IC,TBD
PVCCIN_CPU1              U2D1             BJ68     SKX_EXT_B_BGA1-IC,TBD
PVCCIN_CPU1              U2D1             BJ70     SKX_EXT_B_BGA1-IC,TBD
PVCCIN_CPU1              U2D1             BJ72     SKX_EXT_B_BGA1-IC,TBD
PVCCIN_CPU1              U2D1             BJ74     SKX_EXT_B_BGA1-IC,TBD
PVCCIN_CPU1              U2D1             BJ76     SKX_EXT_B_BGA1-IC,TBD
PVCCIN_CPU1              U2D1             BJ78     SKX_EXT_B_BGA1-IC,TBD
PVCCIN_CPU1              U2D1             BJ80     SKX_EXT_B_BGA1-IC,TBD
PVCCIN_CPU1              U2D1             BJ82     SKX_EXT_B_BGA1-IC,TBD
PVCCIN_CPU1              U2D1             BJ84     SKX_EXT_B_BGA1-IC,TBD
PVCCIN_CPU1              U2D1             BK61     SKX_EXT_B_BGA1-IC,TBD
PVCCIN_CPU1              U2D1             BK63     SKX_EXT_B_BGA1-IC,TBD
PVCCIN_CPU1              U2D1             BK65     SKX_EXT_B_BGA1-IC,TBD
PVCCIN_CPU1              U2D1             BK67     SKX_EXT_B_BGA1-IC,TBD
PVCCIN_CPU1              U2D1             BK69     SKX_EXT_B_BGA1-IC,TBD
PVCCIN_CPU1              U2D1             BK71     SKX_EXT_B_BGA1-IC,TBD
PVCCIN_CPU1              U2D1             BK73     SKX_EXT_B_BGA1-IC,TBD
PVCCIN_CPU1              U2D1             BK75     SKX_EXT_B_BGA1-IC,TBD
PVCCIN_CPU1              U2D1             BK77     SKX_EXT_B_BGA1-IC,TBD
PVCCIN_CPU1              U2D1             BK79     SKX_EXT_B_BGA1-IC,TBD
PVCCIN_CPU1              U2D1             BK81     SKX_EXT_B_BGA1-IC,TBD
PVCCIN_CPU1              U2D1             BK83     SKX_EXT_B_BGA1-IC,TBD
PVCCIN_CPU1              U2D1             BL60     SKX_EXT_B_BGA1-IC,TBD
PVCCIN_CPU1              U2D1             BL62     SKX_EXT_B_BGA1-IC,TBD
PVCCIN_CPU1              U2D1             BL84     SKX_EXT_B_BGA1-IC,TBD
PVCCIN_CPU1              U2D1             BM61     SKX_EXT_B_BGA1-IC,TBD
PVCCIN_CPU1              U2D1             BM63     SKX_EXT_B_BGA1-IC,TBD
PVCCIN_CPU1              U2D1             BM65     SKX_EXT_B_BGA1-IC,TBD
PVCCIN_CPU1              U2D1             BM67     SKX_EXT_B_BGA1-IC,TBD
PVCCIN_CPU1              U2D1             BM69     SKX_EXT_B_BGA1-IC,TBD
PVCCIN_CPU1              U2D1             BM71     SKX_EXT_B_BGA1-IC,TBD
PVCCIN_CPU1              U2D1             BM73     SKX_EXT_B_BGA1-IC,TBD
PVCCIN_CPU1              U2D1             BM75     SKX_EXT_B_BGA1-IC,TBD
PVCCIN_CPU1              U2D1             BM77     SKX_EXT_B_BGA1-IC,TBD
PVCCIN_CPU1              U2D1             BM79     SKX_EXT_B_BGA1-IC,TBD
PVCCIN_CPU1              U2D1             BM81     SKX_EXT_B_BGA1-IC,TBD
PVCCIN_CPU1              U2D1             BM83     SKX_EXT_B_BGA1-IC,TBD
PVCCIN_CPU1              U2D1             BN60     SKX_EXT_B_BGA1-IC,TBD
PVCCIN_CPU1              U2D1             BN62     SKX_EXT_B_BGA1-IC,TBD
PVCCIN_CPU1              U2D1             BN64     SKX_EXT_B_BGA1-IC,TBD
PVCCIN_CPU1              U2D1             BN66     SKX_EXT_B_BGA1-IC,TBD
PVCCIN_CPU1              U2D1             BN68     SKX_EXT_B_BGA1-IC,TBD
PVCCIN_CPU1              U2D1             BN70     SKX_EXT_B_BGA1-IC,TBD
PVCCIN_CPU1              U2D1             BN72     SKX_EXT_B_BGA1-IC,TBD
PVCCIN_CPU1              U2D1             BN74     SKX_EXT_B_BGA1-IC,TBD
PVCCIN_CPU1              U2D1             BN76     SKX_EXT_B_BGA1-IC,TBD
PVCCIN_CPU1              U2D1             BN78     SKX_EXT_B_BGA1-IC,TBD
PVCCIN_CPU1              U2D1             BN80     SKX_EXT_B_BGA1-IC,TBD
PVCCIN_CPU1              U2D1             BN82     SKX_EXT_B_BGA1-IC,TBD
PVCCIN_CPU1              U2D1             BN84     SKX_EXT_B_BGA1-IC,TBD
PVCCIN_CPU1              U2D1             BP61     SKX_EXT_B_BGA1-IC,TBD
PVCCIN_CPU1              U2D1             BP63     SKX_EXT_B_BGA1-IC,TBD
PVCCIN_CPU1              U2D1             BP65     SKX_EXT_B_BGA1-IC,TBD
PVCCIN_CPU1              U2D1             BP67     SKX_EXT_B_BGA1-IC,TBD
PVCCIN_CPU1              U2D1             BP69     SKX_EXT_B_BGA1-IC,TBD
PVCCIN_CPU1              U2D1             BP71     SKX_EXT_B_BGA1-IC,TBD
PVCCIN_CPU1              U2D1             BP73     SKX_EXT_B_BGA1-IC,TBD
PVCCIN_CPU1              U2D1             BP75     SKX_EXT_B_BGA1-IC,TBD
PVCCIN_CPU1              U2D1             BP77     SKX_EXT_B_BGA1-IC,TBD
PVCCIN_CPU1              U2D1             BP79     SKX_EXT_B_BGA1-IC,TBD
PVCCIN_CPU1              U2D1             BP81     SKX_EXT_B_BGA1-IC,TBD
PVCCIN_CPU1              U2D1             BP83     SKX_EXT_B_BGA1-IC,TBD
PVCCIN_CPU1              U2D1             BR60     SKX_EXT_B_BGA1-IC,TBD
PVCCIN_CPU1              U2D1             BR62     SKX_EXT_B_BGA1-IC,TBD
PVCCIN_CPU1              U2D1             BR84     SKX_EXT_B_BGA1-IC,TBD
PVCCIN_CPU1              U2D1             BT61     SKX_EXT_B_BGA1-IC,TBD
PVCCIN_CPU1              U2D1             BT63     SKX_EXT_B_BGA1-IC,TBD
PVCCIN_CPU1              U2D1             BT65     SKX_EXT_B_BGA1-IC,TBD
PVCCIN_CPU1              U2D1             BT67     SKX_EXT_B_BGA1-IC,TBD
PVCCIN_CPU1              U2D1             BT69     SKX_EXT_B_BGA1-IC,TBD
PVCCIN_CPU1              U2D1             BT71     SKX_EXT_B_BGA1-IC,TBD
PVCCIN_CPU1              U2D1             BT73     SKX_EXT_B_BGA1-IC,TBD
PVCCIN_CPU1              U2D1             BT75     SKX_EXT_B_BGA1-IC,TBD
PVCCIN_CPU1              U2D1             BT77     SKX_EXT_B_BGA1-IC,TBD
PVCCIN_CPU1              U2D1             BT79     SKX_EXT_B_BGA1-IC,TBD
PVCCIN_CPU1              U2D1             BT81     SKX_EXT_B_BGA1-IC,TBD
PVCCIN_CPU1              U2D1             BT83     SKX_EXT_B_BGA1-IC,TBD
PVCCIN_CPU1              U2D1             BU60     SKX_EXT_B_BGA1-IC,TBD
PVCCIN_CPU1              U2D1             BU62     SKX_EXT_B_BGA1-IC,TBD
PVCCIN_CPU1              U2D1             BU64     SKX_EXT_B_BGA1-IC,TBD
PVCCIN_CPU1              U2D1             BU66     SKX_EXT_B_BGA1-IC,TBD
PVCCIN_CPU1              U2D1             BU68     SKX_EXT_B_BGA1-IC,TBD
PVCCIN_CPU1              U2D1             BU70     SKX_EXT_B_BGA1-IC,TBD
PVCCIN_CPU1              U2D1             BU72     SKX_EXT_B_BGA1-IC,TBD
PVCCIN_CPU1              U2D1             BU74     SKX_EXT_B_BGA1-IC,TBD
PVCCIN_CPU1              U2D1             BU76     SKX_EXT_B_BGA1-IC,TBD
PVCCIN_CPU1              U2D1             BU78     SKX_EXT_B_BGA1-IC,TBD
PVCCIN_CPU1              U2D1             BU80     SKX_EXT_B_BGA1-IC,TBD
PVCCIN_CPU1              U2D1             BU82     SKX_EXT_B_BGA1-IC,TBD
PVCCIN_CPU1              U2D1             BU84     SKX_EXT_B_BGA1-IC,TBD
PVCCIN_CPU1              U2D1             BV61     SKX_EXT_B_BGA1-IC,TBD
PVCCIN_CPU1              U2D1             BV63     SKX_EXT_B_BGA1-IC,TBD
PVCCIN_CPU1              U2D1             BV65     SKX_EXT_B_BGA1-IC,TBD
PVCCIN_CPU1              U2D1             BV67     SKX_EXT_B_BGA1-IC,TBD
PVCCIN_CPU1              U2D1             BV69     SKX_EXT_B_BGA1-IC,TBD
PVCCIN_CPU1              U2D1             BV71     SKX_EXT_B_BGA1-IC,TBD
PVCCIN_CPU1              U2D1             BV73     SKX_EXT_B_BGA1-IC,TBD
PVCCIN_CPU1              U2D1             BV75     SKX_EXT_B_BGA1-IC,TBD
PVCCIN_CPU1              U2D1             BV77     SKX_EXT_B_BGA1-IC,TBD
PVCCIN_CPU1              U2D1             BV79     SKX_EXT_B_BGA1-IC,TBD
PVCCIN_CPU1              U2D1             BV81     SKX_EXT_B_BGA1-IC,TBD
PVCCIN_CPU1              U2D1             BV83     SKX_EXT_B_BGA1-IC,TBD
PVCCIN_CPU1              U2D1             BW60     SKX_EXT_B_BGA1-IC,TBD
PVCCIN_CPU1              U2D1             BW62     SKX_EXT_B_BGA1-IC,TBD
PVCCIN_CPU1              U2D1             BW64     SKX_EXT_B_BGA1-IC,TBD
PVCCIN_CPU1              U2D1             BW66     SKX_EXT_B_BGA1-IC,TBD
PVCCIN_CPU1              U2D1             BW68     SKX_EXT_B_BGA1-IC,TBD
PVCCIN_CPU1              U2D1             BW70     SKX_EXT_B_BGA1-IC,TBD
PVCCIN_CPU1              U2D1             BW84     SKX_EXT_B_BGA1-IC,TBD
PVCCIN_CPU1              U2D1             BY61     SKX_EXT_B_BGA1-IC,TBD
PVCCIN_CPU1              U2D1             BY73     SKX_EXT_B_BGA1-IC,TBD
PVCCIN_CPU1              U2D1             BY75     SKX_EXT_B_BGA1-IC,TBD
PVCCIN_CPU1              U2D1             BY77     SKX_EXT_B_BGA1-IC,TBD
PVCCIN_CPU1              U2D1             BY79     SKX_EXT_B_BGA1-IC,TBD
PVCCIN_CPU1              U2D1             BY81     SKX_EXT_B_BGA1-IC,TBD
PVCCIN_CPU1              U2D1             BY83     SKX_EXT_B_BGA1-IC,TBD
PVCCIN_CPU1              U2D1             CA60     SKX_EXT_B_BGA1-IC,TBD
PVCCIN_CPU1              U2D1             CA62     SKX_EXT_B_BGA1-IC,TBD
PVCCIN_CPU1              U2D1             CA72     SKX_EXT_B_BGA1-IC,TBD
PVCCIN_CPU1              U2D1             CA74     SKX_EXT_B_BGA1-IC,TBD
PVCCIN_CPU1              U2D1             CA76     SKX_EXT_B_BGA1-IC,TBD
PVCCIN_CPU1              U2D1             CA78     SKX_EXT_B_BGA1-IC,TBD
PVCCIN_CPU1              U2D1             CA80     SKX_EXT_B_BGA1-IC,TBD
PVCCIN_CPU1              U2D1             CA82     SKX_EXT_B_BGA1-IC,TBD
PVCCIN_CPU1              U2D1             CA84     SKX_EXT_B_BGA1-IC,TBD
PVCCIN_CPU1              U2D1             CB61     SKX_EXT_B_BGA1-IC,TBD
PVCCIN_CPU1              U2D1             CB73     SKX_EXT_B_BGA1-IC,TBD
PVCCIN_CPU1              U2D1             CB75     SKX_EXT_B_BGA1-IC,TBD
PVCCIN_CPU1              U2D1             CB77     SKX_EXT_B_BGA1-IC,TBD
PVCCIN_CPU1              U2D1             CB79     SKX_EXT_B_BGA1-IC,TBD
PVCCIN_CPU1              U2D1             CB81     SKX_EXT_B_BGA1-IC,TBD
PVCCIN_CPU1              U2D1             CB83     SKX_EXT_B_BGA1-IC,TBD
PVCCIN_CPU1              U2D1             CC60     SKX_EXT_B_BGA1-IC,TBD
PVCCIN_CPU1              U2D1             CC62     SKX_EXT_B_BGA1-IC,TBD
PVCCIN_CPU1              U2D1             CC84     SKX_EXT_B_BGA1-IC,TBD
PVCCIN_CPU1              U2D1             CD61     SKX_EXT_B_BGA1-IC,TBD
PVCCIN_CPU1              U2D1             CD83     SKX_EXT_B_BGA1-IC,TBD
PVCCIN_CPU1              U2D1             CD85     SKX_EXT_B_BGA1-IC,TBD
PVCCIN_CPU1              U2D1             CE60     SKX_EXT_B_BGA1-IC,TBD
PVCCIN_CPU1              U2D1             CE84     SKX_EXT_B_BGA1-IC,TBD
PVCCIN_CPU1              U2D1             CF61     SKX_EXT_B_BGA1-IC,TBD
PVCCIN_CPU1              U2D1             CF85     SKX_EXT_B_BGA1-IC,TBD
PVCCIN_CPU1              U2D1             CG60     SKX_EXT_B_BGA1-IC,TBD
PVCCIN_CPU1              U2D1             CG84     SKX_EXT_B_BGA1-IC,TBD
PVCCIN_CPU1              U2D1             CH61     SKX_EXT_B_BGA1-IC,TBD
PVCCIN_CPU1              U2D1             CH85     SKX_EXT_B_BGA1-IC,TBD
PVCCIN_CPU1              U2D1             CJ60     SKX_EXT_B_BGA1-IC,TBD
PVCCIN_CPU1              U2D1             CK59     SKX_EXT_B_BGA1-IC,TBD
PVCCIN_CPU1              U2D1             CK61     SKX_EXT_B_BGA1-IC,TBD
PVCCIN_CPU1              U2D1             CL58     SKX_EXT_B_BGA1-IC,TBD
PVCCIN_CPU1              U2D1             CL60     SKX_EXT_B_BGA1-IC,TBD
PVCCIN_CPU1              U2D1             CM57     SKX_EXT_B_BGA1-IC,TBD
PVCCIN_CPU1              U2D1             CM59     SKX_EXT_B_BGA1-IC,TBD
PVCCIN_CPU1              U2D1             CN56     SKX_EXT_B_BGA1-IC,TBD
PVCCIN_CPU1              U2D1             CN58     SKX_EXT_B_BGA1-IC,TBD
PVCCIN_CPU1              U2D1             CP33     SKX_EXT_B_BGA1-IC,TBD
PVCCIN_CPU1              U2D1             CP55     SKX_EXT_B_BGA1-IC,TBD
PVCCIN_CPU1              U2D1             CP57     SKX_EXT_B_BGA1-IC,TBD
PVCCIN_CPU1              U2D1             CR34     SKX_EXT_B_BGA1-IC,TBD
PVCCIN_CPU1              U2D1             CR54     SKX_EXT_B_BGA1-IC,TBD
PVCCIN_CPU1              U2D1             CR56     SKX_EXT_B_BGA1-IC,TBD
PVCCIN_CPU1              U2D1             CT37     SKX_EXT_B_BGA1-IC,TBD
PVCCIN_CPU1              U2D1             CT39     SKX_EXT_B_BGA1-IC,TBD
PVCCIN_CPU1              U2D1             CT41     SKX_EXT_B_BGA1-IC,TBD
PVCCIN_CPU1              U2D1             CT53     SKX_EXT_B_BGA1-IC,TBD
PVCCIN_CPU1              U2D1             CT55     SKX_EXT_B_BGA1-IC,TBD
PVCCIN_CPU1              U2D1             CU38     SKX_EXT_B_BGA1-IC,TBD
PVCCIN_CPU1              U2D1             CU40     SKX_EXT_B_BGA1-IC,TBD
PVCCIN_CPU1              U2D1             CU42     SKX_EXT_B_BGA1-IC,TBD
PVCCIN_CPU1              U2D1             CU52     SKX_EXT_B_BGA1-IC,TBD
PVCCIN_CPU1              U2D1             CU54     SKX_EXT_B_BGA1-IC,TBD
PVCCIN_CPU1              U2D1             CV51     SKX_EXT_B_BGA1-IC,TBD
PVCCIN_CPU1              U2D1             CW46     SKX_EXT_B_BGA1-IC,TBD
PVCCIN_CPU1              U2D1             CW48     SKX_EXT_B_BGA1-IC,TBD
PVCCIN_CPU1              U2D1             CW50     SKX_EXT_B_BGA1-IC,TBD
PVCCIN_CPU1              U2D1             CY47     SKX_EXT_B_BGA1-IC,TBD
PVCCIN_CPU1              U2D1             CY49     SKX_EXT_B_BGA1-IC,TBD
PVCCIN_PVSA_CPU0_IINSEN  EU4D4            46       PXE1610B_QFN-IC,H79206-001
PVCCIN_PVSA_CPU0_IINSEN  U4C1             6        ADM4073_SM-EMPTY,G12194-001
PVCCIN_PVSA_CPU1_IINSEN  EU1C2            46       PXE1610B_QFN-IC,H79206-001
PVCCIN_PVSA_CPU1_IINSEN  U1B3             6        ADM4073_SM-EMPTY,G12194-001
PVCCIOMCP_CPU0           C3M46            1        CAP_A_0402V-1.0UF,6.3V,10%,X6SA
PVCCIOMCP_CPU0           C3N14            1        CAPP_3018-470UF,2.5V,20%,ALUM,A
PVCCIOMCP_CPU0           C3N40            1        CAP_A_0402V-1.0UF,6.3V,10%,X6SA
PVCCIOMCP_CPU0           J6B1             C17      SCONN120_H61426002_SM-CONN,H61A
PVCCIOMCP_CPU0           J6B1             C18      SCONN120_H61426002_SM-CONN,H61A
PVCCIOMCP_CPU0           J6B1             C19      SCONN120_H61426002_SM-CONN,H61A
PVCCIOMCP_CPU0           J6B1             D15      SCONN120_H61426002_SM-CONN,H61A
PVCCIOMCP_CPU0           J6B1             D16      SCONN120_H61426002_SM-CONN,H61A
PVCCIOMCP_CPU0           J6B1             D17      SCONN120_H61426002_SM-CONN,H61A
PVCCIOMCP_CPU0           J6B1             D18      SCONN120_H61426002_SM-CONN,H61A
PVCCIOMCP_CPU0           J6B1             D19      SCONN120_H61426002_SM-CONN,H61A
PVCCIOMCP_CPU0           J6B1             E15      SCONN120_H61426002_SM-CONN,H61A
PVCCIOMCP_CPU0           J6B1             E16      SCONN120_H61426002_SM-CONN,H61A
PVCCIOMCP_CPU0           J6B1             E17      SCONN120_H61426002_SM-CONN,H61A
PVCCIOMCP_CPU0           J6B1             E18      SCONN120_H61426002_SM-CONN,H61A
PVCCIOMCP_CPU0           J6B1             E19      SCONN120_H61426002_SM-CONN,H61A
PVCCIOMCP_CPU0           J6B1             F15      SCONN120_H61426002_SM-CONN,H61A
PVCCIOMCP_CPU0           J6B1             F16      SCONN120_H61426002_SM-CONN,H61A
PVCCIOMCP_CPU0           J6B1             F17      SCONN120_H61426002_SM-CONN,H61A
PVCCIOMCP_CPU0           J6B1             F18      SCONN120_H61426002_SM-CONN,H61A
PVCCIOMCP_CPU0           J6B1             F19      SCONN120_H61426002_SM-CONN,H61A
PVCCIOMCP_CPU0           U5D1             BM11     SKX_EXT_B_BGA1-IC,TBD
PVCCIOMCP_CPU0           U5D1             BN12     SKX_EXT_B_BGA1-IC,TBD
PVCCIOMCP_CPU0           U5D1             BN14     SKX_EXT_B_BGA1-IC,TBD
PVCCIOMCP_CPU0           U5D1             BP11     SKX_EXT_B_BGA1-IC,TBD
PVCCIOMCP_CPU0           U5D1             BP13     SKX_EXT_B_BGA1-IC,TBD
PVCCIOMCP_CPU0           U5D1             BP15     SKX_EXT_B_BGA1-IC,TBD
PVCCIOMCP_CPU0           U5D1             BR12     SKX_EXT_B_BGA1-IC,TBD
PVCCIOMCP_CPU0           U5D1             BR14     SKX_EXT_B_BGA1-IC,TBD
PVCCIOMCP_CPU0           U5D1             BT11     SKX_EXT_B_BGA1-IC,TBD
PVCCIOMCP_CPU0           U5D1             BT13     SKX_EXT_B_BGA1-IC,TBD
PVCCIOMCP_CPU0           U5D1             BT15     SKX_EXT_B_BGA1-IC,TBD
PVCCIOMCP_CPU0           U5D1             BU12     SKX_EXT_B_BGA1-IC,TBD
PVCCIOMCP_CPU0           U5D1             BU14     SKX_EXT_B_BGA1-IC,TBD
PVCCIOMCP_CPU0           U5D1             BV11     SKX_EXT_B_BGA1-IC,TBD
PVCCIOMCP_CPU0           U5D1             BV13     SKX_EXT_B_BGA1-IC,TBD
PVCCIOMCP_CPU0           U5D1             BV15     SKX_EXT_B_BGA1-IC,TBD
PVCCIOMCP_CPU1           C3C1             1        CAP_A_0402V-1.0UF,6.3V,10%,X6SA
PVCCIOMCP_CPU1           C3C2             1        CAP_A_0402V-1.0UF,6.3V,10%,X6SA
PVCCIOMCP_CPU1           C4C1             1        CAPP_3018-470UF,2.5V,20%,ALUM,A
PVCCIOMCP_CPU1           J4B2             C17      SCONN120_H61426002_SM-CONN,H61A
PVCCIOMCP_CPU1           J4B2             C18      SCONN120_H61426002_SM-CONN,H61A
PVCCIOMCP_CPU1           J4B2             C19      SCONN120_H61426002_SM-CONN,H61A
PVCCIOMCP_CPU1           J4B2             D15      SCONN120_H61426002_SM-CONN,H61A
PVCCIOMCP_CPU1           J4B2             D16      SCONN120_H61426002_SM-CONN,H61A
PVCCIOMCP_CPU1           J4B2             D17      SCONN120_H61426002_SM-CONN,H61A
PVCCIOMCP_CPU1           J4B2             D18      SCONN120_H61426002_SM-CONN,H61A
PVCCIOMCP_CPU1           J4B2             D19      SCONN120_H61426002_SM-CONN,H61A
PVCCIOMCP_CPU1           J4B2             E15      SCONN120_H61426002_SM-CONN,H61A
PVCCIOMCP_CPU1           J4B2             E16      SCONN120_H61426002_SM-CONN,H61A
PVCCIOMCP_CPU1           J4B2             E17      SCONN120_H61426002_SM-CONN,H61A
PVCCIOMCP_CPU1           J4B2             E18      SCONN120_H61426002_SM-CONN,H61A
PVCCIOMCP_CPU1           J4B2             E19      SCONN120_H61426002_SM-CONN,H61A
PVCCIOMCP_CPU1           J4B2             F15      SCONN120_H61426002_SM-CONN,H61A
PVCCIOMCP_CPU1           J4B2             F16      SCONN120_H61426002_SM-CONN,H61A
PVCCIOMCP_CPU1           J4B2             F17      SCONN120_H61426002_SM-CONN,H61A
PVCCIOMCP_CPU1           J4B2             F18      SCONN120_H61426002_SM-CONN,H61A
PVCCIOMCP_CPU1           J4B2             F19      SCONN120_H61426002_SM-CONN,H61A
PVCCIOMCP_CPU1           U2D1             BM11     SKX_EXT_B_BGA1-IC,TBD
PVCCIOMCP_CPU1           U2D1             BN12     SKX_EXT_B_BGA1-IC,TBD
PVCCIOMCP_CPU1           U2D1             BN14     SKX_EXT_B_BGA1-IC,TBD
PVCCIOMCP_CPU1           U2D1             BP11     SKX_EXT_B_BGA1-IC,TBD
PVCCIOMCP_CPU1           U2D1             BP13     SKX_EXT_B_BGA1-IC,TBD
PVCCIOMCP_CPU1           U2D1             BP15     SKX_EXT_B_BGA1-IC,TBD
PVCCIOMCP_CPU1           U2D1             BR12     SKX_EXT_B_BGA1-IC,TBD
PVCCIOMCP_CPU1           U2D1             BR14     SKX_EXT_B_BGA1-IC,TBD
PVCCIOMCP_CPU1           U2D1             BT11     SKX_EXT_B_BGA1-IC,TBD
PVCCIOMCP_CPU1           U2D1             BT13     SKX_EXT_B_BGA1-IC,TBD
PVCCIOMCP_CPU1           U2D1             BT15     SKX_EXT_B_BGA1-IC,TBD
PVCCIOMCP_CPU1           U2D1             BU12     SKX_EXT_B_BGA1-IC,TBD
PVCCIOMCP_CPU1           U2D1             BU14     SKX_EXT_B_BGA1-IC,TBD
PVCCIOMCP_CPU1           U2D1             BV11     SKX_EXT_B_BGA1-IC,TBD
PVCCIOMCP_CPU1           U2D1             BV13     SKX_EXT_B_BGA1-IC,TBD
PVCCIOMCP_CPU1           U2D1             BV15     SKX_EXT_B_BGA1-IC,TBD
PVCCIO_CPU0              C1T21            1        CAP_A_0402V-1.0UF,6.3V,10%,X6SA
PVCCIO_CPU0              C3N26            1        CAPP_3018-470UF,2.5V,20%,ALUM,A
PVCCIO_CPU0              C3N35            1        CAPP_3018-470UF,2.5V,20%,ALUM,A
PVCCIO_CPU0              C3N38            1        CAPP_3018-470UF,2.5V,20%,ALUM,A
PVCCIO_CPU0              C4P1             1        CAP_0805-47UF,4V,20%,X6S,C9533A
PVCCIO_CPU0              C4P6             1        CAP_A_0603V-22.0UF,4V,20%,X6S,A
PVCCIO_CPU0              C4P8             1        CAP_A_0603V-22.0UF,4V,20%,X6S,A
PVCCIO_CPU0              C4P9             1        CAP_0805-47UF,4V,20%,X6S,C9533A
PVCCIO_CPU0              C4P10            1        CAP_0805-47UF,4V,20%,X6S,C9533A
PVCCIO_CPU0              C6D3             1        CAP_A_0603V-22.0UF,4V,20%,X6S,A
PVCCIO_CPU0              C6D4             1        CAP_A_0603V-22.0UF,4V,20%,X6S,A
PVCCIO_CPU0              C6D6             1        CAP_A_0603V-22.0UF,4V,20%,X6S,A
PVCCIO_CPU0              C6D7             1        CAP_A_0603V-22.0UF,4V,20%,X6S,A
PVCCIO_CPU0              C6D9             1        CAP_A_0603V-22.0UF,4V,20%,X6S,A
PVCCIO_CPU0              C6D10            1        CAP_A_0603V-22.0UF,4V,20%,X6S,A
PVCCIO_CPU0              C6F2             1        CAP_A_0402V-0.1UF,16V,10%,X7R,A
PVCCIO_CPU0              C7C6             1        CAP_A_0603V-22.0UF,4V,20%,X6S,A
PVCCIO_CPU0              C7C10            1        CAP_A_0603V-22.0UF,4V,20%,X6S,A
PVCCIO_CPU0              C7E1             1        CAP_A_0402V-0.1UF,16V,10%,X7R,A
PVCCIO_CPU0              EU7C1            1        IR354XX_SM-IR35412,IC,H73684-0A
PVCCIO_CPU0              J6B1             F1       SCONN120_H61426002_SM-CONN,H61A
PVCCIO_CPU0              L7C2             2        INDUCTOR_SM-150NH,IND,D92183-0A
PVCCIO_CPU0              R1L15            1        RES_0402-150.0,1%,1/16W,CHIP,GA
PVCCIO_CPU0              R1L17            2        RES_0402-150.0,1%,1/16W,CHIP,GA
PVCCIO_CPU0              R1M3             1        RES_0402-100.0,1%,1/16W,CHIP,GA
PVCCIO_CPU0              R1M4             1        RES_0402-100.0,1%,1/16W,CHIP,GA
PVCCIO_CPU0              R1U43            1        RES_0402-49.9,1%,1/16W,CHIP,G2A
PVCCIO_CPU0              R2T19            1        RES_0402-200.0,1%,1/16W,CHIP,GA
PVCCIO_CPU0              R2T26            1        RES_0402-200.0,1%,1/16W,CHIP,GA
PVCCIO_CPU0              R2T36            1        RES_0402-49.9,1%,1/16W,CHIP,G2A
PVCCIO_CPU0              R2T37            1        RES_0402-200.0,1%,1/16W,CHIP,GA
PVCCIO_CPU0              R2T72            1        RES_0402-150.0,1%,1/16W,CHIP,GA
PVCCIO_CPU0              R2U40            1        RES_0402-150.0,1%,1/16W,CHIP,GA
PVCCIO_CPU0              R2U41            1        RES_0402-150.0,1%,1/16W,CHIP,GA
PVCCIO_CPU0              R3L11            1        RES_0402-100.0,1%,1/16W,EMPTY,A
PVCCIO_CPU0              R3L13            1        RES_0402-49.9,1%,1/16W,CHIP,G2A
PVCCIO_CPU0              R3N21            2        RES_0402-100.0,1%,1/16W,CHIP,GA
PVCCIO_CPU0              R3P13            1        RES_0402-100.0,1%,1/16W,EMPTY,A
PVCCIO_CPU0              R3P17            1        RES_0402-49.9,1%,1/16W,EMPTY,GA
PVCCIO_CPU0              R3P45            1        RES_0402-49.9,1%,1/16W,CHIP,G2A
PVCCIO_CPU0              R3P60            1        RES_0402-240,1.0%,1/16W,CHIP,GA
PVCCIO_CPU0              R3R13            1        RES_0402-240,1.0%,1/16W,CHIP,GA
PVCCIO_CPU0              R3T11            1        RES_0402-49.9,1%,1/16W,EMPTY,GA
PVCCIO_CPU0              R3U2             1        RES_0402-100.0,1%,1/16W,CHIP,GA
PVCCIO_CPU0              R4E9             1        RES_0402-49.9,1%,1/16W,CHIP,G2A
PVCCIO_CPU0              R4E10            1        RES_0402-100.0,1%,1/16W,CHIP,GA
PVCCIO_CPU0              R4P12            1        RES_0402-100.0,1%,1/16W,CHIP,GA
PVCCIO_CPU0              R4P14            1        RES_0402-240,1.0%,1/16W,CHIP,GA
PVCCIO_CPU0              R4P15            1        RES_0402-100.0,1%,1/16W,CHIP,GA
PVCCIO_CPU0              R4P17            2        RES_0402-150.0,1%,1/16W,CHIP,GA
PVCCIO_CPU0              R4P20            2        RES_0402-150.0,1%,1/16W,CHIP,GA
PVCCIO_CPU0              R4P21            1        RES_0402-240,1.0%,1/16W,CHIP,GA
PVCCIO_CPU0              R4P23            1        RES_0402-150.0,1%,1/16W,CHIP,GA
PVCCIO_CPU0              R4P24            1        RES_0402-150.0,1%,1/16W,CHIP,GA
PVCCIO_CPU0              R4R2             1        RES_0402-150.0,1%,1/16W,CHIP,GA
PVCCIO_CPU0              R4R3             1        RES_0402-150.0,1%,1/16W,CHIP,GA
PVCCIO_CPU0              R4R4             1        RES_0402-150.0,1%,1/16W,CHIP,GA
PVCCIO_CPU0              R4T5             1        RES_0402-240,1.0%,1/16W,CHIP,GA
PVCCIO_CPU0              R4T6             1        RES_0402-240,1.0%,1/16W,CHIP,GA
PVCCIO_CPU0              R5D3             1        RES_0402-240,1.0%,1/16W,CHIP,GA
PVCCIO_CPU0              R5D4             1        RES_0402-240,1.0%,1/16W,EMPTY,A
PVCCIO_CPU0              R5D6             1        RES_0402-10.0,1%,1/16W,EMPTY,GA
PVCCIO_CPU0              R6B1             1        RES_0402-49.9,1%,1/16W,CHIP,G2A
PVCCIO_CPU0              R6B2             1        RES_0402-100.0,1%,1/16W,CHIP,GA
PVCCIO_CPU0              R6D7             1        RES_0402-240,1.0%,1/16W,EMPTY,A
PVCCIO_CPU0              R6D8             1        RES_0402-49.9,1%,1/16W,CHIP,G2A
PVCCIO_CPU0              R6D9             1        RES_0402-150.0,1%,1/16W,CHIP,GA
PVCCIO_CPU0              R6D10            1        RES_0402-240,1.0%,1/16W,EMPTY,A
PVCCIO_CPU0              R6D12            1        RES_0402-49.9,1%,1/16W,CHIP,G2A
PVCCIO_CPU0              R6D13            1        RES_0402-240,1.0%,1/16W,EMPTY,A
PVCCIO_CPU0              R6D14            1        RES_0402-240,1.0%,1/16W,EMPTY,A
PVCCIO_CPU0              R6D15            1        RES_0402-240,1.0%,1/16W,EMPTY,A
PVCCIO_CPU0              R6N1             2        RES_0402-49.9,1%,1/16W,CHIP,G2A
PVCCIO_CPU0              R6N2             2        RES_0402-100.0,1%,1/16W,CHIP,GA
PVCCIO_CPU0              R6P16            1        RES_0402-1.00K,1%,1/16W,CHIP,GA
PVCCIO_CPU0              R6P46            1        RES_0402-100.0,1%,1/16W,CHIP,GA
PVCCIO_CPU0              R6T8             1        RES_0402-100.0,1%,1/16W,CHIP,GA
PVCCIO_CPU0              R6T9             1        RES_0402-100.0,1%,1/16W,CHIP,GA
PVCCIO_CPU0              R7C3             1        RES_0402-51.1,1.0%,1/16W,CHIP,A
PVCCIO_CPU0              R7C17            1        RES_0402-4.75K,1%,1/16W,CHIP,GA
PVCCIO_CPU0              R7C22            1        RES_0402-4.75K,1%,1/16W,EMPTY,A
PVCCIO_CPU0              R7D33            1        RES_0402-49.9,1%,1/16W,CHIP,G2A
PVCCIO_CPU0              R7E2             1        RES_0402-75,1.0%,1/16W,CHIP,G2A
PVCCIO_CPU0              R7P18            1        RES_0402-150.0,1%,1/16W,CHIP,GA
PVCCIO_CPU0              R7P20            1        RES_0402-150.0,1%,1/16W,CHIP,GA
PVCCIO_CPU0              R7P27            1        RES_0402-150.0,1%,1/16W,CHIP,GA
PVCCIO_CPU0              R7P30            1        RES_0402-100.0,1%,1/16W,CHIP,GA
PVCCIO_CPU0              R9A4             2        RES_0402-475.0,1%,1/16W,CHIP,GA
PVCCIO_CPU0              U5D1             AA10     SKX_EXT_B_BGA1-IC,TBD
PVCCIO_CPU0              U5D1             AC4      SKX_EXT_B_BGA1-IC,TBD
PVCCIO_CPU0              U5D1             AC20     SKX_EXT_B_BGA1-IC,TBD
PVCCIO_CPU0              U5D1             AC36     SKX_EXT_B_BGA1-IC,TBD
PVCCIO_CPU0              U5D1             AD35     SKX_EXT_B_BGA1-IC,TBD
PVCCIO_CPU0              U5D1             AD37     SKX_EXT_B_BGA1-IC,TBD
PVCCIO_CPU0              U5D1             AE10     SKX_EXT_B_BGA1-IC,TBD
PVCCIO_CPU0              U5D1             AE34     SKX_EXT_B_BGA1-IC,TBD
PVCCIO_CPU0              U5D1             AE36     SKX_EXT_B_BGA1-IC,TBD
PVCCIO_CPU0              U5D1             AF5      SKX_EXT_B_BGA1-IC,TBD
PVCCIO_CPU0              U5D1             AF35     SKX_EXT_B_BGA1-IC,TBD
PVCCIO_CPU0              U5D1             AG34     SKX_EXT_B_BGA1-IC,TBD
PVCCIO_CPU0              U5D1             AH9      SKX_EXT_B_BGA1-IC,TBD
PVCCIO_CPU0              U5D1             AL28     SKX_EXT_B_BGA1-IC,TBD
PVCCIO_CPU0              U5D1             AM5      SKX_EXT_B_BGA1-IC,TBD
PVCCIO_CPU0              U5D1             AM29     SKX_EXT_B_BGA1-IC,TBD
PVCCIO_CPU0              U5D1             AN10     SKX_EXT_B_BGA1-IC,TBD
PVCCIO_CPU0              U5D1             AR28     SKX_EXT_B_BGA1-IC,TBD
PVCCIO_CPU0              U5D1             AT5      SKX_EXT_B_BGA1-IC,TBD
PVCCIO_CPU0              U5D1             AT7      SKX_EXT_B_BGA1-IC,TBD
PVCCIO_CPU0              U5D1             AT11     SKX_EXT_B_BGA1-IC,TBD
PVCCIO_CPU0              U5D1             AV27     SKX_EXT_B_BGA1-IC,TBD
PVCCIO_CPU0              U5D1             AW6      SKX_EXT_B_BGA1-IC,TBD
PVCCIO_CPU0              U5D1             AW26     SKX_EXT_B_BGA1-IC,TBD
PVCCIO_CPU0              U5D1             AY11     SKX_EXT_B_BGA1-IC,TBD
PVCCIO_CPU0              U5D1             AY27     SKX_EXT_B_BGA1-IC,TBD
PVCCIO_CPU0              U5D1             BA24     SKX_EXT_B_BGA1-IC,TBD
PVCCIO_CPU0              U5D1             BA26     SKX_EXT_B_BGA1-IC,TBD
PVCCIO_CPU0              U5D1             BB5      SKX_EXT_B_BGA1-IC,TBD
PVCCIO_CPU0              U5D1             BB27     SKX_EXT_B_BGA1-IC,TBD
PVCCIO_CPU0              U5D1             BC26     SKX_EXT_B_BGA1-IC,TBD
PVCCIO_CPU0              U5D1             BE24     SKX_EXT_B_BGA1-IC,TBD
PVCCIO_CPU0              U5D1             BF23     SKX_EXT_B_BGA1-IC,TBD
PVCCIO_CPU0              U5D1             BF27     SKX_EXT_B_BGA1-IC,TBD
PVCCIO_CPU0              U5D1             BG26     SKX_EXT_B_BGA1-IC,TBD
PVCCIO_CPU0              U5D1             BH25     SKX_EXT_B_BGA1-IC,TBD
PVCCIO_CPU0              U5D1             BH27     SKX_EXT_B_BGA1-IC,TBD
PVCCIO_CPU0              U5D1             BJ24     SKX_EXT_B_BGA1-IC,TBD
PVCCIO_CPU0              U5D1             BJ26     SKX_EXT_B_BGA1-IC,TBD
PVCCIO_CPU0              U5D1             BK25     SKX_EXT_B_BGA1-IC,TBD
PVCCIO_CPU0              U5D1             BK27     SKX_EXT_B_BGA1-IC,TBD
PVCCIO_CPU0              U5D1             BL26     SKX_EXT_B_BGA1-IC,TBD
PVCCIO_CPU0              U5D1             BM27     SKX_EXT_B_BGA1-IC,TBD
PVCCIO_CPU0              U5D1             BP25     SKX_EXT_B_BGA1-IC,TBD
PVCCIO_CPU0              U5D1             CB13     SKX_EXT_B_BGA1-IC,TBD
PVCCIO_CPU0              U5D1             CB17     SKX_EXT_B_BGA1-IC,TBD
PVCCIO_CPU0              U5D1             CC26     SKX_EXT_B_BGA1-IC,TBD
PVCCIO_CPU0              U5D1             CD9      SKX_EXT_B_BGA1-IC,TBD
PVCCIO_CPU0              U5D1             CD27     SKX_EXT_B_BGA1-IC,TBD
PVCCIO_CPU0              U5D1             CE18     SKX_EXT_B_BGA1-IC,TBD
PVCCIO_CPU0              U5D1             CF5      SKX_EXT_B_BGA1-IC,TBD
PVCCIO_CPU0              U5D1             CF27     SKX_EXT_B_BGA1-IC,TBD
PVCCIO_CPU0              U5D1             CG14     SKX_EXT_B_BGA1-IC,TBD
PVCCIO_CPU0              U5D1             CH9      SKX_EXT_B_BGA1-IC,TBD
PVCCIO_CPU0              U5D1             CH27     SKX_EXT_B_BGA1-IC,TBD
PVCCIO_CPU0              U5D1             CJ28     SKX_EXT_B_BGA1-IC,TBD
PVCCIO_CPU0              U5D1             CK5      SKX_EXT_B_BGA1-IC,TBD
PVCCIO_CPU0              U5D1             CL12     SKX_EXT_B_BGA1-IC,TBD
PVCCIO_CPU0              U5D1             CL20     SKX_EXT_B_BGA1-IC,TBD
PVCCIO_CPU0              U5D1             CM15     SKX_EXT_B_BGA1-IC,TBD
PVCCIO_CPU0              U5D1             CN6      SKX_EXT_B_BGA1-IC,TBD
PVCCIO_CPU0              U5D1             CP13     SKX_EXT_B_BGA1-IC,TBD
PVCCIO_CPU0              U5D1             CU12     SKX_EXT_B_BGA1-IC,TBD
PVCCIO_CPU0              U5D1             CU18     SKX_EXT_B_BGA1-IC,TBD
PVCCIO_CPU0              U5D1             CV7      SKX_EXT_B_BGA1-IC,TBD
PVCCIO_CPU0              U5D1             CV21     SKX_EXT_B_BGA1-IC,TBD
PVCCIO_CPU0              U5D1             CY17     SKX_EXT_B_BGA1-IC,TBD
PVCCIO_CPU0              U5D1             D7       SKX_EXT_B_BGA1-IC,TBD
PVCCIO_CPU0              U5D1             DA14     SKX_EXT_B_BGA1-IC,TBD
PVCCIO_CPU0              U5D1             DC18     SKX_EXT_B_BGA1-IC,TBD
PVCCIO_CPU0              U5D1             DD7      SKX_EXT_B_BGA1-IC,TBD
PVCCIO_CPU0              U5D1             DE14     SKX_EXT_B_BGA1-IC,TBD
PVCCIO_CPU0              U5D1             DF13     SKX_EXT_B_BGA1-IC,TBD
PVCCIO_CPU0              U5D1             DF21     SKX_EXT_B_BGA1-IC,TBD
PVCCIO_CPU0              U5D1             DG8      SKX_EXT_B_BGA1-IC,TBD
PVCCIO_CPU0              U5D1             DH7      SKX_EXT_B_BGA1-IC,TBD
PVCCIO_CPU0              U5D1             DJ16     SKX_EXT_B_BGA1-IC,TBD
PVCCIO_CPU0              U5D1             DK21     SKX_EXT_B_BGA1-IC,TBD
PVCCIO_CPU0              U5D1             DM17     SKX_EXT_B_BGA1-IC,TBD
PVCCIO_CPU0              U5D1             DN8      SKX_EXT_B_BGA1-IC,TBD
PVCCIO_CPU0              U5D1             DP19     SKX_EXT_B_BGA1-IC,TBD
PVCCIO_CPU0              U5D1             DR2      SKX_EXT_B_BGA1-IC,TBD
PVCCIO_CPU0              U5D1             DR10     SKX_EXT_B_BGA1-IC,TBD
PVCCIO_CPU0              U5D1             DU20     SKX_EXT_B_BGA1-IC,TBD
PVCCIO_CPU0              U5D1             DV11     SKX_EXT_B_BGA1-IC,TBD
PVCCIO_CPU0              U5D1             EA12     SKX_EXT_B_BGA1-IC,TBD
PVCCIO_CPU0              U5D1             EB15     SKX_EXT_B_BGA1-IC,TBD
PVCCIO_CPU0              U5D1             EE10     SKX_EXT_B_BGA1-IC,TBD
PVCCIO_CPU0              U5D1             H13      SKX_EXT_B_BGA1-IC,TBD
PVCCIO_CPU0              U5D1             J2       SKX_EXT_B_BGA1-IC,TBD
PVCCIO_CPU0              U5D1             J10      SKX_EXT_B_BGA1-IC,TBD
PVCCIO_CPU0              U5D1             K15      SKX_EXT_B_BGA1-IC,TBD
PVCCIO_CPU0              U5D1             L14      SKX_EXT_B_BGA1-IC,TBD
PVCCIO_CPU0              U5D1             L16      SKX_EXT_B_BGA1-IC,TBD
PVCCIO_CPU0              U5D1             M7       SKX_EXT_B_BGA1-IC,TBD
PVCCIO_CPU0              U5D1             M9       SKX_EXT_B_BGA1-IC,TBD
PVCCIO_CPU0              U5D1             M11      SKX_EXT_B_BGA1-IC,TBD
PVCCIO_CPU0              U5D1             M21      SKX_EXT_B_BGA1-IC,TBD
PVCCIO_CPU0              U5D1             N18      SKX_EXT_B_BGA1-IC,TBD
PVCCIO_CPU0              U5D1             P5       SKX_EXT_B_BGA1-IC,TBD
PVCCIO_CPU0              U5D1             T3       SKX_EXT_B_BGA1-IC,TBD
PVCCIO_CPU0              U5D1             U14      SKX_EXT_B_BGA1-IC,TBD
PVCCIO_CPU0              U5D1             W4       SKX_EXT_B_BGA1-IC,TBD
PVCCIO_CPU0              U5D1             W6       SKX_EXT_B_BGA1-IC,TBD
PVCCIO_CPU0              U5D1             W10      SKX_EXT_B_BGA1-IC,TBD
PVCCIO_CPU0              U6F1             1        PCA9617_SSOP-IC,G81764-001-GNDA
PVCCIO_CPU0              U7E1             1        PCA9617_SSOP-IC,G81764-001-GNDA
PVCCIO_CPU0              U9F4             V19      AST1250_BGA-IC,G85138-002
PVCCIO_CPU1              C3B4             1        CAP_A_0402V-0.1UF,16V,10%,X7R,A
PVCCIO_CPU1              C3D8             1        CAP_A_0603V-22.0UF,4V,20%,X6S,A
PVCCIO_CPU1              C3D9             1        CAP_A_0603V-22.0UF,4V,20%,X6S,A
PVCCIO_CPU1              C3D15            1        CAP_A_0603V-22.0UF,4V,20%,X6S,A
PVCCIO_CPU1              C3D16            1        CAP_A_0603V-22.0UF,4V,20%,X6S,A
PVCCIO_CPU1              C3D23            1        CAP_A_0603V-22.0UF,4V,20%,X6S,A
PVCCIO_CPU1              C3D24            1        CAP_A_0603V-22.0UF,4V,20%,X6S,A
PVCCIO_CPU1              C3E1             1        CAP_A_0603V-22.0UF,4V,20%,X6S,A
PVCCIO_CPU1              C4E7             1        CAPP_3018-470UF,2.5V,20%,ALUM,A
PVCCIO_CPU1              C4G22            1        CAP_A_0402V-0.1UF,16V,10%,X7R,A
PVCCIO_CPU1              C6R5             1        CAPP_3018-470UF,2.5V,20%,ALUM,A
PVCCIO_CPU1              C6R12            1        CAPP_3018-470UF,2.5V,20%,ALUM,A
PVCCIO_CPU1              C7P3             1        CAP_0805-47UF,4V,20%,X6S,C9533A
PVCCIO_CPU1              C7P12            1        CAP_A_0603V-22.0UF,4V,20%,X6S,A
PVCCIO_CPU1              C7P16            1        CAP_A_0603V-22.0UF,4V,20%,X6S,A
PVCCIO_CPU1              C7P17            1        CAP_0805-47UF,4V,20%,X6S,C9533A
PVCCIO_CPU1              C7P18            1        CAP_0805-47UF,4V,20%,X6S,C9533A
PVCCIO_CPU1              C7R1             1        CAP_A_0603V-22.0UF,4V,20%,X6S,A
PVCCIO_CPU1              C9M8             1        CAP_A_0402V-0.1UF,16V,10%,X7R,A
PVCCIO_CPU1              EU4E2            1        IR354XX_SM-IR35412,IC,H73684-0A
PVCCIO_CPU1              J4B2             F1       SCONN120_H61426002_SM-CONN,H61A
PVCCIO_CPU1              L4E2             2        INDUCTOR_SM-150NH,IND,D92183-0A
PVCCIO_CPU1              R1U35            1        RES_0402-150.0,1%,1/16W,CHIP,GA
PVCCIO_CPU1              R1U41            1        RES_0402-150.0,1%,1/16W,CHIP,GA
PVCCIO_CPU1              R2T73            1        RES_0402-150.0,1%,1/16W,CHIP,GA
PVCCIO_CPU1              R3B2             2        RES_0402-49.9,1%,1/16W,CHIP,G2A
PVCCIO_CPU1              R3B4             2        RES_0402-100.0,1%,1/16W,CHIP,GA
PVCCIO_CPU1              R3D15            1        RES_0402-49.9,1%,1/16W,CHIP,G2A
PVCCIO_CPU1              R3D16            1        RES_0402-240,1.0%,1/16W,EMPTY,A
PVCCIO_CPU1              R3D17            1        RES_0402-240,1.0%,1/16W,EMPTY,A
PVCCIO_CPU1              R3D20            1        RES_0402-49.9,1%,1/16W,CHIP,G2A
PVCCIO_CPU1              R3D22            1        RES_0402-240,1.0%,1/16W,EMPTY,A
PVCCIO_CPU1              R3D23            1        RES_0402-240,1.0%,1/16W,EMPTY,A
PVCCIO_CPU1              R3D24            1        RES_0402-240,1.0%,1/16W,CHIP,GA
PVCCIO_CPU1              R3D25            1        RES_0402-240,1.0%,1/16W,EMPTY,A
PVCCIO_CPU1              R3D26            1        RES_0402-240,1.0%,1/16W,EMPTY,A
PVCCIO_CPU1              R3D32            1        RES_0402-10.0,1%,1/16W,EMPTY,GA
PVCCIO_CPU1              R3E1             2        RES_0402-100.0,1%,1/16W,CHIP,GA
PVCCIO_CPU1              R3P41            1        RES_0402-75,1.0%,1/16W,CHIP,G2A
PVCCIO_CPU1              R4C10            1        RES_0402-240,1.0%,1/16W,CHIP,GA
PVCCIO_CPU1              R6P33            1        RES_0402-110,1%,1/16W,EMPTY,G2A
PVCCIO_CPU1              R6P35            1        RES_0402-100.0,1%,1/16W,EMPTY,A
PVCCIO_CPU1              R6T1             1        RES_0402-240,1.0%,1/16W,CHIP,GA
PVCCIO_CPU1              R6T2             1        RES_0402-240,1.0%,1/16W,CHIP,GA
PVCCIO_CPU1              R6T6             1        RES_0402-150.0,1%,1/16W,CHIP,GA
PVCCIO_CPU1              R6T7             1        RES_0402-150.0,1%,1/16W,CHIP,GA
PVCCIO_CPU1              R7M2             1        RES_0402-240,1.0%,1/16W,CHIP,GA
PVCCIO_CPU1              R7M7             1        RES_0402-240,1.0%,1/16W,CHIP,GA
PVCCIO_CPU1              R7P5             2        RES_0402-150.0,1%,1/16W,CHIP,GA
PVCCIO_CPU1              R7P21            2        RES_0402-150.0,1%,1/16W,CHIP,GA
PVCCIO_CPU1              R7P22            1        RES_0402-240,1.0%,1/16W,EMPTY,A
PVCCIO_CPU1              R7P28            1        RES_0402-150.0,1%,1/16W,CHIP,GA
PVCCIO_CPU1              R7R1             1        RES_0402-51.1,1.0%,1/16W,CHIP,A
PVCCIO_CPU1              R9M6             1        RES_0402-49.9,1%,1/16W,CHIP,G2A
PVCCIO_CPU1              R9M7             1        RES_0402-100.0,1%,1/16W,EMPTY,A
PVCCIO_CPU1              R9M18            1        RES_0402-240,1.0%,1/16W,CHIP,GA
PVCCIO_CPU1              R9M19            1        RES_0402-240,1.0%,1/16W,CHIP,GA
PVCCIO_CPU1              R9N1             1        RES_0402-49.9,1%,1/16W,CHIP,G2A
PVCCIO_CPU1              R9N2             1        RES_0402-100.0,1%,1/16W,CHIP,GA
PVCCIO_CPU1              R9N14            1        RES_0402-1.00K,1%,1/16W,CHIP,GA
PVCCIO_CPU1              R9P1             1        RES_0402-100.0,1%,1/16W,CHIP,GA
PVCCIO_CPU1              R9P2             1        RES_0402-49.9,1%,1/16W,CHIP,G2A
PVCCIO_CPU1              R9U3             1        RES_0402-100.0,1%,1/16W,CHIP,GA
PVCCIO_CPU1              R9U4             1        RES_0402-49.9,1%,1/16W,EMPTY,GA
PVCCIO_CPU1              U1B2             1        PCA9517_SM-IC,G77073-001-GND=GA
PVCCIO_CPU1              U2D1             AA10     SKX_EXT_B_BGA1-IC,TBD
PVCCIO_CPU1              U2D1             AC4      SKX_EXT_B_BGA1-IC,TBD
PVCCIO_CPU1              U2D1             AC20     SKX_EXT_B_BGA1-IC,TBD
PVCCIO_CPU1              U2D1             AC36     SKX_EXT_B_BGA1-IC,TBD
PVCCIO_CPU1              U2D1             AD35     SKX_EXT_B_BGA1-IC,TBD
PVCCIO_CPU1              U2D1             AD37     SKX_EXT_B_BGA1-IC,TBD
PVCCIO_CPU1              U2D1             AE10     SKX_EXT_B_BGA1-IC,TBD
PVCCIO_CPU1              U2D1             AE34     SKX_EXT_B_BGA1-IC,TBD
PVCCIO_CPU1              U2D1             AE36     SKX_EXT_B_BGA1-IC,TBD
PVCCIO_CPU1              U2D1             AF5      SKX_EXT_B_BGA1-IC,TBD
PVCCIO_CPU1              U2D1             AF35     SKX_EXT_B_BGA1-IC,TBD
PVCCIO_CPU1              U2D1             AG34     SKX_EXT_B_BGA1-IC,TBD
PVCCIO_CPU1              U2D1             AH9      SKX_EXT_B_BGA1-IC,TBD
PVCCIO_CPU1              U2D1             AL28     SKX_EXT_B_BGA1-IC,TBD
PVCCIO_CPU1              U2D1             AM5      SKX_EXT_B_BGA1-IC,TBD
PVCCIO_CPU1              U2D1             AM29     SKX_EXT_B_BGA1-IC,TBD
PVCCIO_CPU1              U2D1             AN10     SKX_EXT_B_BGA1-IC,TBD
PVCCIO_CPU1              U2D1             AR28     SKX_EXT_B_BGA1-IC,TBD
PVCCIO_CPU1              U2D1             AT5      SKX_EXT_B_BGA1-IC,TBD
PVCCIO_CPU1              U2D1             AT7      SKX_EXT_B_BGA1-IC,TBD
PVCCIO_CPU1              U2D1             AT11     SKX_EXT_B_BGA1-IC,TBD
PVCCIO_CPU1              U2D1             AV27     SKX_EXT_B_BGA1-IC,TBD
PVCCIO_CPU1              U2D1             AW6      SKX_EXT_B_BGA1-IC,TBD
PVCCIO_CPU1              U2D1             AW26     SKX_EXT_B_BGA1-IC,TBD
PVCCIO_CPU1              U2D1             AY11     SKX_EXT_B_BGA1-IC,TBD
PVCCIO_CPU1              U2D1             AY27     SKX_EXT_B_BGA1-IC,TBD
PVCCIO_CPU1              U2D1             BA24     SKX_EXT_B_BGA1-IC,TBD
PVCCIO_CPU1              U2D1             BA26     SKX_EXT_B_BGA1-IC,TBD
PVCCIO_CPU1              U2D1             BB5      SKX_EXT_B_BGA1-IC,TBD
PVCCIO_CPU1              U2D1             BB27     SKX_EXT_B_BGA1-IC,TBD
PVCCIO_CPU1              U2D1             BC26     SKX_EXT_B_BGA1-IC,TBD
PVCCIO_CPU1              U2D1             BE24     SKX_EXT_B_BGA1-IC,TBD
PVCCIO_CPU1              U2D1             BF23     SKX_EXT_B_BGA1-IC,TBD
PVCCIO_CPU1              U2D1             BF27     SKX_EXT_B_BGA1-IC,TBD
PVCCIO_CPU1              U2D1             BG26     SKX_EXT_B_BGA1-IC,TBD
PVCCIO_CPU1              U2D1             BH25     SKX_EXT_B_BGA1-IC,TBD
PVCCIO_CPU1              U2D1             BH27     SKX_EXT_B_BGA1-IC,TBD
PVCCIO_CPU1              U2D1             BJ24     SKX_EXT_B_BGA1-IC,TBD
PVCCIO_CPU1              U2D1             BJ26     SKX_EXT_B_BGA1-IC,TBD
PVCCIO_CPU1              U2D1             BK25     SKX_EXT_B_BGA1-IC,TBD
PVCCIO_CPU1              U2D1             BK27     SKX_EXT_B_BGA1-IC,TBD
PVCCIO_CPU1              U2D1             BL26     SKX_EXT_B_BGA1-IC,TBD
PVCCIO_CPU1              U2D1             BM27     SKX_EXT_B_BGA1-IC,TBD
PVCCIO_CPU1              U2D1             BP25     SKX_EXT_B_BGA1-IC,TBD
PVCCIO_CPU1              U2D1             CB13     SKX_EXT_B_BGA1-IC,TBD
PVCCIO_CPU1              U2D1             CB17     SKX_EXT_B_BGA1-IC,TBD
PVCCIO_CPU1              U2D1             CC26     SKX_EXT_B_BGA1-IC,TBD
PVCCIO_CPU1              U2D1             CD9      SKX_EXT_B_BGA1-IC,TBD
PVCCIO_CPU1              U2D1             CD27     SKX_EXT_B_BGA1-IC,TBD
PVCCIO_CPU1              U2D1             CE18     SKX_EXT_B_BGA1-IC,TBD
PVCCIO_CPU1              U2D1             CF5      SKX_EXT_B_BGA1-IC,TBD
PVCCIO_CPU1              U2D1             CF27     SKX_EXT_B_BGA1-IC,TBD
PVCCIO_CPU1              U2D1             CG14     SKX_EXT_B_BGA1-IC,TBD
PVCCIO_CPU1              U2D1             CH9      SKX_EXT_B_BGA1-IC,TBD
PVCCIO_CPU1              U2D1             CH27     SKX_EXT_B_BGA1-IC,TBD
PVCCIO_CPU1              U2D1             CJ28     SKX_EXT_B_BGA1-IC,TBD
PVCCIO_CPU1              U2D1             CK5      SKX_EXT_B_BGA1-IC,TBD
PVCCIO_CPU1              U2D1             CL12     SKX_EXT_B_BGA1-IC,TBD
PVCCIO_CPU1              U2D1             CL20     SKX_EXT_B_BGA1-IC,TBD
PVCCIO_CPU1              U2D1             CM15     SKX_EXT_B_BGA1-IC,TBD
PVCCIO_CPU1              U2D1             CN6      SKX_EXT_B_BGA1-IC,TBD
PVCCIO_CPU1              U2D1             CP13     SKX_EXT_B_BGA1-IC,TBD
PVCCIO_CPU1              U2D1             CU12     SKX_EXT_B_BGA1-IC,TBD
PVCCIO_CPU1              U2D1             CU18     SKX_EXT_B_BGA1-IC,TBD
PVCCIO_CPU1              U2D1             CV7      SKX_EXT_B_BGA1-IC,TBD
PVCCIO_CPU1              U2D1             CV21     SKX_EXT_B_BGA1-IC,TBD
PVCCIO_CPU1              U2D1             CY17     SKX_EXT_B_BGA1-IC,TBD
PVCCIO_CPU1              U2D1             D7       SKX_EXT_B_BGA1-IC,TBD
PVCCIO_CPU1              U2D1             DA14     SKX_EXT_B_BGA1-IC,TBD
PVCCIO_CPU1              U2D1             DC18     SKX_EXT_B_BGA1-IC,TBD
PVCCIO_CPU1              U2D1             DD7      SKX_EXT_B_BGA1-IC,TBD
PVCCIO_CPU1              U2D1             DE14     SKX_EXT_B_BGA1-IC,TBD
PVCCIO_CPU1              U2D1             DF13     SKX_EXT_B_BGA1-IC,TBD
PVCCIO_CPU1              U2D1             DF21     SKX_EXT_B_BGA1-IC,TBD
PVCCIO_CPU1              U2D1             DG8      SKX_EXT_B_BGA1-IC,TBD
PVCCIO_CPU1              U2D1             DH7      SKX_EXT_B_BGA1-IC,TBD
PVCCIO_CPU1              U2D1             DJ16     SKX_EXT_B_BGA1-IC,TBD
PVCCIO_CPU1              U2D1             DK21     SKX_EXT_B_BGA1-IC,TBD
PVCCIO_CPU1              U2D1             DM17     SKX_EXT_B_BGA1-IC,TBD
PVCCIO_CPU1              U2D1             DN8      SKX_EXT_B_BGA1-IC,TBD
PVCCIO_CPU1              U2D1             DP19     SKX_EXT_B_BGA1-IC,TBD
PVCCIO_CPU1              U2D1             DR2      SKX_EXT_B_BGA1-IC,TBD
PVCCIO_CPU1              U2D1             DR10     SKX_EXT_B_BGA1-IC,TBD
PVCCIO_CPU1              U2D1             DU20     SKX_EXT_B_BGA1-IC,TBD
PVCCIO_CPU1              U2D1             DV11     SKX_EXT_B_BGA1-IC,TBD
PVCCIO_CPU1              U2D1             EA12     SKX_EXT_B_BGA1-IC,TBD
PVCCIO_CPU1              U2D1             EB15     SKX_EXT_B_BGA1-IC,TBD
PVCCIO_CPU1              U2D1             EE10     SKX_EXT_B_BGA1-IC,TBD
PVCCIO_CPU1              U2D1             H13      SKX_EXT_B_BGA1-IC,TBD
PVCCIO_CPU1              U2D1             J2       SKX_EXT_B_BGA1-IC,TBD
PVCCIO_CPU1              U2D1             J10      SKX_EXT_B_BGA1-IC,TBD
PVCCIO_CPU1              U2D1             K15      SKX_EXT_B_BGA1-IC,TBD
PVCCIO_CPU1              U2D1             L14      SKX_EXT_B_BGA1-IC,TBD
PVCCIO_CPU1              U2D1             L16      SKX_EXT_B_BGA1-IC,TBD
PVCCIO_CPU1              U2D1             M7       SKX_EXT_B_BGA1-IC,TBD
PVCCIO_CPU1              U2D1             M9       SKX_EXT_B_BGA1-IC,TBD
PVCCIO_CPU1              U2D1             M11      SKX_EXT_B_BGA1-IC,TBD
PVCCIO_CPU1              U2D1             M21      SKX_EXT_B_BGA1-IC,TBD
PVCCIO_CPU1              U2D1             N18      SKX_EXT_B_BGA1-IC,TBD
PVCCIO_CPU1              U2D1             P5       SKX_EXT_B_BGA1-IC,TBD
PVCCIO_CPU1              U2D1             T3       SKX_EXT_B_BGA1-IC,TBD
PVCCIO_CPU1              U2D1             U14      SKX_EXT_B_BGA1-IC,TBD
PVCCIO_CPU1              U2D1             W4       SKX_EXT_B_BGA1-IC,TBD
PVCCIO_CPU1              U2D1             W6       SKX_EXT_B_BGA1-IC,TBD
PVCCIO_CPU1              U2D1             W10      SKX_EXT_B_BGA1-IC,TBD
PVCCIO_CPU1              U3B1             1        PCA9617_SSOP-IC,G81764-001-GNDA
PVCCIO_CPU1              U4G1             1        PCA9617_SSOP-IC,G81764-001-GNDA
PVCCMCP_CPU0             C3R4             1        CAPP_3018-470UF,2.5V,20%,ALUM,A
PVCCMCP_CPU0             C4P2             1        CAP_0805-47UF,4V,20%,X6S,C9533A
PVCCMCP_CPU0             C4P3             1        CAP_0805-47UF,4V,20%,X6S,C9533A
PVCCMCP_CPU0             C4P4             1        CAP_0805-47UF,4V,20%,X6S,C9533A
PVCCMCP_CPU0             C4P5             1        CAP_0805-47UF,4V,20%,X6S,C9533A
PVCCMCP_CPU0             C4P7             1        CAP_0805-47UF,4V,20%,X6S,C9533A
PVCCMCP_CPU0             C4R1             1        CAPP_3018-470UF,2.5V,20%,ALUM,A
PVCCMCP_CPU0             C5D20            1        CAP_A_0603V-22.0UF,4V,20%,X6S,A
PVCCMCP_CPU0             C5D21            1        CAP_A_0603V-22.0UF,4V,20%,X6S,A
PVCCMCP_CPU0             C5D22            1        CAP_A_0603V-22.0UF,4V,20%,X6S,A
PVCCMCP_CPU0             C5D23            1        CAP_A_0603V-22.0UF,4V,20%,X6S,A
PVCCMCP_CPU0             C5D33            1        CAP_A_0603V-22.0UF,4V,20%,X6S,A
PVCCMCP_CPU0             C5D34            1        CAP_A_0603V-22.0UF,4V,20%,X6S,A
PVCCMCP_CPU0             C5D35            1        CAP_A_0603V-22.0UF,4V,20%,X6S,A
PVCCMCP_CPU0             C5D36            1        CAP_A_0603V-22.0UF,4V,20%,X6S,A
PVCCMCP_CPU0             C5D37            1        CAP_A_0603V-22.0UF,4V,20%,X6S,A
PVCCMCP_CPU0             C5D38            1        CAP_A_0603V-22.0UF,4V,20%,X6S,A
PVCCMCP_CPU0             C5D48            1        CAP_A_0603V-22.0UF,4V,20%,X6S,A
PVCCMCP_CPU0             C5D49            1        CAP_A_0603V-22.0UF,4V,20%,X6S,A
PVCCMCP_CPU0             C5D50            1        CAP_A_0603V-22.0UF,4V,20%,X6S,A
PVCCMCP_CPU0             C5D51            1        CAP_A_0603V-22.0UF,4V,20%,X6S,A
PVCCMCP_CPU0             C5D52            1        CAP_A_0603V-22.0UF,4V,20%,X6S,A
PVCCMCP_CPU0             C5D53            1        CAP_A_0603V-22.0UF,4V,20%,X6S,A
PVCCMCP_CPU0             C5P10            1        CAP_0805-47UF,4V,20%,X6S,C9533A
PVCCMCP_CPU0             C5P11            1        CAP_0805-47UF,4V,20%,X6S,C9533A
PVCCMCP_CPU0             C5P12            1        CAP_0805-47UF,4V,20%,X6S,C9533A
PVCCMCP_CPU0             C5P13            1        CAP_0805-47UF,4V,20%,X6S,C9533A
PVCCMCP_CPU0             C5P18            1        CAP_0805-47UF,4V,20%,X6S,C9533A
PVCCMCP_CPU0             C5P19            1        CAP_0805-47UF,4V,20%,X6S,C9533A
PVCCMCP_CPU0             C5P20            1        CAP_0805-47UF,4V,20%,X6S,C9533A
PVCCMCP_CPU0             C5P21            1        CAP_0805-47UF,4V,20%,X6S,C9533A
PVCCMCP_CPU0             C5P28            1        CAP_0805-47UF,4V,20%,X6S,C9533A
PVCCMCP_CPU0             C5P29            1        CAP_0805-47UF,4V,20%,X6S,C9533A
PVCCMCP_CPU0             C5P30            1        CAP_0805-47UF,4V,20%,X6S,C9533A
PVCCMCP_CPU0             C5P31            1        CAP_0805-47UF,4V,20%,X6S,C9533A
PVCCMCP_CPU0             C6D2             1        CAP_A_0603V-22.0UF,4V,20%,X6S,A
PVCCMCP_CPU0             C6D5             1        CAP_A_0603V-22.0UF,4V,20%,X6S,A
PVCCMCP_CPU0             C6D8             1        CAP_A_0603V-22.0UF,4V,20%,X6S,A
PVCCMCP_CPU0             J6E1             A1       SCONN120_H61426002_SM-CONN,H61A
PVCCMCP_CPU0             J6E1             A2       SCONN120_H61426002_SM-CONN,H61A
PVCCMCP_CPU0             J6E1             A3       SCONN120_H61426002_SM-CONN,H61A
PVCCMCP_CPU0             J6E1             A5       SCONN120_H61426002_SM-CONN,H61A
PVCCMCP_CPU0             J6E1             A6       SCONN120_H61426002_SM-CONN,H61A
PVCCMCP_CPU0             J6E1             A7       SCONN120_H61426002_SM-CONN,H61A
PVCCMCP_CPU0             J6E1             A8       SCONN120_H61426002_SM-CONN,H61A
PVCCMCP_CPU0             J6E1             A9       SCONN120_H61426002_SM-CONN,H61A
PVCCMCP_CPU0             J6E1             A10      SCONN120_H61426002_SM-CONN,H61A
PVCCMCP_CPU0             J6E1             A11      SCONN120_H61426002_SM-CONN,H61A
PVCCMCP_CPU0             J6E1             A12      SCONN120_H61426002_SM-CONN,H61A
PVCCMCP_CPU0             J6E1             A13      SCONN120_H61426002_SM-CONN,H61A
PVCCMCP_CPU0             J6E1             A14      SCONN120_H61426002_SM-CONN,H61A
PVCCMCP_CPU0             J6E1             A15      SCONN120_H61426002_SM-CONN,H61A
PVCCMCP_CPU0             J6E1             A16      SCONN120_H61426002_SM-CONN,H61A
PVCCMCP_CPU0             J6E1             A17      SCONN120_H61426002_SM-CONN,H61A
PVCCMCP_CPU0             J6E1             A18      SCONN120_H61426002_SM-CONN,H61A
PVCCMCP_CPU0             J6E1             B1       SCONN120_H61426002_SM-CONN,H61A
PVCCMCP_CPU0             J6E1             B2       SCONN120_H61426002_SM-CONN,H61A
PVCCMCP_CPU0             J6E1             B3       SCONN120_H61426002_SM-CONN,H61A
PVCCMCP_CPU0             J6E1             B5       SCONN120_H61426002_SM-CONN,H61A
PVCCMCP_CPU0             J6E1             B6       SCONN120_H61426002_SM-CONN,H61A
PVCCMCP_CPU0             J6E1             B7       SCONN120_H61426002_SM-CONN,H61A
PVCCMCP_CPU0             J6E1             B8       SCONN120_H61426002_SM-CONN,H61A
PVCCMCP_CPU0             J6E1             B9       SCONN120_H61426002_SM-CONN,H61A
PVCCMCP_CPU0             J6E1             B10      SCONN120_H61426002_SM-CONN,H61A
PVCCMCP_CPU0             J6E1             B11      SCONN120_H61426002_SM-CONN,H61A
PVCCMCP_CPU0             J6E1             B12      SCONN120_H61426002_SM-CONN,H61A
PVCCMCP_CPU0             J6E1             B13      SCONN120_H61426002_SM-CONN,H61A
PVCCMCP_CPU0             J6E1             B14      SCONN120_H61426002_SM-CONN,H61A
PVCCMCP_CPU0             J6E1             B15      SCONN120_H61426002_SM-CONN,H61A
PVCCMCP_CPU0             J6E1             B16      SCONN120_H61426002_SM-CONN,H61A
PVCCMCP_CPU0             J6E1             B17      SCONN120_H61426002_SM-CONN,H61A
PVCCMCP_CPU0             J6E1             B18      SCONN120_H61426002_SM-CONN,H61A
PVCCMCP_CPU0             J6E1             C1       SCONN120_H61426002_SM-CONN,H61A
PVCCMCP_CPU0             J6E1             C2       SCONN120_H61426002_SM-CONN,H61A
PVCCMCP_CPU0             J6E1             C3       SCONN120_H61426002_SM-CONN,H61A
PVCCMCP_CPU0             J6E1             C4       SCONN120_H61426002_SM-CONN,H61A
PVCCMCP_CPU0             J6E1             C5       SCONN120_H61426002_SM-CONN,H61A
PVCCMCP_CPU0             J6E1             C6       SCONN120_H61426002_SM-CONN,H61A
PVCCMCP_CPU0             J6E1             C7       SCONN120_H61426002_SM-CONN,H61A
PVCCMCP_CPU0             J6E1             C8       SCONN120_H61426002_SM-CONN,H61A
PVCCMCP_CPU0             J6E1             C9       SCONN120_H61426002_SM-CONN,H61A
PVCCMCP_CPU0             J6E1             C10      SCONN120_H61426002_SM-CONN,H61A
PVCCMCP_CPU0             J6E1             C11      SCONN120_H61426002_SM-CONN,H61A
PVCCMCP_CPU0             J6E1             C12      SCONN120_H61426002_SM-CONN,H61A
PVCCMCP_CPU0             J6E1             C13      SCONN120_H61426002_SM-CONN,H61A
PVCCMCP_CPU0             J6E1             C14      SCONN120_H61426002_SM-CONN,H61A
PVCCMCP_CPU0             J6E1             C15      SCONN120_H61426002_SM-CONN,H61A
PVCCMCP_CPU0             J6E1             C16      SCONN120_H61426002_SM-CONN,H61A
PVCCMCP_CPU0             J6E1             C17      SCONN120_H61426002_SM-CONN,H61A
PVCCMCP_CPU0             J6E1             C18      SCONN120_H61426002_SM-CONN,H61A
PVCCMCP_CPU0             U5D1             AM21     SKX_EXT_B_BGA1-IC,TBD
PVCCMCP_CPU0             U5D1             AM25     SKX_EXT_B_BGA1-IC,TBD
PVCCMCP_CPU0             U5D1             AN18     SKX_EXT_B_BGA1-IC,TBD
PVCCMCP_CPU0             U5D1             AN22     SKX_EXT_B_BGA1-IC,TBD
PVCCMCP_CPU0             U5D1             AN24     SKX_EXT_B_BGA1-IC,TBD
PVCCMCP_CPU0             U5D1             AN26     SKX_EXT_B_BGA1-IC,TBD
PVCCMCP_CPU0             U5D1             AP23     SKX_EXT_B_BGA1-IC,TBD
PVCCMCP_CPU0             U5D1             AP25     SKX_EXT_B_BGA1-IC,TBD
PVCCMCP_CPU0             U5D1             AR20     SKX_EXT_B_BGA1-IC,TBD
PVCCMCP_CPU0             U5D1             AR22     SKX_EXT_B_BGA1-IC,TBD
PVCCMCP_CPU0             U5D1             AR26     SKX_EXT_B_BGA1-IC,TBD
PVCCMCP_CPU0             U5D1             AT23     SKX_EXT_B_BGA1-IC,TBD
PVCCMCP_CPU0             U5D1             AT25     SKX_EXT_B_BGA1-IC,TBD
PVCCMCP_CPU0             U5D1             BD13     SKX_EXT_B_BGA1-IC,TBD
PVCCMCP_CPU0             U5D1             BE12     SKX_EXT_B_BGA1-IC,TBD
PVCCMCP_CPU0             U5D1             BE14     SKX_EXT_B_BGA1-IC,TBD
PVCCMCP_CPU0             U5D1             BF11     SKX_EXT_B_BGA1-IC,TBD
PVCCMCP_CPU0             U5D1             BF13     SKX_EXT_B_BGA1-IC,TBD
PVCCMCP_CPU0             U5D1             BG12     SKX_EXT_B_BGA1-IC,TBD
PVCCMCP_CPU0             U5D1             BG14     SKX_EXT_B_BGA1-IC,TBD
PVCCMCP_CPU0             U5D1             BH13     SKX_EXT_B_BGA1-IC,TBD
PVCCMCP_CPU0             U5D1             BH19     SKX_EXT_B_BGA1-IC,TBD
PVCCMCP_CPU0             U5D1             BJ12     SKX_EXT_B_BGA1-IC,TBD
PVCCMCP_CPU0             U5D1             BJ14     SKX_EXT_B_BGA1-IC,TBD
PVCCMCP_CPU0             U5D1             BJ16     SKX_EXT_B_BGA1-IC,TBD
PVCCMCP_CPU0             U5D1             BJ18     SKX_EXT_B_BGA1-IC,TBD
PVCCMCP_CPU0             U5D1             BJ20     SKX_EXT_B_BGA1-IC,TBD
PVCCMCP_CPU0             U5D1             BK13     SKX_EXT_B_BGA1-IC,TBD
PVCCMCP_CPU0             U5D1             BK15     SKX_EXT_B_BGA1-IC,TBD
PVCCMCP_CPU0             U5D1             BK17     SKX_EXT_B_BGA1-IC,TBD
PVCCMCP_CPU0             U5D1             BL14     SKX_EXT_B_BGA1-IC,TBD
PVCCMCP_CPU0             U5D1             BL18     SKX_EXT_B_BGA1-IC,TBD
PVCCMCP_CPU0             U5D1             BL20     SKX_EXT_B_BGA1-IC,TBD
PVCCMCP_CPU0             U5D1             BM17     SKX_EXT_B_BGA1-IC,TBD
PVCCMCP_CPU0             U5D1             BM19     SKX_EXT_B_BGA1-IC,TBD
PVCCMCP_CPU0             U5D1             BN18     SKX_EXT_B_BGA1-IC,TBD
PVCCMCP_CPU0             U5D1             BP17     SKX_EXT_B_BGA1-IC,TBD
PVCCMCP_CPU0             U5D1             BP21     SKX_EXT_B_BGA1-IC,TBD
PVCCMCP_CPU0             U5D1             BR22     SKX_EXT_B_BGA1-IC,TBD
PVCCMCP_CPU0             U5D1             BR24     SKX_EXT_B_BGA1-IC,TBD
PVCCMCP_CPU0             U5D1             BU18     SKX_EXT_B_BGA1-IC,TBD
PVCCMCP_CPU0             U5D1             BU20     SKX_EXT_B_BGA1-IC,TBD
PVCCMCP_CPU0             U5D1             BU22     SKX_EXT_B_BGA1-IC,TBD
PVCCMCP_CPU0             U5D1             BV19     SKX_EXT_B_BGA1-IC,TBD
PVCCMCP_CPU0             U5D1             BV21     SKX_EXT_B_BGA1-IC,TBD
PVCCMCP_CPU0             U5D1             BW20     SKX_EXT_B_BGA1-IC,TBD
PVCCMCP_CPU0             U5D1             BY19     SKX_EXT_B_BGA1-IC,TBD
PVCCMCP_CPU0             U5D1             CA22     SKX_EXT_B_BGA1-IC,TBD
PVCCMCP_CPU0             U5D1             CB19     SKX_EXT_B_BGA1-IC,TBD
PVCCMCP_CPU0             U5D1             CB21     SKX_EXT_B_BGA1-IC,TBD
PVCCMCP_CPU0             U5D1             CC20     SKX_EXT_B_BGA1-IC,TBD
PVCCMCP_CPU0             U5D1             CD19     SKX_EXT_B_BGA1-IC,TBD
PVCCMCP_CPU0             U5D1             CD21     SKX_EXT_B_BGA1-IC,TBD
PVCCMCP_CPU0             U5D1             CE22     SKX_EXT_B_BGA1-IC,TBD
PVCCMCP_CPU0             U5D1             CF19     SKX_EXT_B_BGA1-IC,TBD
PVCCMCP_CPU0             U5D1             CF21     SKX_EXT_B_BGA1-IC,TBD
PVCCMCP_CPU0             U5D1             CF23     SKX_EXT_B_BGA1-IC,TBD
PVCCMCP_CPU0             U5D1             CG20     SKX_EXT_B_BGA1-IC,TBD
PVCCMCP_CPU0             U5D1             CG26     SKX_EXT_B_BGA1-IC,TBD
PVCCMCP_CPU0             U5D1             CH21     SKX_EXT_B_BGA1-IC,TBD
PVCCMCP_CPU0             U5D1             CH23     SKX_EXT_B_BGA1-IC,TBD
PVCCMCP_CPU0             U5D1             CJ20     SKX_EXT_B_BGA1-IC,TBD
PVCCMCP_CPU0             U5D1             CJ22     SKX_EXT_B_BGA1-IC,TBD
PVCCMCP_CPU0             U5D1             CJ24     SKX_EXT_B_BGA1-IC,TBD
PVCCMCP_CPU0             U5D1             CJ26     SKX_EXT_B_BGA1-IC,TBD
PVCCMCP_CPU0             U5D1             CK23     SKX_EXT_B_BGA1-IC,TBD
PVCCMCP_CPU0             U5D1             CK25     SKX_EXT_B_BGA1-IC,TBD
PVCCMCP_CPU0             U5D1             CL24     SKX_EXT_B_BGA1-IC,TBD
PVCCMCP_CPU0             U5D1             CL26     SKX_EXT_B_BGA1-IC,TBD
PVCCMCP_CPU0             U5D1             CM23     SKX_EXT_B_BGA1-IC,TBD
PVCCMCP_CPU0             U5D1             CM25     SKX_EXT_B_BGA1-IC,TBD
PVCCMCP_CPU0             U5D1             CN24     SKX_EXT_B_BGA1-IC,TBD
PVCCMCP_CPU0             U5D1             CP23     SKX_EXT_B_BGA1-IC,TBD
PVCCMCP_CPU0             U5D1             CT23     SKX_EXT_B_BGA1-IC,TBD
PVCCMCP_CPU0             U5D1             CU24     SKX_EXT_B_BGA1-IC,TBD
PVCCMCP_CPU0             U5D1             CV23     SKX_EXT_B_BGA1-IC,TBD
PVCCMCP_CPU0             U5D1             CW24     SKX_EXT_B_BGA1-IC,TBD
PVCCMCP_CPU0             U5D1             CY25     SKX_EXT_B_BGA1-IC,TBD
PVCCMCP_CPU0             U5D1             DA24     SKX_EXT_B_BGA1-IC,TBD
PVCCMCP_CPU1             C2D18            1        CAP_A_0603V-22.0UF,4V,20%,X6S,A
PVCCMCP_CPU1             C2D28            1        CAP_A_0603V-22.0UF,4V,20%,X6S,A
PVCCMCP_CPU1             C2D29            1        CAP_A_0603V-22.0UF,4V,20%,X6S,A
PVCCMCP_CPU1             C2D39            1        CAP_A_0603V-22.0UF,4V,20%,X6S,A
PVCCMCP_CPU1             C2D40            1        CAP_A_0603V-22.0UF,4V,20%,X6S,A
PVCCMCP_CPU1             C3D4             1        CAP_A_0603V-22.0UF,4V,20%,X6S,A
PVCCMCP_CPU1             C3D5             1        CAP_A_0603V-22.0UF,4V,20%,X6S,A
PVCCMCP_CPU1             C3D6             1        CAP_A_0603V-22.0UF,4V,20%,X6S,A
PVCCMCP_CPU1             C3D7             1        CAP_A_0603V-22.0UF,4V,20%,X6S,A
PVCCMCP_CPU1             C3D10            1        CAP_A_0603V-22.0UF,4V,20%,X6S,A
PVCCMCP_CPU1             C3D11            1        CAP_A_0603V-22.0UF,4V,20%,X6S,A
PVCCMCP_CPU1             C3D12            1        CAP_A_0603V-22.0UF,4V,20%,X6S,A
PVCCMCP_CPU1             C3D13            1        CAP_A_0603V-22.0UF,4V,20%,X6S,A
PVCCMCP_CPU1             C3D14            1        CAP_A_0603V-22.0UF,4V,20%,X6S,A
PVCCMCP_CPU1             C3D17            1        CAP_A_0603V-22.0UF,4V,20%,X6S,A
PVCCMCP_CPU1             C3D18            1        CAP_A_0603V-22.0UF,4V,20%,X6S,A
PVCCMCP_CPU1             C3D19            1        CAP_A_0603V-22.0UF,4V,20%,X6S,A
PVCCMCP_CPU1             C3D20            1        CAP_A_0603V-22.0UF,4V,20%,X6S,A
PVCCMCP_CPU1             C3D21            1        CAP_A_0603V-22.0UF,4V,20%,X6S,A
PVCCMCP_CPU1             C4E24            1        CAPP_3018-470UF,2.5V,20%,ALUM,A
PVCCMCP_CPU1             C6R16            1        CAPP_3018-470UF,2.5V,20%,ALUM,A
PVCCMCP_CPU1             C7P4             1        CAP_0805-47UF,4V,20%,X6S,C9533A
PVCCMCP_CPU1             C7P5             1        CAP_0805-47UF,4V,20%,X6S,C9533A
PVCCMCP_CPU1             C7P6             1        CAP_0805-47UF,4V,20%,X6S,C9533A
PVCCMCP_CPU1             C7P7             1        CAP_0805-47UF,4V,20%,X6S,C9533A
PVCCMCP_CPU1             C7P8             1        CAP_0805-47UF,4V,20%,X6S,C9533A
PVCCMCP_CPU1             C7P9             1        CAP_0805-47UF,4V,20%,X6S,C9533A
PVCCMCP_CPU1             C7P10            1        CAP_0805-47UF,4V,20%,X6S,C9533A
PVCCMCP_CPU1             C7P11            1        CAP_0805-47UF,4V,20%,X6S,C9533A
PVCCMCP_CPU1             C7P13            1        CAP_0805-47UF,4V,20%,X6S,C9533A
PVCCMCP_CPU1             C7P14            1        CAP_0805-47UF,4V,20%,X6S,C9533A
PVCCMCP_CPU1             C7P15            1        CAP_0805-47UF,4V,20%,X6S,C9533A
PVCCMCP_CPU1             C8P8             1        CAP_0805-47UF,4V,20%,X6S,C9533A
PVCCMCP_CPU1             C8P9             1        CAP_0805-47UF,4V,20%,X6S,C9533A
PVCCMCP_CPU1             C8P14            1        CAP_0805-47UF,4V,20%,X6S,C9533A
PVCCMCP_CPU1             C8P15            1        CAP_0805-47UF,4V,20%,X6S,C9533A
PVCCMCP_CPU1             C8P22            1        CAP_0805-47UF,4V,20%,X6S,C9533A
PVCCMCP_CPU1             C8P23            1        CAP_0805-47UF,4V,20%,X6S,C9533A
PVCCMCP_CPU1             J4E1             A1       SCONN120_H61426002_SM-CONN,H61A
PVCCMCP_CPU1             J4E1             A2       SCONN120_H61426002_SM-CONN,H61A
PVCCMCP_CPU1             J4E1             A3       SCONN120_H61426002_SM-CONN,H61A
PVCCMCP_CPU1             J4E1             A5       SCONN120_H61426002_SM-CONN,H61A
PVCCMCP_CPU1             J4E1             A6       SCONN120_H61426002_SM-CONN,H61A
PVCCMCP_CPU1             J4E1             A7       SCONN120_H61426002_SM-CONN,H61A
PVCCMCP_CPU1             J4E1             A8       SCONN120_H61426002_SM-CONN,H61A
PVCCMCP_CPU1             J4E1             A9       SCONN120_H61426002_SM-CONN,H61A
PVCCMCP_CPU1             J4E1             A10      SCONN120_H61426002_SM-CONN,H61A
PVCCMCP_CPU1             J4E1             A11      SCONN120_H61426002_SM-CONN,H61A
PVCCMCP_CPU1             J4E1             A12      SCONN120_H61426002_SM-CONN,H61A
PVCCMCP_CPU1             J4E1             A13      SCONN120_H61426002_SM-CONN,H61A
PVCCMCP_CPU1             J4E1             A14      SCONN120_H61426002_SM-CONN,H61A
PVCCMCP_CPU1             J4E1             A15      SCONN120_H61426002_SM-CONN,H61A
PVCCMCP_CPU1             J4E1             A16      SCONN120_H61426002_SM-CONN,H61A
PVCCMCP_CPU1             J4E1             A17      SCONN120_H61426002_SM-CONN,H61A
PVCCMCP_CPU1             J4E1             A18      SCONN120_H61426002_SM-CONN,H61A
PVCCMCP_CPU1             J4E1             B1       SCONN120_H61426002_SM-CONN,H61A
PVCCMCP_CPU1             J4E1             B2       SCONN120_H61426002_SM-CONN,H61A
PVCCMCP_CPU1             J4E1             B3       SCONN120_H61426002_SM-CONN,H61A
PVCCMCP_CPU1             J4E1             B5       SCONN120_H61426002_SM-CONN,H61A
PVCCMCP_CPU1             J4E1             B6       SCONN120_H61426002_SM-CONN,H61A
PVCCMCP_CPU1             J4E1             B7       SCONN120_H61426002_SM-CONN,H61A
PVCCMCP_CPU1             J4E1             B8       SCONN120_H61426002_SM-CONN,H61A
PVCCMCP_CPU1             J4E1             B9       SCONN120_H61426002_SM-CONN,H61A
PVCCMCP_CPU1             J4E1             B10      SCONN120_H61426002_SM-CONN,H61A
PVCCMCP_CPU1             J4E1             B11      SCONN120_H61426002_SM-CONN,H61A
PVCCMCP_CPU1             J4E1             B12      SCONN120_H61426002_SM-CONN,H61A
PVCCMCP_CPU1             J4E1             B13      SCONN120_H61426002_SM-CONN,H61A
PVCCMCP_CPU1             J4E1             B14      SCONN120_H61426002_SM-CONN,H61A
PVCCMCP_CPU1             J4E1             B15      SCONN120_H61426002_SM-CONN,H61A
PVCCMCP_CPU1             J4E1             B16      SCONN120_H61426002_SM-CONN,H61A
PVCCMCP_CPU1             J4E1             B17      SCONN120_H61426002_SM-CONN,H61A
PVCCMCP_CPU1             J4E1             B18      SCONN120_H61426002_SM-CONN,H61A
PVCCMCP_CPU1             J4E1             C1       SCONN120_H61426002_SM-CONN,H61A
PVCCMCP_CPU1             J4E1             C2       SCONN120_H61426002_SM-CONN,H61A
PVCCMCP_CPU1             J4E1             C3       SCONN120_H61426002_SM-CONN,H61A
PVCCMCP_CPU1             J4E1             C4       SCONN120_H61426002_SM-CONN,H61A
PVCCMCP_CPU1             J4E1             C5       SCONN120_H61426002_SM-CONN,H61A
PVCCMCP_CPU1             J4E1             C6       SCONN120_H61426002_SM-CONN,H61A
PVCCMCP_CPU1             J4E1             C7       SCONN120_H61426002_SM-CONN,H61A
PVCCMCP_CPU1             J4E1             C8       SCONN120_H61426002_SM-CONN,H61A
PVCCMCP_CPU1             J4E1             C9       SCONN120_H61426002_SM-CONN,H61A
PVCCMCP_CPU1             J4E1             C10      SCONN120_H61426002_SM-CONN,H61A
PVCCMCP_CPU1             J4E1             C11      SCONN120_H61426002_SM-CONN,H61A
PVCCMCP_CPU1             J4E1             C12      SCONN120_H61426002_SM-CONN,H61A
PVCCMCP_CPU1             J4E1             C13      SCONN120_H61426002_SM-CONN,H61A
PVCCMCP_CPU1             J4E1             C14      SCONN120_H61426002_SM-CONN,H61A
PVCCMCP_CPU1             J4E1             C15      SCONN120_H61426002_SM-CONN,H61A
PVCCMCP_CPU1             J4E1             C16      SCONN120_H61426002_SM-CONN,H61A
PVCCMCP_CPU1             J4E1             C17      SCONN120_H61426002_SM-CONN,H61A
PVCCMCP_CPU1             J4E1             C18      SCONN120_H61426002_SM-CONN,H61A
PVCCMCP_CPU1             U2D1             AM21     SKX_EXT_B_BGA1-IC,TBD
PVCCMCP_CPU1             U2D1             AM25     SKX_EXT_B_BGA1-IC,TBD
PVCCMCP_CPU1             U2D1             AN18     SKX_EXT_B_BGA1-IC,TBD
PVCCMCP_CPU1             U2D1             AN22     SKX_EXT_B_BGA1-IC,TBD
PVCCMCP_CPU1             U2D1             AN24     SKX_EXT_B_BGA1-IC,TBD
PVCCMCP_CPU1             U2D1             AN26     SKX_EXT_B_BGA1-IC,TBD
PVCCMCP_CPU1             U2D1             AP23     SKX_EXT_B_BGA1-IC,TBD
PVCCMCP_CPU1             U2D1             AP25     SKX_EXT_B_BGA1-IC,TBD
PVCCMCP_CPU1             U2D1             AR20     SKX_EXT_B_BGA1-IC,TBD
PVCCMCP_CPU1             U2D1             AR22     SKX_EXT_B_BGA1-IC,TBD
PVCCMCP_CPU1             U2D1             AR26     SKX_EXT_B_BGA1-IC,TBD
PVCCMCP_CPU1             U2D1             AT23     SKX_EXT_B_BGA1-IC,TBD
PVCCMCP_CPU1             U2D1             AT25     SKX_EXT_B_BGA1-IC,TBD
PVCCMCP_CPU1             U2D1             BD13     SKX_EXT_B_BGA1-IC,TBD
PVCCMCP_CPU1             U2D1             BE12     SKX_EXT_B_BGA1-IC,TBD
PVCCMCP_CPU1             U2D1             BE14     SKX_EXT_B_BGA1-IC,TBD
PVCCMCP_CPU1             U2D1             BF11     SKX_EXT_B_BGA1-IC,TBD
PVCCMCP_CPU1             U2D1             BF13     SKX_EXT_B_BGA1-IC,TBD
PVCCMCP_CPU1             U2D1             BG12     SKX_EXT_B_BGA1-IC,TBD
PVCCMCP_CPU1             U2D1             BG14     SKX_EXT_B_BGA1-IC,TBD
PVCCMCP_CPU1             U2D1             BH13     SKX_EXT_B_BGA1-IC,TBD
PVCCMCP_CPU1             U2D1             BH19     SKX_EXT_B_BGA1-IC,TBD
PVCCMCP_CPU1             U2D1             BJ12     SKX_EXT_B_BGA1-IC,TBD
PVCCMCP_CPU1             U2D1             BJ14     SKX_EXT_B_BGA1-IC,TBD
PVCCMCP_CPU1             U2D1             BJ16     SKX_EXT_B_BGA1-IC,TBD
PVCCMCP_CPU1             U2D1             BJ18     SKX_EXT_B_BGA1-IC,TBD
PVCCMCP_CPU1             U2D1             BJ20     SKX_EXT_B_BGA1-IC,TBD
PVCCMCP_CPU1             U2D1             BK13     SKX_EXT_B_BGA1-IC,TBD
PVCCMCP_CPU1             U2D1             BK15     SKX_EXT_B_BGA1-IC,TBD
PVCCMCP_CPU1             U2D1             BK17     SKX_EXT_B_BGA1-IC,TBD
PVCCMCP_CPU1             U2D1             BL14     SKX_EXT_B_BGA1-IC,TBD
PVCCMCP_CPU1             U2D1             BL18     SKX_EXT_B_BGA1-IC,TBD
PVCCMCP_CPU1             U2D1             BL20     SKX_EXT_B_BGA1-IC,TBD
PVCCMCP_CPU1             U2D1             BM17     SKX_EXT_B_BGA1-IC,TBD
PVCCMCP_CPU1             U2D1             BM19     SKX_EXT_B_BGA1-IC,TBD
PVCCMCP_CPU1             U2D1             BN18     SKX_EXT_B_BGA1-IC,TBD
PVCCMCP_CPU1             U2D1             BP17     SKX_EXT_B_BGA1-IC,TBD
PVCCMCP_CPU1             U2D1             BP21     SKX_EXT_B_BGA1-IC,TBD
PVCCMCP_CPU1             U2D1             BR22     SKX_EXT_B_BGA1-IC,TBD
PVCCMCP_CPU1             U2D1             BR24     SKX_EXT_B_BGA1-IC,TBD
PVCCMCP_CPU1             U2D1             BU18     SKX_EXT_B_BGA1-IC,TBD
PVCCMCP_CPU1             U2D1             BU20     SKX_EXT_B_BGA1-IC,TBD
PVCCMCP_CPU1             U2D1             BU22     SKX_EXT_B_BGA1-IC,TBD
PVCCMCP_CPU1             U2D1             BV19     SKX_EXT_B_BGA1-IC,TBD
PVCCMCP_CPU1             U2D1             BV21     SKX_EXT_B_BGA1-IC,TBD
PVCCMCP_CPU1             U2D1             BW20     SKX_EXT_B_BGA1-IC,TBD
PVCCMCP_CPU1             U2D1             BY19     SKX_EXT_B_BGA1-IC,TBD
PVCCMCP_CPU1             U2D1             CA22     SKX_EXT_B_BGA1-IC,TBD
PVCCMCP_CPU1             U2D1             CB19     SKX_EXT_B_BGA1-IC,TBD
PVCCMCP_CPU1             U2D1             CB21     SKX_EXT_B_BGA1-IC,TBD
PVCCMCP_CPU1             U2D1             CC20     SKX_EXT_B_BGA1-IC,TBD
PVCCMCP_CPU1             U2D1             CD19     SKX_EXT_B_BGA1-IC,TBD
PVCCMCP_CPU1             U2D1             CD21     SKX_EXT_B_BGA1-IC,TBD
PVCCMCP_CPU1             U2D1             CE22     SKX_EXT_B_BGA1-IC,TBD
PVCCMCP_CPU1             U2D1             CF19     SKX_EXT_B_BGA1-IC,TBD
PVCCMCP_CPU1             U2D1             CF21     SKX_EXT_B_BGA1-IC,TBD
PVCCMCP_CPU1             U2D1             CF23     SKX_EXT_B_BGA1-IC,TBD
PVCCMCP_CPU1             U2D1             CG20     SKX_EXT_B_BGA1-IC,TBD
PVCCMCP_CPU1             U2D1             CG26     SKX_EXT_B_BGA1-IC,TBD
PVCCMCP_CPU1             U2D1             CH21     SKX_EXT_B_BGA1-IC,TBD
PVCCMCP_CPU1             U2D1             CH23     SKX_EXT_B_BGA1-IC,TBD
PVCCMCP_CPU1             U2D1             CJ20     SKX_EXT_B_BGA1-IC,TBD
PVCCMCP_CPU1             U2D1             CJ22     SKX_EXT_B_BGA1-IC,TBD
PVCCMCP_CPU1             U2D1             CJ24     SKX_EXT_B_BGA1-IC,TBD
PVCCMCP_CPU1             U2D1             CJ26     SKX_EXT_B_BGA1-IC,TBD
PVCCMCP_CPU1             U2D1             CK23     SKX_EXT_B_BGA1-IC,TBD
PVCCMCP_CPU1             U2D1             CK25     SKX_EXT_B_BGA1-IC,TBD
PVCCMCP_CPU1             U2D1             CL24     SKX_EXT_B_BGA1-IC,TBD
PVCCMCP_CPU1             U2D1             CL26     SKX_EXT_B_BGA1-IC,TBD
PVCCMCP_CPU1             U2D1             CM23     SKX_EXT_B_BGA1-IC,TBD
PVCCMCP_CPU1             U2D1             CM25     SKX_EXT_B_BGA1-IC,TBD
PVCCMCP_CPU1             U2D1             CN24     SKX_EXT_B_BGA1-IC,TBD
PVCCMCP_CPU1             U2D1             CP23     SKX_EXT_B_BGA1-IC,TBD
PVCCMCP_CPU1             U2D1             CT23     SKX_EXT_B_BGA1-IC,TBD
PVCCMCP_CPU1             U2D1             CU24     SKX_EXT_B_BGA1-IC,TBD
PVCCMCP_CPU1             U2D1             CV23     SKX_EXT_B_BGA1-IC,TBD
PVCCMCP_CPU1             U2D1             CW24     SKX_EXT_B_BGA1-IC,TBD
PVCCMCP_CPU1             U2D1             CY25     SKX_EXT_B_BGA1-IC,TBD
PVCCMCP_CPU1             U2D1             DA24     SKX_EXT_B_BGA1-IC,TBD
PVDDQ_ABC                C3U1             1        CAPP_3018-470UF,2.5V,20%,ALUM,A
PVDDQ_ABC                C3U5             1        CAPP_3018-470UF,2.5V,20%,ALUM,A
PVDDQ_ABC                C3U8             1        CAPP_3018-470UF,2.5V,20%,ALUM,A
PVDDQ_ABC                C4T4             1        CAP_0805-100UF,4V,20%,X5R,6024A
PVDDQ_ABC                C5D54            1        CAP_0603LF-10UF,4V,20%,X6S,E15A
PVDDQ_ABC                C5D55            1        CAP_0603LF-10UF,4V,20%,X6S,E15A
PVDDQ_ABC                C5D56            1        CAP_0603LF-10UF,4V,20%,X6S,E15A
PVDDQ_ABC                C5D57            1        CAP_0603LF-10UF,4V,20%,X6S,E15A
PVDDQ_ABC                C5F1             1        CAP_A_0603V-47UF,4V,20%,X5R,60A
PVDDQ_ABC                C5F2             1        CAP_A_0603V-47UF,4V,20%,X5R,60A
PVDDQ_ABC                C5G1             1        CAP_A_0603V-22.0UF,4V,20%,X6S,A
PVDDQ_ABC                C5G2             1        CAP_A_0603V-22.0UF,4V,20%,X6S,A
PVDDQ_ABC                C5G3             1        CAP_A_0603V-22.0UF,4V,20%,X6S,A
PVDDQ_ABC                C5G4             1        CAP_A_0603V-22.0UF,4V,20%,X6S,A
PVDDQ_ABC                C5G5             1        CAP_A_0603V-22.0UF,4V,20%,X6S,A
PVDDQ_ABC                C5G6             1        CAP_A_0603V-22.0UF,4V,20%,X6S,A
PVDDQ_ABC                C5G7             1        CAP_A_0603V-22.0UF,4V,20%,X6S,A
PVDDQ_ABC                C5G8             1        CAP_A_0603V-22.0UF,4V,20%,X6S,A
PVDDQ_ABC                C5G9             1        CAP_0805-100UF,4V,20%,X5R,6024A
PVDDQ_ABC                C5G10            1        CAP_A_0603V-47UF,4V,20%,X5R,60A
PVDDQ_ABC                C5G11            1        CAP_A_0603V-22.0UF,4V,20%,X6S,A
PVDDQ_ABC                C5G12            1        CAP_A_0603V-22.0UF,4V,20%,X6S,A
PVDDQ_ABC                C5G13            1        CAP_A_0603V-22.0UF,4V,20%,X6S,A
PVDDQ_ABC                C5G14            1        CAP_A_0603V-22.0UF,4V,20%,X6S,A
PVDDQ_ABC                C5G15            1        CAP_A_0603V-22.0UF,4V,20%,X6S,A
PVDDQ_ABC                C5G16            1        CAP_A_0603V-22.0UF,4V,20%,X6S,A
PVDDQ_ABC                C5G17            1        CAP_A_0603V-22.0UF,4V,20%,X6S,A
PVDDQ_ABC                C5G18            1        CAP_A_0603V-22.0UF,4V,20%,X6S,A
PVDDQ_ABC                C5G19            1        CAP_A_0603V-47UF,4V,20%,X5R,60A
PVDDQ_ABC                C5G20            1        CAP_0805-100UF,4V,20%,X5R,6024A
PVDDQ_ABC                C5G21            1        CAP_0805-100UF,4V,20%,X5R,6024A
PVDDQ_ABC                C5G22            1        CAP_0805-100UF,4V,20%,X5R,6024A
PVDDQ_ABC                C5G41            1        CAP_A_0603V-22.0UF,4V,20%,X6S,A
PVDDQ_ABC                C5G42            1        CAP_A_0603V-22.0UF,4V,20%,X6S,A
PVDDQ_ABC                C5G43            1        CAP_A_0603V-22.0UF,4V,20%,X6S,A
PVDDQ_ABC                C5G44            1        CAP_A_0603V-22.0UF,4V,20%,X6S,A
PVDDQ_ABC                C5G45            1        CAP_A_0603V-22.0UF,4V,20%,X6S,A
PVDDQ_ABC                C5G46            1        CAP_A_0603V-22.0UF,4V,20%,X6S,A
PVDDQ_ABC                C5G47            1        CAP_A_0603V-22.0UF,4V,20%,X6S,A
PVDDQ_ABC                C5G48            1        CAP_A_0603V-22.0UF,4V,20%,X6S,A
PVDDQ_ABC                C5G49            1        CAP_A_0603V-22.0UF,4V,20%,X6S,A
PVDDQ_ABC                C5G50            1        CAP_A_0603V-22.0UF,4V,20%,X6S,A
PVDDQ_ABC                C5G51            1        CAP_A_0603V-22.0UF,4V,20%,X6S,A
PVDDQ_ABC                C5G52            1        CAP_A_0603V-22.0UF,4V,20%,X6S,A
PVDDQ_ABC                C5G53            1        CAP_A_0603V-22.0UF,4V,20%,X6S,A
PVDDQ_ABC                C5G54            1        CAP_A_0603V-22.0UF,4V,20%,X6S,A
PVDDQ_ABC                C5G55            1        CAP_A_0603V-22.0UF,4V,20%,X6S,A
PVDDQ_ABC                C5G56            1        CAP_A_0603V-22.0UF,4V,20%,X6S,A
PVDDQ_ABC                C5G57            1        CAP_A_0603V-22.0UF,4V,20%,X6S,A
PVDDQ_ABC                C5G58            1        CAP_A_0603V-22.0UF,4V,20%,X6S,A
PVDDQ_ABC                C5P38            1        CAP_0805LF-22UF,4V,20%,X6S,C95A
PVDDQ_ABC                C5P39            1        CAP_0805LF-22UF,4V,20%,X6S,C95A
PVDDQ_ABC                C5T1             1        CAP_A_0603V-47UF,4V,20%,X5R,60A
PVDDQ_ABC                C5T2             1        CAP_A_0603V-47UF,4V,20%,X5R,60A
PVDDQ_ABC                C5T4             1        CAP_A_0603V-47UF,4V,20%,X5R,60A
PVDDQ_ABC                C5T5             1        CAP_A_0603V-22.0UF,4V,20%,X6S,A
PVDDQ_ABC                C5T6             1        CAP_A_0603V-22.0UF,4V,20%,X6S,A
PVDDQ_ABC                C5T7             1        CAP_A_0603V-22.0UF,4V,20%,X6S,A
PVDDQ_ABC                C5T8             1        CAP_A_0603V-22.0UF,4V,20%,X6S,A
PVDDQ_ABC                C5T9             1        CAP_A_0603V-22.0UF,4V,20%,X6S,A
PVDDQ_ABC                C5T10            1        CAP_A_0603V-22.0UF,4V,20%,X6S,A
PVDDQ_ABC                C5T11            1        CAP_A_0603V-22.0UF,4V,20%,X6S,A
PVDDQ_ABC                C5T12            1        CAP_A_0603V-22.0UF,4V,20%,X6S,A
PVDDQ_ABC                C5T13            1        CAP_A_0603V-47UF,4V,20%,X5R,60A
PVDDQ_ABC                C5U1             1        CAP_0805-100UF,4V,20%,X5R,6024A
PVDDQ_ABC                C5U2             1        CAP_A_0603V-22.0UF,4V,20%,X6S,A
PVDDQ_ABC                C5U3             1        CAP_A_0603V-22.0UF,4V,20%,X6S,A
PVDDQ_ABC                C5U4             1        CAP_A_0603V-22.0UF,4V,20%,X6S,A
PVDDQ_ABC                C5U5             1        CAP_A_0603V-22.0UF,4V,20%,X6S,A
PVDDQ_ABC                C5U6             1        CAP_A_0603V-22.0UF,4V,20%,X6S,A
PVDDQ_ABC                C5U7             1        CAP_A_0603V-22.0UF,4V,20%,X6S,A
PVDDQ_ABC                C5U8             1        CAP_A_0603V-22.0UF,4V,20%,X6S,A
PVDDQ_ABC                C5U9             1        CAP_A_0603V-22.0UF,4V,20%,X6S,A
PVDDQ_ABC                C5U10            1        CAP_0805-100UF,4V,20%,X5R,6024A
PVDDQ_ABC                C5U11            1        CAP_A_0603V-47UF,4V,20%,X5R,60A
PVDDQ_ABC                C5U13            1        CAP_0805-100UF,4V,20%,X5R,6024A
PVDDQ_ABC                C5U14            1        CAP_0805-100UF,4V,20%,X5R,6024A
PVDDQ_ABC                C5U15            1        CAP_0805-100UF,4V,20%,X5R,6024A
PVDDQ_ABC                C6G3             1        CAP_0805LF-22UF,4V,20%,X6S,C95A
PVDDQ_ABC                C6U15            1        CAP_0603LF-10UF,4V,20%,X6S,E15A
PVDDQ_ABC                C6U16            1        CAP_0603LF-10UF,4V,20%,X6S,E15A
PVDDQ_ABC                C7G27            1        CAP_0805LF-22UF,4V,20%,X6S,C95A
PVDDQ_ABC                C7G28            1        CAPP_3018-470UF,2.5V,20%,ALUM,A
PVDDQ_ABC                EU4G3            10       MIC5166_DFN-IC,H55101-001
PVDDQ_ABC                EU7G2            1        IR354XX_SM-IR35411,IC,H73688-0A
PVDDQ_ABC                EU7G3            1        IR354XX_SM-IR35411,IC,H73688-0A
PVDDQ_ABC                J4G1             59       SCONN288_H44441004_PIP-SCONN,HA
PVDDQ_ABC                J4G1             61       SCONN288_H44441004_PIP-SCONN,HA
PVDDQ_ABC                J4G1             64       SCONN288_H44441004_PIP-SCONN,HA
PVDDQ_ABC                J4G1             67       SCONN288_H44441004_PIP-SCONN,HA
PVDDQ_ABC                J4G1             70       SCONN288_H44441004_PIP-SCONN,HA
PVDDQ_ABC                J4G1             73       SCONN288_H44441004_PIP-SCONN,HA
PVDDQ_ABC                J4G1             76       SCONN288_H44441004_PIP-SCONN,HA
PVDDQ_ABC                J4G1             80       SCONN288_H44441004_PIP-SCONN,HA
PVDDQ_ABC                J4G1             83       SCONN288_H44441004_PIP-SCONN,HA
PVDDQ_ABC                J4G1             85       SCONN288_H44441004_PIP-SCONN,HA
PVDDQ_ABC                J4G1             88       SCONN288_H44441004_PIP-SCONN,HA
PVDDQ_ABC                J4G1             90       SCONN288_H44441004_PIP-SCONN,HA
PVDDQ_ABC                J4G1             92       SCONN288_H44441004_PIP-SCONN,HA
PVDDQ_ABC                J4G1             204      SCONN288_H44441004_PIP-SCONN,HA
PVDDQ_ABC                J4G1             206      SCONN288_H44441004_PIP-SCONN,HA
PVDDQ_ABC                J4G1             209      SCONN288_H44441004_PIP-SCONN,HA
PVDDQ_ABC                J4G1             212      SCONN288_H44441004_PIP-SCONN,HA
PVDDQ_ABC                J4G1             215      SCONN288_H44441004_PIP-SCONN,HA
PVDDQ_ABC                J4G1             217      SCONN288_H44441004_PIP-SCONN,HA
PVDDQ_ABC                J4G1             220      SCONN288_H44441004_PIP-SCONN,HA
PVDDQ_ABC                J4G1             223      SCONN288_H44441004_PIP-SCONN,HA
PVDDQ_ABC                J4G1             226      SCONN288_H44441004_PIP-SCONN,HA
PVDDQ_ABC                J4G1             229      SCONN288_H44441004_PIP-SCONN,HA
PVDDQ_ABC                J4G1             231      SCONN288_H44441004_PIP-SCONN,HA
PVDDQ_ABC                J4G1             233      SCONN288_H44441004_PIP-SCONN,HA
PVDDQ_ABC                J4G1             236      SCONN288_H44441004_PIP-SCONN,HA
PVDDQ_ABC                J4G2             59       SCONN288_H44441004_PIP-SCONN,HA
PVDDQ_ABC                J4G2             61       SCONN288_H44441004_PIP-SCONN,HA
PVDDQ_ABC                J4G2             64       SCONN288_H44441004_PIP-SCONN,HA
PVDDQ_ABC                J4G2             67       SCONN288_H44441004_PIP-SCONN,HA
PVDDQ_ABC                J4G2             70       SCONN288_H44441004_PIP-SCONN,HA
PVDDQ_ABC                J4G2             73       SCONN288_H44441004_PIP-SCONN,HA
PVDDQ_ABC                J4G2             76       SCONN288_H44441004_PIP-SCONN,HA
PVDDQ_ABC                J4G2             80       SCONN288_H44441004_PIP-SCONN,HA
PVDDQ_ABC                J4G2             83       SCONN288_H44441004_PIP-SCONN,HA
PVDDQ_ABC                J4G2             85       SCONN288_H44441004_PIP-SCONN,HA
PVDDQ_ABC                J4G2             88       SCONN288_H44441004_PIP-SCONN,HA
PVDDQ_ABC                J4G2             90       SCONN288_H44441004_PIP-SCONN,HA
PVDDQ_ABC                J4G2             92       SCONN288_H44441004_PIP-SCONN,HA
PVDDQ_ABC                J4G2             204      SCONN288_H44441004_PIP-SCONN,HA
PVDDQ_ABC                J4G2             206      SCONN288_H44441004_PIP-SCONN,HA
PVDDQ_ABC                J4G2             209      SCONN288_H44441004_PIP-SCONN,HA
PVDDQ_ABC                J4G2             212      SCONN288_H44441004_PIP-SCONN,HA
PVDDQ_ABC                J4G2             215      SCONN288_H44441004_PIP-SCONN,HA
PVDDQ_ABC                J4G2             217      SCONN288_H44441004_PIP-SCONN,HA
PVDDQ_ABC                J4G2             220      SCONN288_H44441004_PIP-SCONN,HA
PVDDQ_ABC                J4G2             223      SCONN288_H44441004_PIP-SCONN,HA
PVDDQ_ABC                J4G2             226      SCONN288_H44441004_PIP-SCONN,HA
PVDDQ_ABC                J4G2             229      SCONN288_H44441004_PIP-SCONN,HA
PVDDQ_ABC                J4G2             231      SCONN288_H44441004_PIP-SCONN,HA
PVDDQ_ABC                J4G2             233      SCONN288_H44441004_PIP-SCONN,HA
PVDDQ_ABC                J4G2             236      SCONN288_H44441004_PIP-SCONN,HA
PVDDQ_ABC                J4G3             59       SCONN288_H44441004_PIP-SCONN,HA
PVDDQ_ABC                J4G3             61       SCONN288_H44441004_PIP-SCONN,HA
PVDDQ_ABC                J4G3             64       SCONN288_H44441004_PIP-SCONN,HA
PVDDQ_ABC                J4G3             67       SCONN288_H44441004_PIP-SCONN,HA
PVDDQ_ABC                J4G3             70       SCONN288_H44441004_PIP-SCONN,HA
PVDDQ_ABC                J4G3             73       SCONN288_H44441004_PIP-SCONN,HA
PVDDQ_ABC                J4G3             76       SCONN288_H44441004_PIP-SCONN,HA
PVDDQ_ABC                J4G3             80       SCONN288_H44441004_PIP-SCONN,HA
PVDDQ_ABC                J4G3             83       SCONN288_H44441004_PIP-SCONN,HA
PVDDQ_ABC                J4G3             85       SCONN288_H44441004_PIP-SCONN,HA
PVDDQ_ABC                J4G3             88       SCONN288_H44441004_PIP-SCONN,HA
PVDDQ_ABC                J4G3             90       SCONN288_H44441004_PIP-SCONN,HA
PVDDQ_ABC                J4G3             92       SCONN288_H44441004_PIP-SCONN,HA
PVDDQ_ABC                J4G3             204      SCONN288_H44441004_PIP-SCONN,HA
PVDDQ_ABC                J4G3             206      SCONN288_H44441004_PIP-SCONN,HA
PVDDQ_ABC                J4G3             209      SCONN288_H44441004_PIP-SCONN,HA
PVDDQ_ABC                J4G3             212      SCONN288_H44441004_PIP-SCONN,HA
PVDDQ_ABC                J4G3             215      SCONN288_H44441004_PIP-SCONN,HA
PVDDQ_ABC                J4G3             217      SCONN288_H44441004_PIP-SCONN,HA
PVDDQ_ABC                J4G3             220      SCONN288_H44441004_PIP-SCONN,HA
PVDDQ_ABC                J4G3             223      SCONN288_H44441004_PIP-SCONN,HA
PVDDQ_ABC                J4G3             226      SCONN288_H44441004_PIP-SCONN,HA
PVDDQ_ABC                J4G3             229      SCONN288_H44441004_PIP-SCONN,HA
PVDDQ_ABC                J4G3             231      SCONN288_H44441004_PIP-SCONN,HA
PVDDQ_ABC                J4G3             233      SCONN288_H44441004_PIP-SCONN,HA
PVDDQ_ABC                J4G3             236      SCONN288_H44441004_PIP-SCONN,HA
PVDDQ_ABC                J6T1             59       SCONN288_H44441003_PIP-SCONN,HA
PVDDQ_ABC                J6T1             61       SCONN288_H44441003_PIP-SCONN,HA
PVDDQ_ABC                J6T1             64       SCONN288_H44441003_PIP-SCONN,HA
PVDDQ_ABC                J6T1             67       SCONN288_H44441003_PIP-SCONN,HA
PVDDQ_ABC                J6T1             70       SCONN288_H44441003_PIP-SCONN,HA
PVDDQ_ABC                J6T1             73       SCONN288_H44441003_PIP-SCONN,HA
PVDDQ_ABC                J6T1             76       SCONN288_H44441003_PIP-SCONN,HA
PVDDQ_ABC                J6T1             80       SCONN288_H44441003_PIP-SCONN,HA
PVDDQ_ABC                J6T1             83       SCONN288_H44441003_PIP-SCONN,HA
PVDDQ_ABC                J6T1             85       SCONN288_H44441003_PIP-SCONN,HA
PVDDQ_ABC                J6T1             88       SCONN288_H44441003_PIP-SCONN,HA
PVDDQ_ABC                J6T1             90       SCONN288_H44441003_PIP-SCONN,HA
PVDDQ_ABC                J6T1             92       SCONN288_H44441003_PIP-SCONN,HA
PVDDQ_ABC                J6T1             204      SCONN288_H44441003_PIP-SCONN,HA
PVDDQ_ABC                J6T1             206      SCONN288_H44441003_PIP-SCONN,HA
PVDDQ_ABC                J6T1             209      SCONN288_H44441003_PIP-SCONN,HA
PVDDQ_ABC                J6T1             212      SCONN288_H44441003_PIP-SCONN,HA
PVDDQ_ABC                J6T1             215      SCONN288_H44441003_PIP-SCONN,HA
PVDDQ_ABC                J6T1             217      SCONN288_H44441003_PIP-SCONN,HA
PVDDQ_ABC                J6T1             220      SCONN288_H44441003_PIP-SCONN,HA
PVDDQ_ABC                J6T1             223      SCONN288_H44441003_PIP-SCONN,HA
PVDDQ_ABC                J6T1             226      SCONN288_H44441003_PIP-SCONN,HA
PVDDQ_ABC                J6T1             229      SCONN288_H44441003_PIP-SCONN,HA
PVDDQ_ABC                J6T1             231      SCONN288_H44441003_PIP-SCONN,HA
PVDDQ_ABC                J6T1             233      SCONN288_H44441003_PIP-SCONN,HA
PVDDQ_ABC                J6T1             236      SCONN288_H44441003_PIP-SCONN,HA
PVDDQ_ABC                J6U1             59       SCONN288_H44441003_PIP-SCONN,HA
PVDDQ_ABC                J6U1             61       SCONN288_H44441003_PIP-SCONN,HA
PVDDQ_ABC                J6U1             64       SCONN288_H44441003_PIP-SCONN,HA
PVDDQ_ABC                J6U1             67       SCONN288_H44441003_PIP-SCONN,HA
PVDDQ_ABC                J6U1             70       SCONN288_H44441003_PIP-SCONN,HA
PVDDQ_ABC                J6U1             73       SCONN288_H44441003_PIP-SCONN,HA
PVDDQ_ABC                J6U1             76       SCONN288_H44441003_PIP-SCONN,HA
PVDDQ_ABC                J6U1             80       SCONN288_H44441003_PIP-SCONN,HA
PVDDQ_ABC                J6U1             83       SCONN288_H44441003_PIP-SCONN,HA
PVDDQ_ABC                J6U1             85       SCONN288_H44441003_PIP-SCONN,HA
PVDDQ_ABC                J6U1             88       SCONN288_H44441003_PIP-SCONN,HA
PVDDQ_ABC                J6U1             90       SCONN288_H44441003_PIP-SCONN,HA
PVDDQ_ABC                J6U1             92       SCONN288_H44441003_PIP-SCONN,HA
PVDDQ_ABC                J6U1             204      SCONN288_H44441003_PIP-SCONN,HA
PVDDQ_ABC                J6U1             206      SCONN288_H44441003_PIP-SCONN,HA
PVDDQ_ABC                J6U1             209      SCONN288_H44441003_PIP-SCONN,HA
PVDDQ_ABC                J6U1             212      SCONN288_H44441003_PIP-SCONN,HA
PVDDQ_ABC                J6U1             215      SCONN288_H44441003_PIP-SCONN,HA
PVDDQ_ABC                J6U1             217      SCONN288_H44441003_PIP-SCONN,HA
PVDDQ_ABC                J6U1             220      SCONN288_H44441003_PIP-SCONN,HA
PVDDQ_ABC                J6U1             223      SCONN288_H44441003_PIP-SCONN,HA
PVDDQ_ABC                J6U1             226      SCONN288_H44441003_PIP-SCONN,HA
PVDDQ_ABC                J6U1             229      SCONN288_H44441003_PIP-SCONN,HA
PVDDQ_ABC                J6U1             231      SCONN288_H44441003_PIP-SCONN,HA
PVDDQ_ABC                J6U1             233      SCONN288_H44441003_PIP-SCONN,HA
PVDDQ_ABC                J6U1             236      SCONN288_H44441003_PIP-SCONN,HA
PVDDQ_ABC                J6U2             59       SCONN288_H44441003_PIP-SCONN,HA
PVDDQ_ABC                J6U2             61       SCONN288_H44441003_PIP-SCONN,HA
PVDDQ_ABC                J6U2             64       SCONN288_H44441003_PIP-SCONN,HA
PVDDQ_ABC                J6U2             67       SCONN288_H44441003_PIP-SCONN,HA
PVDDQ_ABC                J6U2             70       SCONN288_H44441003_PIP-SCONN,HA
PVDDQ_ABC                J6U2             73       SCONN288_H44441003_PIP-SCONN,HA
PVDDQ_ABC                J6U2             76       SCONN288_H44441003_PIP-SCONN,HA
PVDDQ_ABC                J6U2             80       SCONN288_H44441003_PIP-SCONN,HA
PVDDQ_ABC                J6U2             83       SCONN288_H44441003_PIP-SCONN,HA
PVDDQ_ABC                J6U2             85       SCONN288_H44441003_PIP-SCONN,HA
PVDDQ_ABC                J6U2             88       SCONN288_H44441003_PIP-SCONN,HA
PVDDQ_ABC                J6U2             90       SCONN288_H44441003_PIP-SCONN,HA
PVDDQ_ABC                J6U2             92       SCONN288_H44441003_PIP-SCONN,HA
PVDDQ_ABC                J6U2             204      SCONN288_H44441003_PIP-SCONN,HA
PVDDQ_ABC                J6U2             206      SCONN288_H44441003_PIP-SCONN,HA
PVDDQ_ABC                J6U2             209      SCONN288_H44441003_PIP-SCONN,HA
PVDDQ_ABC                J6U2             212      SCONN288_H44441003_PIP-SCONN,HA
PVDDQ_ABC                J6U2             215      SCONN288_H44441003_PIP-SCONN,HA
PVDDQ_ABC                J6U2             217      SCONN288_H44441003_PIP-SCONN,HA
PVDDQ_ABC                J6U2             220      SCONN288_H44441003_PIP-SCONN,HA
PVDDQ_ABC                J6U2             223      SCONN288_H44441003_PIP-SCONN,HA
PVDDQ_ABC                J6U2             226      SCONN288_H44441003_PIP-SCONN,HA
PVDDQ_ABC                J6U2             229      SCONN288_H44441003_PIP-SCONN,HA
PVDDQ_ABC                J6U2             231      SCONN288_H44441003_PIP-SCONN,HA
PVDDQ_ABC                J6U2             233      SCONN288_H44441003_PIP-SCONN,HA
PVDDQ_ABC                J6U2             236      SCONN288_H44441003_PIP-SCONN,HA
PVDDQ_ABC                L7G1             2        INDUCTOR_SM-0.12UH,IND,D92183-A
PVDDQ_ABC                L7G2             2        INDUCTOR_SM-0.12UH,IND,D92183-A
PVDDQ_ABC                R3P38            1        RES_0402-64.9,1.0%,1/16W,CHIP,A
PVDDQ_ABC                R3U4             1        RES_0603-120.0,1%,1/10W,CHIP,GA
PVDDQ_ABC                R4F4             1        RES_0402-1.00K,1%,1/16W,CHIP,GA
PVDDQ_ABC                R4G2             1        RES_0402-1.00K,1%,1/16W,CHIP,GA
PVDDQ_ABC                R4G21            1        RES_0402-1.00K,1%,1/16W,CHIP,GA
PVDDQ_ABC                R6U5             1        RES_0402-0.0,5%,1/16W,CHIP,G21A
PVDDQ_ABC                SH4U2            2        SHUNT_SH0201-EMPTY,N_A
PVDDQ_ABC                U5D1             AD45     SKX_EXT_B_BGA1-IC,TBD
PVDDQ_ABC                U5D1             AF55     SKX_EXT_B_BGA1-IC,TBD
PVDDQ_ABC                U5D1             AF57     SKX_EXT_B_BGA1-IC,TBD
PVDDQ_ABC                U5D1             AF59     SKX_EXT_B_BGA1-IC,TBD
PVDDQ_ABC                U5D1             AF61     SKX_EXT_B_BGA1-IC,TBD
PVDDQ_ABC                U5D1             AF63     SKX_EXT_B_BGA1-IC,TBD
PVDDQ_ABC                U5D1             B47      SKX_EXT_B_BGA1-IC,TBD
PVDDQ_ABC                U5D1             B49      SKX_EXT_B_BGA1-IC,TBD
PVDDQ_ABC                U5D1             B53      SKX_EXT_B_BGA1-IC,TBD
PVDDQ_ABC                U5D1             B59      SKX_EXT_B_BGA1-IC,TBD
PVDDQ_ABC                U5D1             C46      SKX_EXT_B_BGA1-IC,TBD
PVDDQ_ABC                U5D1             D45      SKX_EXT_B_BGA1-IC,TBD
PVDDQ_ABC                U5D1             E46      SKX_EXT_B_BGA1-IC,TBD
PVDDQ_ABC                U5D1             E48      SKX_EXT_B_BGA1-IC,TBD
PVDDQ_ABC                U5D1             E50      SKX_EXT_B_BGA1-IC,TBD
PVDDQ_ABC                U5D1             E52      SKX_EXT_B_BGA1-IC,TBD
PVDDQ_ABC                U5D1             E54      SKX_EXT_B_BGA1-IC,TBD
PVDDQ_ABC                U5D1             E56      SKX_EXT_B_BGA1-IC,TBD
PVDDQ_ABC                U5D1             E58      SKX_EXT_B_BGA1-IC,TBD
PVDDQ_ABC                U5D1             E60      SKX_EXT_B_BGA1-IC,TBD
PVDDQ_ABC                U5D1             E62      SKX_EXT_B_BGA1-IC,TBD
PVDDQ_ABC                U5D1             E64      SKX_EXT_B_BGA1-IC,TBD
PVDDQ_ABC                U5D1             L46      SKX_EXT_B_BGA1-IC,TBD
PVDDQ_ABC                U5D1             L48      SKX_EXT_B_BGA1-IC,TBD
PVDDQ_ABC                U5D1             L50      SKX_EXT_B_BGA1-IC,TBD
PVDDQ_ABC                U5D1             L52      SKX_EXT_B_BGA1-IC,TBD
PVDDQ_ABC                U5D1             L54      SKX_EXT_B_BGA1-IC,TBD
PVDDQ_ABC                U5D1             L56      SKX_EXT_B_BGA1-IC,TBD
PVDDQ_ABC                U5D1             L58      SKX_EXT_B_BGA1-IC,TBD
PVDDQ_ABC                U5D1             L60      SKX_EXT_B_BGA1-IC,TBD
PVDDQ_ABC                U5D1             L62      SKX_EXT_B_BGA1-IC,TBD
PVDDQ_ABC                U5D1             N64      SKX_EXT_B_BGA1-IC,TBD
PVDDQ_ABC                U5D1             U46      SKX_EXT_B_BGA1-IC,TBD
PVDDQ_ABC                U5D1             U48      SKX_EXT_B_BGA1-IC,TBD
PVDDQ_ABC                U5D1             U50      SKX_EXT_B_BGA1-IC,TBD
PVDDQ_ABC                U5D1             U52      SKX_EXT_B_BGA1-IC,TBD
PVDDQ_ABC                U5D1             U54      SKX_EXT_B_BGA1-IC,TBD
PVDDQ_ABC                U5D1             U56      SKX_EXT_B_BGA1-IC,TBD
PVDDQ_ABC                U5D1             U58      SKX_EXT_B_BGA1-IC,TBD
PVDDQ_ABC                U5D1             U60      SKX_EXT_B_BGA1-IC,TBD
PVDDQ_ABC                U5D1             U62      SKX_EXT_B_BGA1-IC,TBD
PVDDQ_ABC                U5D1             W64      SKX_EXT_B_BGA1-IC,TBD
PVDDQ_ABC                U5D1             Y45      SKX_EXT_B_BGA1-IC,TBD
PVDDQ_ABC                U5D1             Y47      SKX_EXT_B_BGA1-IC,TBD
PVDDQ_ABC                U5D1             Y49      SKX_EXT_B_BGA1-IC,TBD
PVDDQ_ABC                U5D1             Y51      SKX_EXT_B_BGA1-IC,TBD
PVDDQ_ABC                U5D1             Y53      SKX_EXT_B_BGA1-IC,TBD
PVDDQ_ABC                U5D1             Y55      SKX_EXT_B_BGA1-IC,TBD
PVDDQ_ABC                U5D1             Y57      SKX_EXT_B_BGA1-IC,TBD
PVDDQ_ABC                U5D1             Y59      SKX_EXT_B_BGA1-IC,TBD
PVDDQ_ABC                U5D1             Y61      SKX_EXT_B_BGA1-IC,TBD
PVDDQ_ABC                U5D1             Y63      SKX_EXT_B_BGA1-IC,TBD
PVDDQ_DEF                C3L6             1        CAPP_3018-470UF,2.5V,20%,ALUM,A
PVDDQ_DEF                C3L14            1        CAPP_3018-470UF,2.5V,20%,ALUM,A
PVDDQ_DEF                C4L5             1        CAPP_3018-470UF,2.5V,20%,ALUM,A
PVDDQ_DEF                C4M2             1        CAP_A_0603V-22.0UF,4V,20%,X6S,A
PVDDQ_DEF                C4M5             1        CAP_A_0603V-47UF,4V,20%,X5R,60A
PVDDQ_DEF                C5A1             1        CAP_A_0603V-22.0UF,4V,20%,X6S,A
PVDDQ_DEF                C5A2             1        CAP_A_0603V-22.0UF,4V,20%,X6S,A
PVDDQ_DEF                C5A3             1        CAP_A_0603V-22.0UF,4V,20%,X6S,A
PVDDQ_DEF                C5A4             1        CAP_A_0603V-22.0UF,4V,20%,X6S,A
PVDDQ_DEF                C5A5             1        CAP_A_0603V-47UF,4V,20%,X5R,60A
PVDDQ_DEF                C5A6             1        CAP_A_0603V-22.0UF,4V,20%,X6S,A
PVDDQ_DEF                C5A7             1        CAP_A_0603V-22.0UF,4V,20%,X6S,A
PVDDQ_DEF                C5A8             1        CAP_A_0603V-22.0UF,4V,20%,X6S,A
PVDDQ_DEF                C5A9             1        CAP_A_0603V-22.0UF,4V,20%,X6S,A
PVDDQ_DEF                C5A10            1        CAP_0805-100UF,4V,20%,X5R,6024A
PVDDQ_DEF                C5A11            1        CAP_A_0603V-22.0UF,4V,20%,X6S,A
PVDDQ_DEF                C5A12            1        CAP_A_0603V-22.0UF,4V,20%,X6S,A
PVDDQ_DEF                C5A13            1        CAP_A_0603V-22.0UF,4V,20%,X6S,A
PVDDQ_DEF                C5A14            1        CAP_A_0603V-22.0UF,4V,20%,X6S,A
PVDDQ_DEF                C5A15            1        CAP_A_0603V-22.0UF,4V,20%,X6S,A
PVDDQ_DEF                C5A16            1        CAP_A_0603V-22.0UF,4V,20%,X6S,A
PVDDQ_DEF                C5A17            1        CAP_A_0603V-22.0UF,4V,20%,X6S,A
PVDDQ_DEF                C5A18            1        CAP_A_0603V-22.0UF,4V,20%,X6S,A
PVDDQ_DEF                C5A19            1        CAP_A_0603V-22.0UF,4V,20%,X6S,A
PVDDQ_DEF                C5A20            1        CAP_0805-100UF,4V,20%,X5R,6024A
PVDDQ_DEF                C5B1             1        CAP_A_0603V-47UF,4V,20%,X5R,60A
PVDDQ_DEF                C5B2             1        CAP_A_0603V-47UF,4V,20%,X5R,60A
PVDDQ_DEF                C5D6             1        CAP_0603LF-10UF,4V,20%,X6S,E15A
PVDDQ_DEF                C5D7             1        CAP_0603LF-10UF,4V,20%,X6S,E15A
PVDDQ_DEF                C5D8             1        CAP_0603LF-10UF,4V,20%,X6S,E15A
PVDDQ_DEF                C5D9             1        CAP_0603LF-10UF,4V,20%,X6S,E15A
PVDDQ_DEF                C5G59            1        CAP_A_0603V-22.0UF,4V,20%,X6S,A
PVDDQ_DEF                C5G60            1        CAP_A_0603V-22.0UF,4V,20%,X6S,A
PVDDQ_DEF                C5G61            1        CAP_A_0603V-22.0UF,4V,20%,X6S,A
PVDDQ_DEF                C5G62            1        CAP_A_0603V-22.0UF,4V,20%,X6S,A
PVDDQ_DEF                C5G63            1        CAP_A_0603V-22.0UF,4V,20%,X6S,A
PVDDQ_DEF                C5G64            1        CAP_A_0603V-22.0UF,4V,20%,X6S,A
PVDDQ_DEF                C5G65            1        CAP_A_0603V-22.0UF,4V,20%,X6S,A
PVDDQ_DEF                C5G66            1        CAP_A_0603V-22.0UF,4V,20%,X6S,A
PVDDQ_DEF                C5G67            1        CAP_A_0603V-22.0UF,4V,20%,X6S,A
PVDDQ_DEF                C5G68            1        CAP_A_0603V-22.0UF,4V,20%,X6S,A
PVDDQ_DEF                C5G69            1        CAP_A_0603V-22.0UF,4V,20%,X6S,A
PVDDQ_DEF                C5G70            1        CAP_A_0603V-22.0UF,4V,20%,X6S,A
PVDDQ_DEF                C5G71            1        CAP_A_0603V-22.0UF,4V,20%,X6S,A
PVDDQ_DEF                C5G72            1        CAP_A_0603V-22.0UF,4V,20%,X6S,A
PVDDQ_DEF                C5G73            1        CAP_A_0603V-22.0UF,4V,20%,X6S,A
PVDDQ_DEF                C5G74            1        CAP_A_0603V-22.0UF,4V,20%,X6S,A
PVDDQ_DEF                C5G75            1        CAP_A_0603V-22.0UF,4V,20%,X6S,A
PVDDQ_DEF                C5G76            1        CAP_A_0603V-22.0UF,4V,20%,X6S,A
PVDDQ_DEF                C5G77            1        CAP_0805-100UF,4V,20%,X5R,6024A
PVDDQ_DEF                C5G78            1        CAP_0805-100UF,4V,20%,X5R,6024A
PVDDQ_DEF                C5L1             1        CAP_0805-100UF,4V,20%,X5R,6024A
PVDDQ_DEF                C5L2             1        CAP_0805-100UF,4V,20%,X5R,6024A
PVDDQ_DEF                C5L3             1        CAP_0805-100UF,4V,20%,X5R,6024A
PVDDQ_DEF                C5L6             1        CAP_A_0603V-22.0UF,4V,20%,X6S,A
PVDDQ_DEF                C5L7             1        CAP_A_0603V-22.0UF,4V,20%,X6S,A
PVDDQ_DEF                C5L8             1        CAP_A_0603V-22.0UF,4V,20%,X6S,A
PVDDQ_DEF                C5L9             1        CAP_A_0603V-22.0UF,4V,20%,X6S,A
PVDDQ_DEF                C5L10            1        CAP_A_0603V-22.0UF,4V,20%,X6S,A
PVDDQ_DEF                C5L11            1        CAP_A_0603V-22.0UF,4V,20%,X6S,A
PVDDQ_DEF                C5L12            1        CAP_A_0603V-22.0UF,4V,20%,X6S,A
PVDDQ_DEF                C5L13            1        CAP_A_0603V-22.0UF,4V,20%,X6S,A
PVDDQ_DEF                C5L14            1        CAP_0805-100UF,4V,20%,X5R,6024A
PVDDQ_DEF                C5L15            1        CAP_A_0603V-47UF,4V,20%,X5R,60A
PVDDQ_DEF                C5M1             1        CAP_A_0603V-22.0UF,4V,20%,X6S,A
PVDDQ_DEF                C5M2             1        CAP_A_0603V-22.0UF,4V,20%,X6S,A
PVDDQ_DEF                C5M3             1        CAP_A_0603V-47UF,4V,20%,X5R,60A
PVDDQ_DEF                C5M4             1        CAP_A_0603V-22.0UF,4V,20%,X6S,A
PVDDQ_DEF                C5M5             1        CAP_A_0603V-22.0UF,4V,20%,X6S,A
PVDDQ_DEF                C5M6             1        CAP_A_0603V-22.0UF,4V,20%,X6S,A
PVDDQ_DEF                C5M7             1        CAP_A_0603V-22.0UF,4V,20%,X6S,A
PVDDQ_DEF                C5M8             1        CAP_0805-100UF,4V,20%,X5R,6024A
PVDDQ_DEF                C5M9             1        CAP_A_0603V-47UF,4V,20%,X5R,60A
PVDDQ_DEF                C5M10            1        CAP_A_0603V-47UF,4V,20%,X5R,60A
PVDDQ_DEF                C5M11            1        CAP_A_0603V-47UF,4V,20%,X5R,60A
PVDDQ_DEF                C5M12            1        CAP_0805-100UF,4V,20%,X5R,6024A
PVDDQ_DEF                C5P1             1        CAP_0805LF-22UF,4V,20%,X6S,C95A
PVDDQ_DEF                C5P2             1        CAP_0805LF-22UF,4V,20%,X6S,C95A
PVDDQ_DEF                C6A1             1        CAP_0805LF-22UF,4V,20%,X6S,C95A
PVDDQ_DEF                C6A4             1        CAP_0805LF-22UF,4V,20%,X6S,C95A
PVDDQ_DEF                C6A5             1        CAPP_3018-470UF,2.5V,20%,ALUM,A
PVDDQ_DEF                C6L3             1        CAP_0603LF-10UF,4V,20%,X6S,E15A
PVDDQ_DEF                C6L4             1        CAP_0603LF-10UF,4V,20%,X6S,E15A
PVDDQ_DEF                EU4A1            10       MIC5166_DFN-IC,H55101-001
PVDDQ_DEF                EU7A1            1        IR354XX_SM-IR35411,IC,H73688-0A
PVDDQ_DEF                EU7A4            1        IR354XX_SM-IR35411,IC,H73688-0A
PVDDQ_DEF                J4A1             59       SCONN288_H44441004_PIP-SCONN,HA
PVDDQ_DEF                J4A1             61       SCONN288_H44441004_PIP-SCONN,HA
PVDDQ_DEF                J4A1             64       SCONN288_H44441004_PIP-SCONN,HA
PVDDQ_DEF                J4A1             67       SCONN288_H44441004_PIP-SCONN,HA
PVDDQ_DEF                J4A1             70       SCONN288_H44441004_PIP-SCONN,HA
PVDDQ_DEF                J4A1             73       SCONN288_H44441004_PIP-SCONN,HA
PVDDQ_DEF                J4A1             76       SCONN288_H44441004_PIP-SCONN,HA
PVDDQ_DEF                J4A1             80       SCONN288_H44441004_PIP-SCONN,HA
PVDDQ_DEF                J4A1             83       SCONN288_H44441004_PIP-SCONN,HA
PVDDQ_DEF                J4A1             85       SCONN288_H44441004_PIP-SCONN,HA
PVDDQ_DEF                J4A1             88       SCONN288_H44441004_PIP-SCONN,HA
PVDDQ_DEF                J4A1             90       SCONN288_H44441004_PIP-SCONN,HA
PVDDQ_DEF                J4A1             92       SCONN288_H44441004_PIP-SCONN,HA
PVDDQ_DEF                J4A1             204      SCONN288_H44441004_PIP-SCONN,HA
PVDDQ_DEF                J4A1             206      SCONN288_H44441004_PIP-SCONN,HA
PVDDQ_DEF                J4A1             209      SCONN288_H44441004_PIP-SCONN,HA
PVDDQ_DEF                J4A1             212      SCONN288_H44441004_PIP-SCONN,HA
PVDDQ_DEF                J4A1             215      SCONN288_H44441004_PIP-SCONN,HA
PVDDQ_DEF                J4A1             217      SCONN288_H44441004_PIP-SCONN,HA
PVDDQ_DEF                J4A1             220      SCONN288_H44441004_PIP-SCONN,HA
PVDDQ_DEF                J4A1             223      SCONN288_H44441004_PIP-SCONN,HA
PVDDQ_DEF                J4A1             226      SCONN288_H44441004_PIP-SCONN,HA
PVDDQ_DEF                J4A1             229      SCONN288_H44441004_PIP-SCONN,HA
PVDDQ_DEF                J4A1             231      SCONN288_H44441004_PIP-SCONN,HA
PVDDQ_DEF                J4A1             233      SCONN288_H44441004_PIP-SCONN,HA
PVDDQ_DEF                J4A1             236      SCONN288_H44441004_PIP-SCONN,HA
PVDDQ_DEF                J4A2             59       SCONN288_H44441004_PIP-SCONN,HA
PVDDQ_DEF                J4A2             61       SCONN288_H44441004_PIP-SCONN,HA
PVDDQ_DEF                J4A2             64       SCONN288_H44441004_PIP-SCONN,HA
PVDDQ_DEF                J4A2             67       SCONN288_H44441004_PIP-SCONN,HA
PVDDQ_DEF                J4A2             70       SCONN288_H44441004_PIP-SCONN,HA
PVDDQ_DEF                J4A2             73       SCONN288_H44441004_PIP-SCONN,HA
PVDDQ_DEF                J4A2             76       SCONN288_H44441004_PIP-SCONN,HA
PVDDQ_DEF                J4A2             80       SCONN288_H44441004_PIP-SCONN,HA
PVDDQ_DEF                J4A2             83       SCONN288_H44441004_PIP-SCONN,HA
PVDDQ_DEF                J4A2             85       SCONN288_H44441004_PIP-SCONN,HA
PVDDQ_DEF                J4A2             88       SCONN288_H44441004_PIP-SCONN,HA
PVDDQ_DEF                J4A2             90       SCONN288_H44441004_PIP-SCONN,HA
PVDDQ_DEF                J4A2             92       SCONN288_H44441004_PIP-SCONN,HA
PVDDQ_DEF                J4A2             204      SCONN288_H44441004_PIP-SCONN,HA
PVDDQ_DEF                J4A2             206      SCONN288_H44441004_PIP-SCONN,HA
PVDDQ_DEF                J4A2             209      SCONN288_H44441004_PIP-SCONN,HA
PVDDQ_DEF                J4A2             212      SCONN288_H44441004_PIP-SCONN,HA
PVDDQ_DEF                J4A2             215      SCONN288_H44441004_PIP-SCONN,HA
PVDDQ_DEF                J4A2             217      SCONN288_H44441004_PIP-SCONN,HA
PVDDQ_DEF                J4A2             220      SCONN288_H44441004_PIP-SCONN,HA
PVDDQ_DEF                J4A2             223      SCONN288_H44441004_PIP-SCONN,HA
PVDDQ_DEF                J4A2             226      SCONN288_H44441004_PIP-SCONN,HA
PVDDQ_DEF                J4A2             229      SCONN288_H44441004_PIP-SCONN,HA
PVDDQ_DEF                J4A2             231      SCONN288_H44441004_PIP-SCONN,HA
PVDDQ_DEF                J4A2             233      SCONN288_H44441004_PIP-SCONN,HA
PVDDQ_DEF                J4A2             236      SCONN288_H44441004_PIP-SCONN,HA
PVDDQ_DEF                J4B1             59       SCONN288_H44441004_PIP-SCONN,HA
PVDDQ_DEF                J4B1             61       SCONN288_H44441004_PIP-SCONN,HA
PVDDQ_DEF                J4B1             64       SCONN288_H44441004_PIP-SCONN,HA
PVDDQ_DEF                J4B1             67       SCONN288_H44441004_PIP-SCONN,HA
PVDDQ_DEF                J4B1             70       SCONN288_H44441004_PIP-SCONN,HA
PVDDQ_DEF                J4B1             73       SCONN288_H44441004_PIP-SCONN,HA
PVDDQ_DEF                J4B1             76       SCONN288_H44441004_PIP-SCONN,HA
PVDDQ_DEF                J4B1             80       SCONN288_H44441004_PIP-SCONN,HA
PVDDQ_DEF                J4B1             83       SCONN288_H44441004_PIP-SCONN,HA
PVDDQ_DEF                J4B1             85       SCONN288_H44441004_PIP-SCONN,HA
PVDDQ_DEF                J4B1             88       SCONN288_H44441004_PIP-SCONN,HA
PVDDQ_DEF                J4B1             90       SCONN288_H44441004_PIP-SCONN,HA
PVDDQ_DEF                J4B1             92       SCONN288_H44441004_PIP-SCONN,HA
PVDDQ_DEF                J4B1             204      SCONN288_H44441004_PIP-SCONN,HA
PVDDQ_DEF                J4B1             206      SCONN288_H44441004_PIP-SCONN,HA
PVDDQ_DEF                J4B1             209      SCONN288_H44441004_PIP-SCONN,HA
PVDDQ_DEF                J4B1             212      SCONN288_H44441004_PIP-SCONN,HA
PVDDQ_DEF                J4B1             215      SCONN288_H44441004_PIP-SCONN,HA
PVDDQ_DEF                J4B1             217      SCONN288_H44441004_PIP-SCONN,HA
PVDDQ_DEF                J4B1             220      SCONN288_H44441004_PIP-SCONN,HA
PVDDQ_DEF                J4B1             223      SCONN288_H44441004_PIP-SCONN,HA
PVDDQ_DEF                J4B1             226      SCONN288_H44441004_PIP-SCONN,HA
PVDDQ_DEF                J4B1             229      SCONN288_H44441004_PIP-SCONN,HA
PVDDQ_DEF                J4B1             231      SCONN288_H44441004_PIP-SCONN,HA
PVDDQ_DEF                J4B1             233      SCONN288_H44441004_PIP-SCONN,HA
PVDDQ_DEF                J4B1             236      SCONN288_H44441004_PIP-SCONN,HA
PVDDQ_DEF                J6L1             59       SCONN288_H44441003_PIP-SCONN,HA
PVDDQ_DEF                J6L1             61       SCONN288_H44441003_PIP-SCONN,HA
PVDDQ_DEF                J6L1             64       SCONN288_H44441003_PIP-SCONN,HA
PVDDQ_DEF                J6L1             67       SCONN288_H44441003_PIP-SCONN,HA
PVDDQ_DEF                J6L1             70       SCONN288_H44441003_PIP-SCONN,HA
PVDDQ_DEF                J6L1             73       SCONN288_H44441003_PIP-SCONN,HA
PVDDQ_DEF                J6L1             76       SCONN288_H44441003_PIP-SCONN,HA
PVDDQ_DEF                J6L1             80       SCONN288_H44441003_PIP-SCONN,HA
PVDDQ_DEF                J6L1             83       SCONN288_H44441003_PIP-SCONN,HA
PVDDQ_DEF                J6L1             85       SCONN288_H44441003_PIP-SCONN,HA
PVDDQ_DEF                J6L1             88       SCONN288_H44441003_PIP-SCONN,HA
PVDDQ_DEF                J6L1             90       SCONN288_H44441003_PIP-SCONN,HA
PVDDQ_DEF                J6L1             92       SCONN288_H44441003_PIP-SCONN,HA
PVDDQ_DEF                J6L1             204      SCONN288_H44441003_PIP-SCONN,HA
PVDDQ_DEF                J6L1             206      SCONN288_H44441003_PIP-SCONN,HA
PVDDQ_DEF                J6L1             209      SCONN288_H44441003_PIP-SCONN,HA
PVDDQ_DEF                J6L1             212      SCONN288_H44441003_PIP-SCONN,HA
PVDDQ_DEF                J6L1             215      SCONN288_H44441003_PIP-SCONN,HA
PVDDQ_DEF                J6L1             217      SCONN288_H44441003_PIP-SCONN,HA
PVDDQ_DEF                J6L1             220      SCONN288_H44441003_PIP-SCONN,HA
PVDDQ_DEF                J6L1             223      SCONN288_H44441003_PIP-SCONN,HA
PVDDQ_DEF                J6L1             226      SCONN288_H44441003_PIP-SCONN,HA
PVDDQ_DEF                J6L1             229      SCONN288_H44441003_PIP-SCONN,HA
PVDDQ_DEF                J6L1             231      SCONN288_H44441003_PIP-SCONN,HA
PVDDQ_DEF                J6L1             233      SCONN288_H44441003_PIP-SCONN,HA
PVDDQ_DEF                J6L1             236      SCONN288_H44441003_PIP-SCONN,HA
PVDDQ_DEF                J6L2             59       SCONN288_H44441003_PIP-SCONN,HA
PVDDQ_DEF                J6L2             61       SCONN288_H44441003_PIP-SCONN,HA
PVDDQ_DEF                J6L2             64       SCONN288_H44441003_PIP-SCONN,HA
PVDDQ_DEF                J6L2             67       SCONN288_H44441003_PIP-SCONN,HA
PVDDQ_DEF                J6L2             70       SCONN288_H44441003_PIP-SCONN,HA
PVDDQ_DEF                J6L2             73       SCONN288_H44441003_PIP-SCONN,HA
PVDDQ_DEF                J6L2             76       SCONN288_H44441003_PIP-SCONN,HA
PVDDQ_DEF                J6L2             80       SCONN288_H44441003_PIP-SCONN,HA
PVDDQ_DEF                J6L2             83       SCONN288_H44441003_PIP-SCONN,HA
PVDDQ_DEF                J6L2             85       SCONN288_H44441003_PIP-SCONN,HA
PVDDQ_DEF                J6L2             88       SCONN288_H44441003_PIP-SCONN,HA
PVDDQ_DEF                J6L2             90       SCONN288_H44441003_PIP-SCONN,HA
PVDDQ_DEF                J6L2             92       SCONN288_H44441003_PIP-SCONN,HA
PVDDQ_DEF                J6L2             204      SCONN288_H44441003_PIP-SCONN,HA
PVDDQ_DEF                J6L2             206      SCONN288_H44441003_PIP-SCONN,HA
PVDDQ_DEF                J6L2             209      SCONN288_H44441003_PIP-SCONN,HA
PVDDQ_DEF                J6L2             212      SCONN288_H44441003_PIP-SCONN,HA
PVDDQ_DEF                J6L2             215      SCONN288_H44441003_PIP-SCONN,HA
PVDDQ_DEF                J6L2             217      SCONN288_H44441003_PIP-SCONN,HA
PVDDQ_DEF                J6L2             220      SCONN288_H44441003_PIP-SCONN,HA
PVDDQ_DEF                J6L2             223      SCONN288_H44441003_PIP-SCONN,HA
PVDDQ_DEF                J6L2             226      SCONN288_H44441003_PIP-SCONN,HA
PVDDQ_DEF                J6L2             229      SCONN288_H44441003_PIP-SCONN,HA
PVDDQ_DEF                J6L2             231      SCONN288_H44441003_PIP-SCONN,HA
PVDDQ_DEF                J6L2             233      SCONN288_H44441003_PIP-SCONN,HA
PVDDQ_DEF                J6L2             236      SCONN288_H44441003_PIP-SCONN,HA
PVDDQ_DEF                J6M1             59       SCONN288_H44441003_PIP-SCONN,HA
PVDDQ_DEF                J6M1             61       SCONN288_H44441003_PIP-SCONN,HA
PVDDQ_DEF                J6M1             64       SCONN288_H44441003_PIP-SCONN,HA
PVDDQ_DEF                J6M1             67       SCONN288_H44441003_PIP-SCONN,HA
PVDDQ_DEF                J6M1             70       SCONN288_H44441003_PIP-SCONN,HA
PVDDQ_DEF                J6M1             73       SCONN288_H44441003_PIP-SCONN,HA
PVDDQ_DEF                J6M1             76       SCONN288_H44441003_PIP-SCONN,HA
PVDDQ_DEF                J6M1             80       SCONN288_H44441003_PIP-SCONN,HA
PVDDQ_DEF                J6M1             83       SCONN288_H44441003_PIP-SCONN,HA
PVDDQ_DEF                J6M1             85       SCONN288_H44441003_PIP-SCONN,HA
PVDDQ_DEF                J6M1             88       SCONN288_H44441003_PIP-SCONN,HA
PVDDQ_DEF                J6M1             90       SCONN288_H44441003_PIP-SCONN,HA
PVDDQ_DEF                J6M1             92       SCONN288_H44441003_PIP-SCONN,HA
PVDDQ_DEF                J6M1             204      SCONN288_H44441003_PIP-SCONN,HA
PVDDQ_DEF                J6M1             206      SCONN288_H44441003_PIP-SCONN,HA
PVDDQ_DEF                J6M1             209      SCONN288_H44441003_PIP-SCONN,HA
PVDDQ_DEF                J6M1             212      SCONN288_H44441003_PIP-SCONN,HA
PVDDQ_DEF                J6M1             215      SCONN288_H44441003_PIP-SCONN,HA
PVDDQ_DEF                J6M1             217      SCONN288_H44441003_PIP-SCONN,HA
PVDDQ_DEF                J6M1             220      SCONN288_H44441003_PIP-SCONN,HA
PVDDQ_DEF                J6M1             223      SCONN288_H44441003_PIP-SCONN,HA
PVDDQ_DEF                J6M1             226      SCONN288_H44441003_PIP-SCONN,HA
PVDDQ_DEF                J6M1             229      SCONN288_H44441003_PIP-SCONN,HA
PVDDQ_DEF                J6M1             231      SCONN288_H44441003_PIP-SCONN,HA
PVDDQ_DEF                J6M1             233      SCONN288_H44441003_PIP-SCONN,HA
PVDDQ_DEF                J6M1             236      SCONN288_H44441003_PIP-SCONN,HA
PVDDQ_DEF                L7A1             2        INDUCTOR_SM-0.12UH,IND,D92183-A
PVDDQ_DEF                L7A3             2        INDUCTOR_SM-0.12UH,IND,D92183-A
PVDDQ_DEF                R3P29            1        RES_0402-64.9,1.0%,1/16W,CHIP,A
PVDDQ_DEF                R4L4             1        RES_0603-120.0,1%,1/10W,CHIP,GA
PVDDQ_DEF                R6L2             1        RES_0402-1.00K,1%,1/16W,CHIP,GA
PVDDQ_DEF                R6L10            1        RES_0402-0.0,5%,1/16W,CHIP,G21A
PVDDQ_DEF                R6L13            1        RES_0402-1.00K,1%,1/16W,CHIP,GA
PVDDQ_DEF                R6M1             1        RES_0402-1.00K,1%,1/16W,CHIP,GA
PVDDQ_DEF                SH4L2            2        SHUNT_SH0201-EMPTY,N_A
PVDDQ_DEF                U5D1             DB53     SKX_EXT_B_BGA1-IC,TBD
PVDDQ_DEF                U5D1             DB55     SKX_EXT_B_BGA1-IC,TBD
PVDDQ_DEF                U5D1             DB57     SKX_EXT_B_BGA1-IC,TBD
PVDDQ_DEF                U5D1             DB59     SKX_EXT_B_BGA1-IC,TBD
PVDDQ_DEF                U5D1             DB61     SKX_EXT_B_BGA1-IC,TBD
PVDDQ_DEF                U5D1             DB63     SKX_EXT_B_BGA1-IC,TBD
PVDDQ_DEF                U5D1             DD45     SKX_EXT_B_BGA1-IC,TBD
PVDDQ_DEF                U5D1             DH45     SKX_EXT_B_BGA1-IC,TBD
PVDDQ_DEF                U5D1             DH47     SKX_EXT_B_BGA1-IC,TBD
PVDDQ_DEF                U5D1             DH49     SKX_EXT_B_BGA1-IC,TBD
PVDDQ_DEF                U5D1             DH51     SKX_EXT_B_BGA1-IC,TBD
PVDDQ_DEF                U5D1             DH53     SKX_EXT_B_BGA1-IC,TBD
PVDDQ_DEF                U5D1             DH55     SKX_EXT_B_BGA1-IC,TBD
PVDDQ_DEF                U5D1             DH57     SKX_EXT_B_BGA1-IC,TBD
PVDDQ_DEF                U5D1             DH59     SKX_EXT_B_BGA1-IC,TBD
PVDDQ_DEF                U5D1             DH61     SKX_EXT_B_BGA1-IC,TBD
PVDDQ_DEF                U5D1             DH63     SKX_EXT_B_BGA1-IC,TBD
PVDDQ_DEF                U5D1             DJ64     SKX_EXT_B_BGA1-IC,TBD
PVDDQ_DEF                U5D1             DL46     SKX_EXT_B_BGA1-IC,TBD
PVDDQ_DEF                U5D1             DL48     SKX_EXT_B_BGA1-IC,TBD
PVDDQ_DEF                U5D1             DL50     SKX_EXT_B_BGA1-IC,TBD
PVDDQ_DEF                U5D1             DL52     SKX_EXT_B_BGA1-IC,TBD
PVDDQ_DEF                U5D1             DL54     SKX_EXT_B_BGA1-IC,TBD
PVDDQ_DEF                U5D1             DL56     SKX_EXT_B_BGA1-IC,TBD
PVDDQ_DEF                U5D1             DL58     SKX_EXT_B_BGA1-IC,TBD
PVDDQ_DEF                U5D1             DL60     SKX_EXT_B_BGA1-IC,TBD
PVDDQ_DEF                U5D1             DL62     SKX_EXT_B_BGA1-IC,TBD
PVDDQ_DEF                U5D1             DU46     SKX_EXT_B_BGA1-IC,TBD
PVDDQ_DEF                U5D1             DU48     SKX_EXT_B_BGA1-IC,TBD
PVDDQ_DEF                U5D1             DU50     SKX_EXT_B_BGA1-IC,TBD
PVDDQ_DEF                U5D1             DU52     SKX_EXT_B_BGA1-IC,TBD
PVDDQ_DEF                U5D1             DU54     SKX_EXT_B_BGA1-IC,TBD
PVDDQ_DEF                U5D1             DU56     SKX_EXT_B_BGA1-IC,TBD
PVDDQ_DEF                U5D1             DU58     SKX_EXT_B_BGA1-IC,TBD
PVDDQ_DEF                U5D1             DU60     SKX_EXT_B_BGA1-IC,TBD
PVDDQ_DEF                U5D1             DU62     SKX_EXT_B_BGA1-IC,TBD
PVDDQ_DEF                U5D1             DU64     SKX_EXT_B_BGA1-IC,TBD
PVDDQ_DEF                U5D1             EC46     SKX_EXT_B_BGA1-IC,TBD
PVDDQ_DEF                U5D1             EC48     SKX_EXT_B_BGA1-IC,TBD
PVDDQ_DEF                U5D1             EC50     SKX_EXT_B_BGA1-IC,TBD
PVDDQ_DEF                U5D1             EC52     SKX_EXT_B_BGA1-IC,TBD
PVDDQ_DEF                U5D1             EC54     SKX_EXT_B_BGA1-IC,TBD
PVDDQ_DEF                U5D1             EC56     SKX_EXT_B_BGA1-IC,TBD
PVDDQ_DEF                U5D1             EC58     SKX_EXT_B_BGA1-IC,TBD
PVDDQ_DEF                U5D1             EC60     SKX_EXT_B_BGA1-IC,TBD
PVDDQ_DEF                U5D1             EC62     SKX_EXT_B_BGA1-IC,TBD
PVDDQ_DEF                U5D1             EE44     SKX_EXT_B_BGA1-IC,TBD
PVDDQ_DEF                U5D1             EF45     SKX_EXT_B_BGA1-IC,TBD
PVDDQ_DEF                U5D1             EF49     SKX_EXT_B_BGA1-IC,TBD
PVDDQ_DEF                U5D1             EF53     SKX_EXT_B_BGA1-IC,TBD
PVDDQ_DEF                U5D1             EF59     SKX_EXT_B_BGA1-IC,TBD
PVDDQ_GHJ                C1G17            1        CAP_0805LF-22UF,4V,20%,X6S,C95A
PVDDQ_GHJ                C1G20            1        CAP_0805LF-22UF,4V,20%,X6S,C95A
PVDDQ_GHJ                C2D41            1        CAP_0603LF-10UF,4V,20%,X6S,E15A
PVDDQ_GHJ                C2D42            1        CAP_0603LF-10UF,4V,20%,X6S,E15A
PVDDQ_GHJ                C2D43            1        CAP_0603LF-10UF,4V,20%,X6S,E15A
PVDDQ_GHJ                C2D44            1        CAP_0603LF-10UF,4V,20%,X6S,E15A
PVDDQ_GHJ                C2F1             1        CAP_A_0603V-47UF,4V,20%,X5R,60A
PVDDQ_GHJ                C2G1             1        CAP_A_0603V-22.0UF,4V,20%,X6S,A
PVDDQ_GHJ                C2G2             1        CAP_A_0603V-22.0UF,4V,20%,X6S,A
PVDDQ_GHJ                C2G3             1        CAP_A_0603V-22.0UF,4V,20%,X6S,A
PVDDQ_GHJ                C2G4             1        CAP_A_0603V-22.0UF,4V,20%,X6S,A
PVDDQ_GHJ                C2G5             1        CAP_A_0603V-22.0UF,4V,20%,X6S,A
PVDDQ_GHJ                C2G6             1        CAP_A_0603V-22.0UF,4V,20%,X6S,A
PVDDQ_GHJ                C2G7             1        CAP_0805-100UF,4V,20%,X5R,6024A
PVDDQ_GHJ                C2G8             1        CAP_A_0603V-47UF,4V,20%,X5R,60A
PVDDQ_GHJ                C2G9             1        CAP_A_0603V-22.0UF,4V,20%,X6S,A
PVDDQ_GHJ                C2G10            1        CAP_A_0603V-22.0UF,4V,20%,X6S,A
PVDDQ_GHJ                C2G11            1        CAP_A_0603V-22.0UF,4V,20%,X6S,A
PVDDQ_GHJ                C2G12            1        CAP_A_0603V-22.0UF,4V,20%,X6S,A
PVDDQ_GHJ                C2G13            1        CAP_A_0603V-22.0UF,4V,20%,X6S,A
PVDDQ_GHJ                C2G14            1        CAP_A_0603V-22.0UF,4V,20%,X6S,A
PVDDQ_GHJ                C2G15            1        CAP_A_0603V-47UF,4V,20%,X5R,60A
PVDDQ_GHJ                C2G16            1        CAP_0805-100UF,4V,20%,X5R,6024A
PVDDQ_GHJ                C3G1             1        CAP_A_0603V-22.0UF,4V,20%,X6S,A
PVDDQ_GHJ                C3G2             1        CAP_A_0603V-22.0UF,4V,20%,X6S,A
PVDDQ_GHJ                C3G5             1        CAP_A_0603V-22.0UF,4V,20%,X6S,A
PVDDQ_GHJ                C3G6             1        CAP_A_0603V-22.0UF,4V,20%,X6S,A
PVDDQ_GHJ                C5G79            1        CAP_A_0603V-22.0UF,4V,20%,X6S,A
PVDDQ_GHJ                C5G80            1        CAP_A_0603V-22.0UF,4V,20%,X6S,A
PVDDQ_GHJ                C5G81            1        CAP_A_0603V-22.0UF,4V,20%,X6S,A
PVDDQ_GHJ                C5G82            1        CAP_A_0603V-22.0UF,4V,20%,X6S,A
PVDDQ_GHJ                C5G83            1        CAP_A_0603V-22.0UF,4V,20%,X6S,A
PVDDQ_GHJ                C5G84            1        CAP_A_0603V-22.0UF,4V,20%,X6S,A
PVDDQ_GHJ                C5G85            1        CAP_A_0603V-22.0UF,4V,20%,X6S,A
PVDDQ_GHJ                C5G86            1        CAP_A_0603V-22.0UF,4V,20%,X6S,A
PVDDQ_GHJ                C5G87            1        CAP_A_0603V-22.0UF,4V,20%,X6S,A
PVDDQ_GHJ                C5G88            1        CAP_A_0603V-22.0UF,4V,20%,X6S,A
PVDDQ_GHJ                C5G89            1        CAP_A_0603V-22.0UF,4V,20%,X6S,A
PVDDQ_GHJ                C5G90            1        CAP_A_0603V-22.0UF,4V,20%,X6S,A
PVDDQ_GHJ                C5G91            1        CAP_A_0603V-22.0UF,4V,20%,X6S,A
PVDDQ_GHJ                C5G92            1        CAP_A_0603V-22.0UF,4V,20%,X6S,A
PVDDQ_GHJ                C5G93            1        CAP_A_0603V-22.0UF,4V,20%,X6S,A
PVDDQ_GHJ                C5G94            1        CAP_A_0603V-22.0UF,4V,20%,X6S,A
PVDDQ_GHJ                C5G95            1        CAP_A_0603V-22.0UF,4V,20%,X6S,A
PVDDQ_GHJ                C5G96            1        CAP_A_0603V-22.0UF,4V,20%,X6S,A
PVDDQ_GHJ                C5G117           1        CAP_0805-100UF,4V,20%,X5R,6024A
PVDDQ_GHJ                C5G118           1        CAP_0805-100UF,4V,20%,X5R,6024A
PVDDQ_GHJ                C6U13            1        CAP_0603LF-10UF,4V,20%,X6S,E15A
PVDDQ_GHJ                C6U14            1        CAP_0603LF-10UF,4V,20%,X6S,E15A
PVDDQ_GHJ                C7T1             1        CAP_0805-100UF,4V,20%,X5R,6024A
PVDDQ_GHJ                C7T4             1        CAP_A_0603V-22.0UF,4V,20%,X6S,A
PVDDQ_GHJ                C7T5             1        CAP_A_0603V-22.0UF,4V,20%,X6S,A
PVDDQ_GHJ                C7U1             1        CAP_A_0603V-22.0UF,4V,20%,X6S,A
PVDDQ_GHJ                C7U2             1        CAP_A_0603V-22.0UF,4V,20%,X6S,A
PVDDQ_GHJ                C7U7             1        CAP_0805-100UF,4V,20%,X5R,6024A
PVDDQ_GHJ                C8P30            1        CAP_0805LF-22UF,4V,20%,X6S,C95A
PVDDQ_GHJ                C8P31            1        CAP_0805LF-22UF,4V,20%,X6S,C95A
PVDDQ_GHJ                C8T1             1        CAP_A_0603V-47UF,4V,20%,X5R,60A
PVDDQ_GHJ                C8T2             1        CAP_A_0603V-47UF,4V,20%,X5R,60A
PVDDQ_GHJ                C8T4             1        CAP_A_0603V-47UF,4V,20%,X5R,60A
PVDDQ_GHJ                C8T5             1        CAP_A_0603V-22.0UF,4V,20%,X6S,A
PVDDQ_GHJ                C8T6             1        CAP_A_0603V-22.0UF,4V,20%,X6S,A
PVDDQ_GHJ                C8T7             1        CAP_A_0603V-22.0UF,4V,20%,X6S,A
PVDDQ_GHJ                C8T8             1        CAP_A_0603V-22.0UF,4V,20%,X6S,A
PVDDQ_GHJ                C8T9             1        CAP_A_0603V-22.0UF,4V,20%,X6S,A
PVDDQ_GHJ                C8T10            1        CAP_A_0603V-22.0UF,4V,20%,X6S,A
PVDDQ_GHJ                C8T11            1        CAP_A_0603V-47UF,4V,20%,X5R,60A
PVDDQ_GHJ                C8U1             1        CAP_0805-100UF,4V,20%,X5R,6024A
PVDDQ_GHJ                C8U2             1        CAP_A_0603V-22.0UF,4V,20%,X6S,A
PVDDQ_GHJ                C8U3             1        CAP_A_0603V-22.0UF,4V,20%,X6S,A
PVDDQ_GHJ                C8U4             1        CAP_A_0603V-22.0UF,4V,20%,X6S,A
PVDDQ_GHJ                C8U5             1        CAP_A_0603V-22.0UF,4V,20%,X6S,A
PVDDQ_GHJ                C8U6             1        CAP_A_0603V-22.0UF,4V,20%,X6S,A
PVDDQ_GHJ                C8U7             1        CAP_A_0603V-22.0UF,4V,20%,X6S,A
PVDDQ_GHJ                C8U8             1        CAP_0805-100UF,4V,20%,X5R,6024A
PVDDQ_GHJ                C8U9             1        CAP_A_0603V-47UF,4V,20%,X5R,60A
PVDDQ_GHJ                C8U11            1        CAP_0805-100UF,4V,20%,X5R,6024A
PVDDQ_GHJ                C8U12            1        CAP_0805-100UF,4V,20%,X5R,6024A
PVDDQ_GHJ                C8U13            1        CAP_A_0603V-47UF,4V,20%,X5R,60A
PVDDQ_GHJ                C9T5             1        CAPP_3018-470UF,2.5V,20%,ALUM,A
PVDDQ_GHJ                C9U2             1        CAPP_3018-470UF,2.5V,20%,ALUM,A
PVDDQ_GHJ                C9U5             1        CAPP_3018-470UF,2.5V,20%,ALUM,A
PVDDQ_GHJ                C9U9             1        CAPP_3018-470UF,2.5V,20%,ALUM,A
PVDDQ_GHJ                EU1F1            1        IR354XX_SM-IR35411,IC,H73688-0A
PVDDQ_GHJ                EU1G1            1        IR354XX_SM-IR35411,IC,H73688-0A
PVDDQ_GHJ                EU4G2            10       MIC5166_DFN-IC,H55101-001
PVDDQ_GHJ                J1G1             59       SCONN288_H44441004_PIP-SCONN,HA
PVDDQ_GHJ                J1G1             61       SCONN288_H44441004_PIP-SCONN,HA
PVDDQ_GHJ                J1G1             64       SCONN288_H44441004_PIP-SCONN,HA
PVDDQ_GHJ                J1G1             67       SCONN288_H44441004_PIP-SCONN,HA
PVDDQ_GHJ                J1G1             70       SCONN288_H44441004_PIP-SCONN,HA
PVDDQ_GHJ                J1G1             73       SCONN288_H44441004_PIP-SCONN,HA
PVDDQ_GHJ                J1G1             76       SCONN288_H44441004_PIP-SCONN,HA
PVDDQ_GHJ                J1G1             80       SCONN288_H44441004_PIP-SCONN,HA
PVDDQ_GHJ                J1G1             83       SCONN288_H44441004_PIP-SCONN,HA
PVDDQ_GHJ                J1G1             85       SCONN288_H44441004_PIP-SCONN,HA
PVDDQ_GHJ                J1G1             88       SCONN288_H44441004_PIP-SCONN,HA
PVDDQ_GHJ                J1G1             90       SCONN288_H44441004_PIP-SCONN,HA
PVDDQ_GHJ                J1G1             92       SCONN288_H44441004_PIP-SCONN,HA
PVDDQ_GHJ                J1G1             204      SCONN288_H44441004_PIP-SCONN,HA
PVDDQ_GHJ                J1G1             206      SCONN288_H44441004_PIP-SCONN,HA
PVDDQ_GHJ                J1G1             209      SCONN288_H44441004_PIP-SCONN,HA
PVDDQ_GHJ                J1G1             212      SCONN288_H44441004_PIP-SCONN,HA
PVDDQ_GHJ                J1G1             215      SCONN288_H44441004_PIP-SCONN,HA
PVDDQ_GHJ                J1G1             217      SCONN288_H44441004_PIP-SCONN,HA
PVDDQ_GHJ                J1G1             220      SCONN288_H44441004_PIP-SCONN,HA
PVDDQ_GHJ                J1G1             223      SCONN288_H44441004_PIP-SCONN,HA
PVDDQ_GHJ                J1G1             226      SCONN288_H44441004_PIP-SCONN,HA
PVDDQ_GHJ                J1G1             229      SCONN288_H44441004_PIP-SCONN,HA
PVDDQ_GHJ                J1G1             231      SCONN288_H44441004_PIP-SCONN,HA
PVDDQ_GHJ                J1G1             233      SCONN288_H44441004_PIP-SCONN,HA
PVDDQ_GHJ                J1G1             236      SCONN288_H44441004_PIP-SCONN,HA
PVDDQ_GHJ                J1G2             59       SCONN288_H44441004_PIP-SCONN,HA
PVDDQ_GHJ                J1G2             61       SCONN288_H44441004_PIP-SCONN,HA
PVDDQ_GHJ                J1G2             64       SCONN288_H44441004_PIP-SCONN,HA
PVDDQ_GHJ                J1G2             67       SCONN288_H44441004_PIP-SCONN,HA
PVDDQ_GHJ                J1G2             70       SCONN288_H44441004_PIP-SCONN,HA
PVDDQ_GHJ                J1G2             73       SCONN288_H44441004_PIP-SCONN,HA
PVDDQ_GHJ                J1G2             76       SCONN288_H44441004_PIP-SCONN,HA
PVDDQ_GHJ                J1G2             80       SCONN288_H44441004_PIP-SCONN,HA
PVDDQ_GHJ                J1G2             83       SCONN288_H44441004_PIP-SCONN,HA
PVDDQ_GHJ                J1G2             85       SCONN288_H44441004_PIP-SCONN,HA
PVDDQ_GHJ                J1G2             88       SCONN288_H44441004_PIP-SCONN,HA
PVDDQ_GHJ                J1G2             90       SCONN288_H44441004_PIP-SCONN,HA
PVDDQ_GHJ                J1G2             92       SCONN288_H44441004_PIP-SCONN,HA
PVDDQ_GHJ                J1G2             204      SCONN288_H44441004_PIP-SCONN,HA
PVDDQ_GHJ                J1G2             206      SCONN288_H44441004_PIP-SCONN,HA
PVDDQ_GHJ                J1G2             209      SCONN288_H44441004_PIP-SCONN,HA
PVDDQ_GHJ                J1G2             212      SCONN288_H44441004_PIP-SCONN,HA
PVDDQ_GHJ                J1G2             215      SCONN288_H44441004_PIP-SCONN,HA
PVDDQ_GHJ                J1G2             217      SCONN288_H44441004_PIP-SCONN,HA
PVDDQ_GHJ                J1G2             220      SCONN288_H44441004_PIP-SCONN,HA
PVDDQ_GHJ                J1G2             223      SCONN288_H44441004_PIP-SCONN,HA
PVDDQ_GHJ                J1G2             226      SCONN288_H44441004_PIP-SCONN,HA
PVDDQ_GHJ                J1G2             229      SCONN288_H44441004_PIP-SCONN,HA
PVDDQ_GHJ                J1G2             231      SCONN288_H44441004_PIP-SCONN,HA
PVDDQ_GHJ                J1G2             233      SCONN288_H44441004_PIP-SCONN,HA
PVDDQ_GHJ                J1G2             236      SCONN288_H44441004_PIP-SCONN,HA
PVDDQ_GHJ                J1G3             59       SCONN288_H44441004_PIP-SCONN,HA
PVDDQ_GHJ                J1G3             61       SCONN288_H44441004_PIP-SCONN,HA
PVDDQ_GHJ                J1G3             64       SCONN288_H44441004_PIP-SCONN,HA
PVDDQ_GHJ                J1G3             67       SCONN288_H44441004_PIP-SCONN,HA
PVDDQ_GHJ                J1G3             70       SCONN288_H44441004_PIP-SCONN,HA
PVDDQ_GHJ                J1G3             73       SCONN288_H44441004_PIP-SCONN,HA
PVDDQ_GHJ                J1G3             76       SCONN288_H44441004_PIP-SCONN,HA
PVDDQ_GHJ                J1G3             80       SCONN288_H44441004_PIP-SCONN,HA
PVDDQ_GHJ                J1G3             83       SCONN288_H44441004_PIP-SCONN,HA
PVDDQ_GHJ                J1G3             85       SCONN288_H44441004_PIP-SCONN,HA
PVDDQ_GHJ                J1G3             88       SCONN288_H44441004_PIP-SCONN,HA
PVDDQ_GHJ                J1G3             90       SCONN288_H44441004_PIP-SCONN,HA
PVDDQ_GHJ                J1G3             92       SCONN288_H44441004_PIP-SCONN,HA
PVDDQ_GHJ                J1G3             204      SCONN288_H44441004_PIP-SCONN,HA
PVDDQ_GHJ                J1G3             206      SCONN288_H44441004_PIP-SCONN,HA
PVDDQ_GHJ                J1G3             209      SCONN288_H44441004_PIP-SCONN,HA
PVDDQ_GHJ                J1G3             212      SCONN288_H44441004_PIP-SCONN,HA
PVDDQ_GHJ                J1G3             215      SCONN288_H44441004_PIP-SCONN,HA
PVDDQ_GHJ                J1G3             217      SCONN288_H44441004_PIP-SCONN,HA
PVDDQ_GHJ                J1G3             220      SCONN288_H44441004_PIP-SCONN,HA
PVDDQ_GHJ                J1G3             223      SCONN288_H44441004_PIP-SCONN,HA
PVDDQ_GHJ                J1G3             226      SCONN288_H44441004_PIP-SCONN,HA
PVDDQ_GHJ                J1G3             229      SCONN288_H44441004_PIP-SCONN,HA
PVDDQ_GHJ                J1G3             231      SCONN288_H44441004_PIP-SCONN,HA
PVDDQ_GHJ                J1G3             233      SCONN288_H44441004_PIP-SCONN,HA
PVDDQ_GHJ                J1G3             236      SCONN288_H44441004_PIP-SCONN,HA
PVDDQ_GHJ                J9T1             59       SCONN288_H44441003_PIP-SCONN,HA
PVDDQ_GHJ                J9T1             61       SCONN288_H44441003_PIP-SCONN,HA
PVDDQ_GHJ                J9T1             64       SCONN288_H44441003_PIP-SCONN,HA
PVDDQ_GHJ                J9T1             67       SCONN288_H44441003_PIP-SCONN,HA
PVDDQ_GHJ                J9T1             70       SCONN288_H44441003_PIP-SCONN,HA
PVDDQ_GHJ                J9T1             73       SCONN288_H44441003_PIP-SCONN,HA
PVDDQ_GHJ                J9T1             76       SCONN288_H44441003_PIP-SCONN,HA
PVDDQ_GHJ                J9T1             80       SCONN288_H44441003_PIP-SCONN,HA
PVDDQ_GHJ                J9T1             83       SCONN288_H44441003_PIP-SCONN,HA
PVDDQ_GHJ                J9T1             85       SCONN288_H44441003_PIP-SCONN,HA
PVDDQ_GHJ                J9T1             88       SCONN288_H44441003_PIP-SCONN,HA
PVDDQ_GHJ                J9T1             90       SCONN288_H44441003_PIP-SCONN,HA
PVDDQ_GHJ                J9T1             92       SCONN288_H44441003_PIP-SCONN,HA
PVDDQ_GHJ                J9T1             204      SCONN288_H44441003_PIP-SCONN,HA
PVDDQ_GHJ                J9T1             206      SCONN288_H44441003_PIP-SCONN,HA
PVDDQ_GHJ                J9T1             209      SCONN288_H44441003_PIP-SCONN,HA
PVDDQ_GHJ                J9T1             212      SCONN288_H44441003_PIP-SCONN,HA
PVDDQ_GHJ                J9T1             215      SCONN288_H44441003_PIP-SCONN,HA
PVDDQ_GHJ                J9T1             217      SCONN288_H44441003_PIP-SCONN,HA
PVDDQ_GHJ                J9T1             220      SCONN288_H44441003_PIP-SCONN,HA
PVDDQ_GHJ                J9T1             223      SCONN288_H44441003_PIP-SCONN,HA
PVDDQ_GHJ                J9T1             226      SCONN288_H44441003_PIP-SCONN,HA
PVDDQ_GHJ                J9T1             229      SCONN288_H44441003_PIP-SCONN,HA
PVDDQ_GHJ                J9T1             231      SCONN288_H44441003_PIP-SCONN,HA
PVDDQ_GHJ                J9T1             233      SCONN288_H44441003_PIP-SCONN,HA
PVDDQ_GHJ                J9T1             236      SCONN288_H44441003_PIP-SCONN,HA
PVDDQ_GHJ                J9U1             59       SCONN288_H44441003_PIP-SCONN,HA
PVDDQ_GHJ                J9U1             61       SCONN288_H44441003_PIP-SCONN,HA
PVDDQ_GHJ                J9U1             64       SCONN288_H44441003_PIP-SCONN,HA
PVDDQ_GHJ                J9U1             67       SCONN288_H44441003_PIP-SCONN,HA
PVDDQ_GHJ                J9U1             70       SCONN288_H44441003_PIP-SCONN,HA
PVDDQ_GHJ                J9U1             73       SCONN288_H44441003_PIP-SCONN,HA
PVDDQ_GHJ                J9U1             76       SCONN288_H44441003_PIP-SCONN,HA
PVDDQ_GHJ                J9U1             80       SCONN288_H44441003_PIP-SCONN,HA
PVDDQ_GHJ                J9U1             83       SCONN288_H44441003_PIP-SCONN,HA
PVDDQ_GHJ                J9U1             85       SCONN288_H44441003_PIP-SCONN,HA
PVDDQ_GHJ                J9U1             88       SCONN288_H44441003_PIP-SCONN,HA
PVDDQ_GHJ                J9U1             90       SCONN288_H44441003_PIP-SCONN,HA
PVDDQ_GHJ                J9U1             92       SCONN288_H44441003_PIP-SCONN,HA
PVDDQ_GHJ                J9U1             204      SCONN288_H44441003_PIP-SCONN,HA
PVDDQ_GHJ                J9U1             206      SCONN288_H44441003_PIP-SCONN,HA
PVDDQ_GHJ                J9U1             209      SCONN288_H44441003_PIP-SCONN,HA
PVDDQ_GHJ                J9U1             212      SCONN288_H44441003_PIP-SCONN,HA
PVDDQ_GHJ                J9U1             215      SCONN288_H44441003_PIP-SCONN,HA
PVDDQ_GHJ                J9U1             217      SCONN288_H44441003_PIP-SCONN,HA
PVDDQ_GHJ                J9U1             220      SCONN288_H44441003_PIP-SCONN,HA
PVDDQ_GHJ                J9U1             223      SCONN288_H44441003_PIP-SCONN,HA
PVDDQ_GHJ                J9U1             226      SCONN288_H44441003_PIP-SCONN,HA
PVDDQ_GHJ                J9U1             229      SCONN288_H44441003_PIP-SCONN,HA
PVDDQ_GHJ                J9U1             231      SCONN288_H44441003_PIP-SCONN,HA
PVDDQ_GHJ                J9U1             233      SCONN288_H44441003_PIP-SCONN,HA
PVDDQ_GHJ                J9U1             236      SCONN288_H44441003_PIP-SCONN,HA
PVDDQ_GHJ                J9U2             59       SCONN288_H44441003_PIP-SCONN,HA
PVDDQ_GHJ                J9U2             61       SCONN288_H44441003_PIP-SCONN,HA
PVDDQ_GHJ                J9U2             64       SCONN288_H44441003_PIP-SCONN,HA
PVDDQ_GHJ                J9U2             67       SCONN288_H44441003_PIP-SCONN,HA
PVDDQ_GHJ                J9U2             70       SCONN288_H44441003_PIP-SCONN,HA
PVDDQ_GHJ                J9U2             73       SCONN288_H44441003_PIP-SCONN,HA
PVDDQ_GHJ                J9U2             76       SCONN288_H44441003_PIP-SCONN,HA
PVDDQ_GHJ                J9U2             80       SCONN288_H44441003_PIP-SCONN,HA
PVDDQ_GHJ                J9U2             83       SCONN288_H44441003_PIP-SCONN,HA
PVDDQ_GHJ                J9U2             85       SCONN288_H44441003_PIP-SCONN,HA
PVDDQ_GHJ                J9U2             88       SCONN288_H44441003_PIP-SCONN,HA
PVDDQ_GHJ                J9U2             90       SCONN288_H44441003_PIP-SCONN,HA
PVDDQ_GHJ                J9U2             92       SCONN288_H44441003_PIP-SCONN,HA
PVDDQ_GHJ                J9U2             204      SCONN288_H44441003_PIP-SCONN,HA
PVDDQ_GHJ                J9U2             206      SCONN288_H44441003_PIP-SCONN,HA
PVDDQ_GHJ                J9U2             209      SCONN288_H44441003_PIP-SCONN,HA
PVDDQ_GHJ                J9U2             212      SCONN288_H44441003_PIP-SCONN,HA
PVDDQ_GHJ                J9U2             215      SCONN288_H44441003_PIP-SCONN,HA
PVDDQ_GHJ                J9U2             217      SCONN288_H44441003_PIP-SCONN,HA
PVDDQ_GHJ                J9U2             220      SCONN288_H44441003_PIP-SCONN,HA
PVDDQ_GHJ                J9U2             223      SCONN288_H44441003_PIP-SCONN,HA
PVDDQ_GHJ                J9U2             226      SCONN288_H44441003_PIP-SCONN,HA
PVDDQ_GHJ                J9U2             229      SCONN288_H44441003_PIP-SCONN,HA
PVDDQ_GHJ                J9U2             231      SCONN288_H44441003_PIP-SCONN,HA
PVDDQ_GHJ                J9U2             233      SCONN288_H44441003_PIP-SCONN,HA
PVDDQ_GHJ                J9U2             236      SCONN288_H44441003_PIP-SCONN,HA
PVDDQ_GHJ                L1F2             2        INDUCTOR_SM-0.12UH,IND,D92183-A
PVDDQ_GHJ                L1G1             2        INDUCTOR_SM-0.12UH,IND,D92183-A
PVDDQ_GHJ                R1F5             1        RES_0402-1.00K,1%,1/16W,CHIP,GA
PVDDQ_GHJ                R1G2             1        RES_0402-1.00K,1%,1/16W,CHIP,GA
PVDDQ_GHJ                R1G15            1        RES_0402-1.00K,1%,1/16W,CHIP,GA
PVDDQ_GHJ                R1G20            1        RES_0603-120.0,1%,1/10W,CHIP,GA
PVDDQ_GHJ                R3D21            1        RES_0402-64.9,1.0%,1/16W,CHIP,A
PVDDQ_GHJ                R6U6             1        RES_0402-0.0,5%,1/16W,CHIP,G21A
PVDDQ_GHJ                SH7U1            2        SHUNT_SH0201-EMPTY,N_A
PVDDQ_GHJ                U2D1             AD45     SKX_EXT_B_BGA1-IC,TBD
PVDDQ_GHJ                U2D1             AF55     SKX_EXT_B_BGA1-IC,TBD
PVDDQ_GHJ                U2D1             AF57     SKX_EXT_B_BGA1-IC,TBD
PVDDQ_GHJ                U2D1             AF59     SKX_EXT_B_BGA1-IC,TBD
PVDDQ_GHJ                U2D1             AF61     SKX_EXT_B_BGA1-IC,TBD
PVDDQ_GHJ                U2D1             AF63     SKX_EXT_B_BGA1-IC,TBD
PVDDQ_GHJ                U2D1             B47      SKX_EXT_B_BGA1-IC,TBD
PVDDQ_GHJ                U2D1             B49      SKX_EXT_B_BGA1-IC,TBD
PVDDQ_GHJ                U2D1             B53      SKX_EXT_B_BGA1-IC,TBD
PVDDQ_GHJ                U2D1             B59      SKX_EXT_B_BGA1-IC,TBD
PVDDQ_GHJ                U2D1             C46      SKX_EXT_B_BGA1-IC,TBD
PVDDQ_GHJ                U2D1             D45      SKX_EXT_B_BGA1-IC,TBD
PVDDQ_GHJ                U2D1             E46      SKX_EXT_B_BGA1-IC,TBD
PVDDQ_GHJ                U2D1             E48      SKX_EXT_B_BGA1-IC,TBD
PVDDQ_GHJ                U2D1             E50      SKX_EXT_B_BGA1-IC,TBD
PVDDQ_GHJ                U2D1             E52      SKX_EXT_B_BGA1-IC,TBD
PVDDQ_GHJ                U2D1             E54      SKX_EXT_B_BGA1-IC,TBD
PVDDQ_GHJ                U2D1             E56      SKX_EXT_B_BGA1-IC,TBD
PVDDQ_GHJ                U2D1             E58      SKX_EXT_B_BGA1-IC,TBD
PVDDQ_GHJ                U2D1             E60      SKX_EXT_B_BGA1-IC,TBD
PVDDQ_GHJ                U2D1             E62      SKX_EXT_B_BGA1-IC,TBD
PVDDQ_GHJ                U2D1             E64      SKX_EXT_B_BGA1-IC,TBD
PVDDQ_GHJ                U2D1             L46      SKX_EXT_B_BGA1-IC,TBD
PVDDQ_GHJ                U2D1             L48      SKX_EXT_B_BGA1-IC,TBD
PVDDQ_GHJ                U2D1             L50      SKX_EXT_B_BGA1-IC,TBD
PVDDQ_GHJ                U2D1             L52      SKX_EXT_B_BGA1-IC,TBD
PVDDQ_GHJ                U2D1             L54      SKX_EXT_B_BGA1-IC,TBD
PVDDQ_GHJ                U2D1             L56      SKX_EXT_B_BGA1-IC,TBD
PVDDQ_GHJ                U2D1             L58      SKX_EXT_B_BGA1-IC,TBD
PVDDQ_GHJ                U2D1             L60      SKX_EXT_B_BGA1-IC,TBD
PVDDQ_GHJ                U2D1             L62      SKX_EXT_B_BGA1-IC,TBD
PVDDQ_GHJ                U2D1             N64      SKX_EXT_B_BGA1-IC,TBD
PVDDQ_GHJ                U2D1             U46      SKX_EXT_B_BGA1-IC,TBD
PVDDQ_GHJ                U2D1             U48      SKX_EXT_B_BGA1-IC,TBD
PVDDQ_GHJ                U2D1             U50      SKX_EXT_B_BGA1-IC,TBD
PVDDQ_GHJ                U2D1             U52      SKX_EXT_B_BGA1-IC,TBD
PVDDQ_GHJ                U2D1             U54      SKX_EXT_B_BGA1-IC,TBD
PVDDQ_GHJ                U2D1             U56      SKX_EXT_B_BGA1-IC,TBD
PVDDQ_GHJ                U2D1             U58      SKX_EXT_B_BGA1-IC,TBD
PVDDQ_GHJ                U2D1             U60      SKX_EXT_B_BGA1-IC,TBD
PVDDQ_GHJ                U2D1             U62      SKX_EXT_B_BGA1-IC,TBD
PVDDQ_GHJ                U2D1             W64      SKX_EXT_B_BGA1-IC,TBD
PVDDQ_GHJ                U2D1             Y45      SKX_EXT_B_BGA1-IC,TBD
PVDDQ_GHJ                U2D1             Y47      SKX_EXT_B_BGA1-IC,TBD
PVDDQ_GHJ                U2D1             Y49      SKX_EXT_B_BGA1-IC,TBD
PVDDQ_GHJ                U2D1             Y51      SKX_EXT_B_BGA1-IC,TBD
PVDDQ_GHJ                U2D1             Y53      SKX_EXT_B_BGA1-IC,TBD
PVDDQ_GHJ                U2D1             Y55      SKX_EXT_B_BGA1-IC,TBD
PVDDQ_GHJ                U2D1             Y57      SKX_EXT_B_BGA1-IC,TBD
PVDDQ_GHJ                U2D1             Y59      SKX_EXT_B_BGA1-IC,TBD
PVDDQ_GHJ                U2D1             Y61      SKX_EXT_B_BGA1-IC,TBD
PVDDQ_GHJ                U2D1             Y63      SKX_EXT_B_BGA1-IC,TBD
PVDDQ_KLM                C1A1             1        CAP_0805LF-22UF,4V,20%,X6S,C95A
PVDDQ_KLM                C1A12            1        CAP_0805LF-22UF,4V,20%,X6S,C95A
PVDDQ_KLM                C2A1             1        CAP_A_0603V-22.0UF,4V,20%,X6S,A
PVDDQ_KLM                C2A2             1        CAP_A_0603V-22.0UF,4V,20%,X6S,A
PVDDQ_KLM                C2A3             1        CAP_A_0603V-22.0UF,4V,20%,X6S,A
PVDDQ_KLM                C2A4             1        CAP_A_0603V-22.0UF,4V,20%,X6S,A
PVDDQ_KLM                C2A5             1        CAP_A_0603V-47UF,4V,20%,X5R,60A
PVDDQ_KLM                C2A6             1        CAP_A_0603V-22.0UF,4V,20%,X6S,A
PVDDQ_KLM                C2A7             1        CAP_A_0603V-22.0UF,4V,20%,X6S,A
PVDDQ_KLM                C2A8             1        CAP_0805-100UF,4V,20%,X5R,6024A
PVDDQ_KLM                C2A9             1        CAP_A_0603V-22.0UF,4V,20%,X6S,A
PVDDQ_KLM                C2A10            1        CAP_A_0603V-22.0UF,4V,20%,X6S,A
PVDDQ_KLM                C2A11            1        CAP_A_0603V-22.0UF,4V,20%,X6S,A
PVDDQ_KLM                C2A12            1        CAP_A_0603V-22.0UF,4V,20%,X6S,A
PVDDQ_KLM                C2A13            1        CAP_A_0603V-22.0UF,4V,20%,X6S,A
PVDDQ_KLM                C2A14            1        CAP_A_0603V-22.0UF,4V,20%,X6S,A
PVDDQ_KLM                C2A15            1        CAP_A_0603V-22.0UF,4V,20%,X6S,A
PVDDQ_KLM                C2A16            1        CAP_0805-100UF,4V,20%,X5R,6024A
PVDDQ_KLM                C2B1             1        CAP_A_0603V-47UF,4V,20%,X5R,60A
PVDDQ_KLM                C2B2             1        CAP_A_0603V-47UF,4V,20%,X5R,60A
PVDDQ_KLM                C2D4             1        CAP_0603LF-10UF,4V,20%,X6S,E15A
PVDDQ_KLM                C2D5             1        CAP_0603LF-10UF,4V,20%,X6S,E15A
PVDDQ_KLM                C2D6             1        CAP_0603LF-10UF,4V,20%,X6S,E15A
PVDDQ_KLM                C2D7             1        CAP_0603LF-10UF,4V,20%,X6S,E15A
PVDDQ_KLM                C3A1             1        CAP_A_0603V-22.0UF,4V,20%,X6S,A
PVDDQ_KLM                C3A2             1        CAP_A_0603V-22.0UF,4V,20%,X6S,A
PVDDQ_KLM                C3A5             1        CAP_A_0603V-22.0UF,4V,20%,X6S,A
PVDDQ_KLM                C3A6             1        CAP_A_0603V-22.0UF,4V,20%,X6S,A
PVDDQ_KLM                C4A15            1        CAP_0603LF-10UF,4V,20%,X6S,E15A
PVDDQ_KLM                C5G97            1        CAP_A_0603V-22.0UF,4V,20%,X6S,A
PVDDQ_KLM                C5G98            1        CAP_A_0603V-22.0UF,4V,20%,X6S,A
PVDDQ_KLM                C5G99            1        CAP_A_0603V-22.0UF,4V,20%,X6S,A
PVDDQ_KLM                C5G100           1        CAP_A_0603V-22.0UF,4V,20%,X6S,A
PVDDQ_KLM                C5G101           1        CAP_A_0603V-22.0UF,4V,20%,X6S,A
PVDDQ_KLM                C5G102           1        CAP_A_0603V-22.0UF,4V,20%,X6S,A
PVDDQ_KLM                C5G103           1        CAP_A_0603V-22.0UF,4V,20%,X6S,A
PVDDQ_KLM                C5G104           1        CAP_A_0603V-22.0UF,4V,20%,X6S,A
PVDDQ_KLM                C5G105           1        CAP_A_0603V-22.0UF,4V,20%,X6S,A
PVDDQ_KLM                C5G106           1        CAP_A_0603V-22.0UF,4V,20%,X6S,A
PVDDQ_KLM                C5G107           1        CAP_A_0603V-22.0UF,4V,20%,X6S,A
PVDDQ_KLM                C5G108           1        CAP_A_0603V-22.0UF,4V,20%,X6S,A
PVDDQ_KLM                C5G109           1        CAP_A_0603V-22.0UF,4V,20%,X6S,A
PVDDQ_KLM                C5G110           1        CAP_A_0603V-22.0UF,4V,20%,X6S,A
PVDDQ_KLM                C5G111           1        CAP_A_0603V-22.0UF,4V,20%,X6S,A
PVDDQ_KLM                C5G112           1        CAP_A_0603V-22.0UF,4V,20%,X6S,A
PVDDQ_KLM                C5G113           1        CAP_A_0603V-22.0UF,4V,20%,X6S,A
PVDDQ_KLM                C5G114           1        CAP_A_0603V-22.0UF,4V,20%,X6S,A
PVDDQ_KLM                C5G115           1        CAP_0805-100UF,4V,20%,X5R,6024A
PVDDQ_KLM                C5G116           1        CAP_0805-100UF,4V,20%,X5R,6024A
PVDDQ_KLM                C6L5             1        CAP_0603LF-10UF,4V,20%,X6S,E15A
PVDDQ_KLM                C7L1             1        CAP_0805-100UF,4V,20%,X5R,6024A
PVDDQ_KLM                C7L4             1        CAP_A_0603V-22.0UF,4V,20%,X6S,A
PVDDQ_KLM                C7L5             1        CAP_A_0603V-22.0UF,4V,20%,X6S,A
PVDDQ_KLM                C7M1             1        CAP_A_0603V-22.0UF,4V,20%,X6S,A
PVDDQ_KLM                C7M2             1        CAP_A_0603V-22.0UF,4V,20%,X6S,A
PVDDQ_KLM                C7M5             1        CAP_A_0603V-47UF,4V,20%,X5R,60A
PVDDQ_KLM                C8L1             1        CAP_0805-100UF,4V,20%,X5R,6024A
PVDDQ_KLM                C8L2             1        CAP_0805-100UF,4V,20%,X5R,6024A
PVDDQ_KLM                C8L5             1        CAP_A_0603V-22.0UF,4V,20%,X6S,A
PVDDQ_KLM                C8L6             1        CAP_A_0603V-22.0UF,4V,20%,X6S,A
PVDDQ_KLM                C8L7             1        CAP_A_0603V-22.0UF,4V,20%,X6S,A
PVDDQ_KLM                C8L8             1        CAP_A_0603V-22.0UF,4V,20%,X6S,A
PVDDQ_KLM                C8L9             1        CAP_A_0603V-22.0UF,4V,20%,X6S,A
PVDDQ_KLM                C8L10            1        CAP_A_0603V-22.0UF,4V,20%,X6S,A
PVDDQ_KLM                C8L11            1        CAP_0805-100UF,4V,20%,X5R,6024A
PVDDQ_KLM                C8L12            1        CAP_A_0603V-47UF,4V,20%,X5R,60A
PVDDQ_KLM                C8M1             1        CAP_A_0603V-22.0UF,4V,20%,X6S,A
PVDDQ_KLM                C8M2             1        CAP_A_0603V-47UF,4V,20%,X5R,60A
PVDDQ_KLM                C8M3             1        CAP_A_0603V-22.0UF,4V,20%,X6S,A
PVDDQ_KLM                C8M4             1        CAP_A_0603V-22.0UF,4V,20%,X6S,A
PVDDQ_KLM                C8M5             1        CAP_A_0603V-22.0UF,4V,20%,X6S,A
PVDDQ_KLM                C8M6             1        CAP_A_0603V-22.0UF,4V,20%,X6S,A
PVDDQ_KLM                C8M7             1        CAP_0805-100UF,4V,20%,X5R,6024A
PVDDQ_KLM                C8M8             1        CAP_A_0603V-47UF,4V,20%,X5R,60A
PVDDQ_KLM                C8M9             1        CAP_A_0603V-47UF,4V,20%,X5R,60A
PVDDQ_KLM                C8M10            1        CAP_A_0603V-47UF,4V,20%,X5R,60A
PVDDQ_KLM                C8M11            1        CAP_0805-100UF,4V,20%,X5R,6024A
PVDDQ_KLM                C8P1             1        CAP_0805LF-22UF,4V,20%,X6S,C95A
PVDDQ_KLM                C8P2             1        CAP_0805LF-22UF,4V,20%,X6S,C95A
PVDDQ_KLM                C9L2             1        CAPP_3018-470UF,2.5V,20%,ALUM,A
PVDDQ_KLM                C9L4             1        CAPP_3018-470UF,2.5V,20%,ALUM,A
PVDDQ_KLM                C9L9             1        CAPP_3018-470UF,2.5V,20%,ALUM,A
PVDDQ_KLM                C9L12            1        CAPP_3018-470UF,2.5V,20%,ALUM,A
PVDDQ_KLM                EU1A1            1        IR354XX_SM-IR35411,IC,H73688-0A
PVDDQ_KLM                EU1A2            1        IR354XX_SM-IR35411,IC,H73688-0A
PVDDQ_KLM                EU4A2            10       MIC5166_DFN-IC,H55101-001
PVDDQ_KLM                J1A1             59       SCONN288_H44441004_PIP-SCONN,HA
PVDDQ_KLM                J1A1             61       SCONN288_H44441004_PIP-SCONN,HA
PVDDQ_KLM                J1A1             64       SCONN288_H44441004_PIP-SCONN,HA
PVDDQ_KLM                J1A1             67       SCONN288_H44441004_PIP-SCONN,HA
PVDDQ_KLM                J1A1             70       SCONN288_H44441004_PIP-SCONN,HA
PVDDQ_KLM                J1A1             73       SCONN288_H44441004_PIP-SCONN,HA
PVDDQ_KLM                J1A1             76       SCONN288_H44441004_PIP-SCONN,HA
PVDDQ_KLM                J1A1             80       SCONN288_H44441004_PIP-SCONN,HA
PVDDQ_KLM                J1A1             83       SCONN288_H44441004_PIP-SCONN,HA
PVDDQ_KLM                J1A1             85       SCONN288_H44441004_PIP-SCONN,HA
PVDDQ_KLM                J1A1             88       SCONN288_H44441004_PIP-SCONN,HA
PVDDQ_KLM                J1A1             90       SCONN288_H44441004_PIP-SCONN,HA
PVDDQ_KLM                J1A1             92       SCONN288_H44441004_PIP-SCONN,HA
PVDDQ_KLM                J1A1             204      SCONN288_H44441004_PIP-SCONN,HA
PVDDQ_KLM                J1A1             206      SCONN288_H44441004_PIP-SCONN,HA
PVDDQ_KLM                J1A1             209      SCONN288_H44441004_PIP-SCONN,HA
PVDDQ_KLM                J1A1             212      SCONN288_H44441004_PIP-SCONN,HA
PVDDQ_KLM                J1A1             215      SCONN288_H44441004_PIP-SCONN,HA
PVDDQ_KLM                J1A1             217      SCONN288_H44441004_PIP-SCONN,HA
PVDDQ_KLM                J1A1             220      SCONN288_H44441004_PIP-SCONN,HA
PVDDQ_KLM                J1A1             223      SCONN288_H44441004_PIP-SCONN,HA
PVDDQ_KLM                J1A1             226      SCONN288_H44441004_PIP-SCONN,HA
PVDDQ_KLM                J1A1             229      SCONN288_H44441004_PIP-SCONN,HA
PVDDQ_KLM                J1A1             231      SCONN288_H44441004_PIP-SCONN,HA
PVDDQ_KLM                J1A1             233      SCONN288_H44441004_PIP-SCONN,HA
PVDDQ_KLM                J1A1             236      SCONN288_H44441004_PIP-SCONN,HA
PVDDQ_KLM                J1A2             59       SCONN288_H44441004_PIP-SCONN,HA
PVDDQ_KLM                J1A2             61       SCONN288_H44441004_PIP-SCONN,HA
PVDDQ_KLM                J1A2             64       SCONN288_H44441004_PIP-SCONN,HA
PVDDQ_KLM                J1A2             67       SCONN288_H44441004_PIP-SCONN,HA
PVDDQ_KLM                J1A2             70       SCONN288_H44441004_PIP-SCONN,HA
PVDDQ_KLM                J1A2             73       SCONN288_H44441004_PIP-SCONN,HA
PVDDQ_KLM                J1A2             76       SCONN288_H44441004_PIP-SCONN,HA
PVDDQ_KLM                J1A2             80       SCONN288_H44441004_PIP-SCONN,HA
PVDDQ_KLM                J1A2             83       SCONN288_H44441004_PIP-SCONN,HA
PVDDQ_KLM                J1A2             85       SCONN288_H44441004_PIP-SCONN,HA
PVDDQ_KLM                J1A2             88       SCONN288_H44441004_PIP-SCONN,HA
PVDDQ_KLM                J1A2             90       SCONN288_H44441004_PIP-SCONN,HA
PVDDQ_KLM                J1A2             92       SCONN288_H44441004_PIP-SCONN,HA
PVDDQ_KLM                J1A2             204      SCONN288_H44441004_PIP-SCONN,HA
PVDDQ_KLM                J1A2             206      SCONN288_H44441004_PIP-SCONN,HA
PVDDQ_KLM                J1A2             209      SCONN288_H44441004_PIP-SCONN,HA
PVDDQ_KLM                J1A2             212      SCONN288_H44441004_PIP-SCONN,HA
PVDDQ_KLM                J1A2             215      SCONN288_H44441004_PIP-SCONN,HA
PVDDQ_KLM                J1A2             217      SCONN288_H44441004_PIP-SCONN,HA
PVDDQ_KLM                J1A2             220      SCONN288_H44441004_PIP-SCONN,HA
PVDDQ_KLM                J1A2             223      SCONN288_H44441004_PIP-SCONN,HA
PVDDQ_KLM                J1A2             226      SCONN288_H44441004_PIP-SCONN,HA
PVDDQ_KLM                J1A2             229      SCONN288_H44441004_PIP-SCONN,HA
PVDDQ_KLM                J1A2             231      SCONN288_H44441004_PIP-SCONN,HA
PVDDQ_KLM                J1A2             233      SCONN288_H44441004_PIP-SCONN,HA
PVDDQ_KLM                J1A2             236      SCONN288_H44441004_PIP-SCONN,HA
PVDDQ_KLM                J1B1             59       SCONN288_H44441004_PIP-SCONN,HA
PVDDQ_KLM                J1B1             61       SCONN288_H44441004_PIP-SCONN,HA
PVDDQ_KLM                J1B1             64       SCONN288_H44441004_PIP-SCONN,HA
PVDDQ_KLM                J1B1             67       SCONN288_H44441004_PIP-SCONN,HA
PVDDQ_KLM                J1B1             70       SCONN288_H44441004_PIP-SCONN,HA
PVDDQ_KLM                J1B1             73       SCONN288_H44441004_PIP-SCONN,HA
PVDDQ_KLM                J1B1             76       SCONN288_H44441004_PIP-SCONN,HA
PVDDQ_KLM                J1B1             80       SCONN288_H44441004_PIP-SCONN,HA
PVDDQ_KLM                J1B1             83       SCONN288_H44441004_PIP-SCONN,HA
PVDDQ_KLM                J1B1             85       SCONN288_H44441004_PIP-SCONN,HA
PVDDQ_KLM                J1B1             88       SCONN288_H44441004_PIP-SCONN,HA
PVDDQ_KLM                J1B1             90       SCONN288_H44441004_PIP-SCONN,HA
PVDDQ_KLM                J1B1             92       SCONN288_H44441004_PIP-SCONN,HA
PVDDQ_KLM                J1B1             204      SCONN288_H44441004_PIP-SCONN,HA
PVDDQ_KLM                J1B1             206      SCONN288_H44441004_PIP-SCONN,HA
PVDDQ_KLM                J1B1             209      SCONN288_H44441004_PIP-SCONN,HA
PVDDQ_KLM                J1B1             212      SCONN288_H44441004_PIP-SCONN,HA
PVDDQ_KLM                J1B1             215      SCONN288_H44441004_PIP-SCONN,HA
PVDDQ_KLM                J1B1             217      SCONN288_H44441004_PIP-SCONN,HA
PVDDQ_KLM                J1B1             220      SCONN288_H44441004_PIP-SCONN,HA
PVDDQ_KLM                J1B1             223      SCONN288_H44441004_PIP-SCONN,HA
PVDDQ_KLM                J1B1             226      SCONN288_H44441004_PIP-SCONN,HA
PVDDQ_KLM                J1B1             229      SCONN288_H44441004_PIP-SCONN,HA
PVDDQ_KLM                J1B1             231      SCONN288_H44441004_PIP-SCONN,HA
PVDDQ_KLM                J1B1             233      SCONN288_H44441004_PIP-SCONN,HA
PVDDQ_KLM                J1B1             236      SCONN288_H44441004_PIP-SCONN,HA
PVDDQ_KLM                J9L1             59       SCONN288_H44441003_PIP-SCONN,HA
PVDDQ_KLM                J9L1             61       SCONN288_H44441003_PIP-SCONN,HA
PVDDQ_KLM                J9L1             64       SCONN288_H44441003_PIP-SCONN,HA
PVDDQ_KLM                J9L1             67       SCONN288_H44441003_PIP-SCONN,HA
PVDDQ_KLM                J9L1             70       SCONN288_H44441003_PIP-SCONN,HA
PVDDQ_KLM                J9L1             73       SCONN288_H44441003_PIP-SCONN,HA
PVDDQ_KLM                J9L1             76       SCONN288_H44441003_PIP-SCONN,HA
PVDDQ_KLM                J9L1             80       SCONN288_H44441003_PIP-SCONN,HA
PVDDQ_KLM                J9L1             83       SCONN288_H44441003_PIP-SCONN,HA
PVDDQ_KLM                J9L1             85       SCONN288_H44441003_PIP-SCONN,HA
PVDDQ_KLM                J9L1             88       SCONN288_H44441003_PIP-SCONN,HA
PVDDQ_KLM                J9L1             90       SCONN288_H44441003_PIP-SCONN,HA
PVDDQ_KLM                J9L1             92       SCONN288_H44441003_PIP-SCONN,HA
PVDDQ_KLM                J9L1             204      SCONN288_H44441003_PIP-SCONN,HA
PVDDQ_KLM                J9L1             206      SCONN288_H44441003_PIP-SCONN,HA
PVDDQ_KLM                J9L1             209      SCONN288_H44441003_PIP-SCONN,HA
PVDDQ_KLM                J9L1             212      SCONN288_H44441003_PIP-SCONN,HA
PVDDQ_KLM                J9L1             215      SCONN288_H44441003_PIP-SCONN,HA
PVDDQ_KLM                J9L1             217      SCONN288_H44441003_PIP-SCONN,HA
PVDDQ_KLM                J9L1             220      SCONN288_H44441003_PIP-SCONN,HA
PVDDQ_KLM                J9L1             223      SCONN288_H44441003_PIP-SCONN,HA
PVDDQ_KLM                J9L1             226      SCONN288_H44441003_PIP-SCONN,HA
PVDDQ_KLM                J9L1             229      SCONN288_H44441003_PIP-SCONN,HA
PVDDQ_KLM                J9L1             231      SCONN288_H44441003_PIP-SCONN,HA
PVDDQ_KLM                J9L1             233      SCONN288_H44441003_PIP-SCONN,HA
PVDDQ_KLM                J9L1             236      SCONN288_H44441003_PIP-SCONN,HA
PVDDQ_KLM                J9L2             59       SCONN288_H44441003_PIP-SCONN,HA
PVDDQ_KLM                J9L2             61       SCONN288_H44441003_PIP-SCONN,HA
PVDDQ_KLM                J9L2             64       SCONN288_H44441003_PIP-SCONN,HA
PVDDQ_KLM                J9L2             67       SCONN288_H44441003_PIP-SCONN,HA
PVDDQ_KLM                J9L2             70       SCONN288_H44441003_PIP-SCONN,HA
PVDDQ_KLM                J9L2             73       SCONN288_H44441003_PIP-SCONN,HA
PVDDQ_KLM                J9L2             76       SCONN288_H44441003_PIP-SCONN,HA
PVDDQ_KLM                J9L2             80       SCONN288_H44441003_PIP-SCONN,HA
PVDDQ_KLM                J9L2             83       SCONN288_H44441003_PIP-SCONN,HA
PVDDQ_KLM                J9L2             85       SCONN288_H44441003_PIP-SCONN,HA
PVDDQ_KLM                J9L2             88       SCONN288_H44441003_PIP-SCONN,HA
PVDDQ_KLM                J9L2             90       SCONN288_H44441003_PIP-SCONN,HA
PVDDQ_KLM                J9L2             92       SCONN288_H44441003_PIP-SCONN,HA
PVDDQ_KLM                J9L2             204      SCONN288_H44441003_PIP-SCONN,HA
PVDDQ_KLM                J9L2             206      SCONN288_H44441003_PIP-SCONN,HA
PVDDQ_KLM                J9L2             209      SCONN288_H44441003_PIP-SCONN,HA
PVDDQ_KLM                J9L2             212      SCONN288_H44441003_PIP-SCONN,HA
PVDDQ_KLM                J9L2             215      SCONN288_H44441003_PIP-SCONN,HA
PVDDQ_KLM                J9L2             217      SCONN288_H44441003_PIP-SCONN,HA
PVDDQ_KLM                J9L2             220      SCONN288_H44441003_PIP-SCONN,HA
PVDDQ_KLM                J9L2             223      SCONN288_H44441003_PIP-SCONN,HA
PVDDQ_KLM                J9L2             226      SCONN288_H44441003_PIP-SCONN,HA
PVDDQ_KLM                J9L2             229      SCONN288_H44441003_PIP-SCONN,HA
PVDDQ_KLM                J9L2             231      SCONN288_H44441003_PIP-SCONN,HA
PVDDQ_KLM                J9L2             233      SCONN288_H44441003_PIP-SCONN,HA
PVDDQ_KLM                J9L2             236      SCONN288_H44441003_PIP-SCONN,HA
PVDDQ_KLM                J9M1             59       SCONN288_H44441003_PIP-SCONN,HA
PVDDQ_KLM                J9M1             61       SCONN288_H44441003_PIP-SCONN,HA
PVDDQ_KLM                J9M1             64       SCONN288_H44441003_PIP-SCONN,HA
PVDDQ_KLM                J9M1             67       SCONN288_H44441003_PIP-SCONN,HA
PVDDQ_KLM                J9M1             70       SCONN288_H44441003_PIP-SCONN,HA
PVDDQ_KLM                J9M1             73       SCONN288_H44441003_PIP-SCONN,HA
PVDDQ_KLM                J9M1             76       SCONN288_H44441003_PIP-SCONN,HA
PVDDQ_KLM                J9M1             80       SCONN288_H44441003_PIP-SCONN,HA
PVDDQ_KLM                J9M1             83       SCONN288_H44441003_PIP-SCONN,HA
PVDDQ_KLM                J9M1             85       SCONN288_H44441003_PIP-SCONN,HA
PVDDQ_KLM                J9M1             88       SCONN288_H44441003_PIP-SCONN,HA
PVDDQ_KLM                J9M1             90       SCONN288_H44441003_PIP-SCONN,HA
PVDDQ_KLM                J9M1             92       SCONN288_H44441003_PIP-SCONN,HA
PVDDQ_KLM                J9M1             204      SCONN288_H44441003_PIP-SCONN,HA
PVDDQ_KLM                J9M1             206      SCONN288_H44441003_PIP-SCONN,HA
PVDDQ_KLM                J9M1             209      SCONN288_H44441003_PIP-SCONN,HA
PVDDQ_KLM                J9M1             212      SCONN288_H44441003_PIP-SCONN,HA
PVDDQ_KLM                J9M1             215      SCONN288_H44441003_PIP-SCONN,HA
PVDDQ_KLM                J9M1             217      SCONN288_H44441003_PIP-SCONN,HA
PVDDQ_KLM                J9M1             220      SCONN288_H44441003_PIP-SCONN,HA
PVDDQ_KLM                J9M1             223      SCONN288_H44441003_PIP-SCONN,HA
PVDDQ_KLM                J9M1             226      SCONN288_H44441003_PIP-SCONN,HA
PVDDQ_KLM                J9M1             229      SCONN288_H44441003_PIP-SCONN,HA
PVDDQ_KLM                J9M1             231      SCONN288_H44441003_PIP-SCONN,HA
PVDDQ_KLM                J9M1             233      SCONN288_H44441003_PIP-SCONN,HA
PVDDQ_KLM                J9M1             236      SCONN288_H44441003_PIP-SCONN,HA
PVDDQ_KLM                L1A1             2        INDUCTOR_SM-0.12UH,IND,D92183-A
PVDDQ_KLM                L1A2             2        INDUCTOR_SM-0.12UH,IND,D92183-A
PVDDQ_KLM                R1A1             1        RES_0603-120.0,1%,1/10W,CHIP,GA
PVDDQ_KLM                R6L6             1        RES_0402-0.0,5%,1/16W,CHIP,G21A
PVDDQ_KLM                R7M9             1        RES_0402-64.9,1.0%,1/16W,CHIP,A
PVDDQ_KLM                R9L2             1        RES_0402-1.00K,1%,1/16W,CHIP,GA
PVDDQ_KLM                R9L7             1        RES_0402-1.00K,1%,1/16W,CHIP,GA
PVDDQ_KLM                R9M1             1        RES_0402-1.00K,1%,1/16W,CHIP,GA
PVDDQ_KLM                SH7L2            2        SHUNT_SH0201-EMPTY,N_A
PVDDQ_KLM                U2D1             DB53     SKX_EXT_B_BGA1-IC,TBD
PVDDQ_KLM                U2D1             DB55     SKX_EXT_B_BGA1-IC,TBD
PVDDQ_KLM                U2D1             DB57     SKX_EXT_B_BGA1-IC,TBD
PVDDQ_KLM                U2D1             DB59     SKX_EXT_B_BGA1-IC,TBD
PVDDQ_KLM                U2D1             DB61     SKX_EXT_B_BGA1-IC,TBD
PVDDQ_KLM                U2D1             DB63     SKX_EXT_B_BGA1-IC,TBD
PVDDQ_KLM                U2D1             DD45     SKX_EXT_B_BGA1-IC,TBD
PVDDQ_KLM                U2D1             DH45     SKX_EXT_B_BGA1-IC,TBD
PVDDQ_KLM                U2D1             DH47     SKX_EXT_B_BGA1-IC,TBD
PVDDQ_KLM                U2D1             DH49     SKX_EXT_B_BGA1-IC,TBD
PVDDQ_KLM                U2D1             DH51     SKX_EXT_B_BGA1-IC,TBD
PVDDQ_KLM                U2D1             DH53     SKX_EXT_B_BGA1-IC,TBD
PVDDQ_KLM                U2D1             DH55     SKX_EXT_B_BGA1-IC,TBD
PVDDQ_KLM                U2D1             DH57     SKX_EXT_B_BGA1-IC,TBD
PVDDQ_KLM                U2D1             DH59     SKX_EXT_B_BGA1-IC,TBD
PVDDQ_KLM                U2D1             DH61     SKX_EXT_B_BGA1-IC,TBD
PVDDQ_KLM                U2D1             DH63     SKX_EXT_B_BGA1-IC,TBD
PVDDQ_KLM                U2D1             DJ64     SKX_EXT_B_BGA1-IC,TBD
PVDDQ_KLM                U2D1             DL46     SKX_EXT_B_BGA1-IC,TBD
PVDDQ_KLM                U2D1             DL48     SKX_EXT_B_BGA1-IC,TBD
PVDDQ_KLM                U2D1             DL50     SKX_EXT_B_BGA1-IC,TBD
PVDDQ_KLM                U2D1             DL52     SKX_EXT_B_BGA1-IC,TBD
PVDDQ_KLM                U2D1             DL54     SKX_EXT_B_BGA1-IC,TBD
PVDDQ_KLM                U2D1             DL56     SKX_EXT_B_BGA1-IC,TBD
PVDDQ_KLM                U2D1             DL58     SKX_EXT_B_BGA1-IC,TBD
PVDDQ_KLM                U2D1             DL60     SKX_EXT_B_BGA1-IC,TBD
PVDDQ_KLM                U2D1             DL62     SKX_EXT_B_BGA1-IC,TBD
PVDDQ_KLM                U2D1             DU46     SKX_EXT_B_BGA1-IC,TBD
PVDDQ_KLM                U2D1             DU48     SKX_EXT_B_BGA1-IC,TBD
PVDDQ_KLM                U2D1             DU50     SKX_EXT_B_BGA1-IC,TBD
PVDDQ_KLM                U2D1             DU52     SKX_EXT_B_BGA1-IC,TBD
PVDDQ_KLM                U2D1             DU54     SKX_EXT_B_BGA1-IC,TBD
PVDDQ_KLM                U2D1             DU56     SKX_EXT_B_BGA1-IC,TBD
PVDDQ_KLM                U2D1             DU58     SKX_EXT_B_BGA1-IC,TBD
PVDDQ_KLM                U2D1             DU60     SKX_EXT_B_BGA1-IC,TBD
PVDDQ_KLM                U2D1             DU62     SKX_EXT_B_BGA1-IC,TBD
PVDDQ_KLM                U2D1             DU64     SKX_EXT_B_BGA1-IC,TBD
PVDDQ_KLM                U2D1             EC46     SKX_EXT_B_BGA1-IC,TBD
PVDDQ_KLM                U2D1             EC48     SKX_EXT_B_BGA1-IC,TBD
PVDDQ_KLM                U2D1             EC50     SKX_EXT_B_BGA1-IC,TBD
PVDDQ_KLM                U2D1             EC52     SKX_EXT_B_BGA1-IC,TBD
PVDDQ_KLM                U2D1             EC54     SKX_EXT_B_BGA1-IC,TBD
PVDDQ_KLM                U2D1             EC56     SKX_EXT_B_BGA1-IC,TBD
PVDDQ_KLM                U2D1             EC58     SKX_EXT_B_BGA1-IC,TBD
PVDDQ_KLM                U2D1             EC60     SKX_EXT_B_BGA1-IC,TBD
PVDDQ_KLM                U2D1             EC62     SKX_EXT_B_BGA1-IC,TBD
PVDDQ_KLM                U2D1             EE44     SKX_EXT_B_BGA1-IC,TBD
PVDDQ_KLM                U2D1             EF45     SKX_EXT_B_BGA1-IC,TBD
PVDDQ_KLM                U2D1             EF49     SKX_EXT_B_BGA1-IC,TBD
PVDDQ_KLM                U2D1             EF53     SKX_EXT_B_BGA1-IC,TBD
PVDDQ_KLM                U2D1             EF59     SKX_EXT_B_BGA1-IC,TBD
PVNN_PCH_STBY            C2N3             1        CAP_A_0402V-1.0UF,6.3V,10%,X6SA
PVNN_PCH_STBY            C2N4             1        CAP_A_0402V-1.0UF,6.3V,10%,X6SA
PVNN_PCH_STBY            C2N9             1        CAP_A_0402V-1.0UF,6.3V,10%,X6SA
PVNN_PCH_STBY            C2N11            1        CAP_A_0402V-1.0UF,6.3V,10%,X6SA
PVNN_PCH_STBY            C2N12            1        CAP_A_0402V-1.0UF,6.3V,10%,X6SA
PVNN_PCH_STBY            C3L18            1        CAPP_SM-470UF,2V,20%,ALUM,6990A
PVNN_PCH_STBY            C3L20            1        CAPP_SM-470UF,2V,20%,ALUM,6990A
PVNN_PCH_STBY            C3L21            1        CAPP_SM-470UF,2V,20%,ALUM,6990A
PVNN_PCH_STBY            C3L22            1        CAP_A_0603V-22.0UF,4V,20%,X6S,A
PVNN_PCH_STBY            C3L23            1        CAP_A_0603V-22.0UF,4V,20%,X6S,A
PVNN_PCH_STBY            C3L24            1        CAP_A_0603V-22.0UF,4V,20%,X6S,A
PVNN_PCH_STBY            C3L25            1        CAP_A_0603V-22.0UF,4V,20%,X6S,A
PVNN_PCH_STBY            C3L26            1        CAP_A_0603V-22.0UF,4V,20%,X6S,A
PVNN_PCH_STBY            C3L27            1        CAP_A_0603V-22.0UF,4V,20%,X6S,A
PVNN_PCH_STBY            C3M6             1        CAP_A_0603V-22.0UF,4V,20%,X6S,A
PVNN_PCH_STBY            C3M7             1        CAP_A_0603V-22.0UF,4V,20%,X6S,A
PVNN_PCH_STBY            C3N1             1        CAP_A_0402V-1.0UF,6.3V,10%,X6SA
PVNN_PCH_STBY            C3N2             1        CAP_A_0402V-1.0UF,6.3V,10%,X6SA
PVNN_PCH_STBY            C3N3             1        CAP_A_0402V-1.0UF,6.3V,10%,X6SA
PVNN_PCH_STBY            C3N4             1        CAP_A_0402V-1.0UF,6.3V,10%,X6SA
PVNN_PCH_STBY            C3N5             1        CAP_A_0402V-1.0UF,6.3V,10%,X6SA
PVNN_PCH_STBY            C3N6             1        CAP_A_0402V-1.0UF,6.3V,10%,X6SA
PVNN_PCH_STBY            C3N7             1        CAP_A_0402V-1.0UF,6.3V,10%,X6SA
PVNN_PCH_STBY            C3N10            1        CAP_A_0603V-22.0UF,4V,20%,X6S,A
PVNN_PCH_STBY            C3N11            1        CAP_A_0603V-22.0UF,4V,20%,X6S,A
PVNN_PCH_STBY            C3N12            1        CAP_A_0603V-22.0UF,4V,20%,X6S,A
PVNN_PCH_STBY            C3N15            1        CAP_A_0402V-1.0UF,6.3V,10%,X6SA
PVNN_PCH_STBY            C3N16            1        CAP_A_0402V-1.0UF,6.3V,10%,X6SA
PVNN_PCH_STBY            C3N17            1        CAP_A_0402V-1.0UF,6.3V,10%,X6SA
PVNN_PCH_STBY            C3N18            1        CAP_A_0402V-1.0UF,6.3V,10%,X6SA
PVNN_PCH_STBY            C3N19            1        CAP_A_0402V-1.0UF,6.3V,10%,X6SA
PVNN_PCH_STBY            C3N20            1        CAP_A_0402V-1.0UF,6.3V,10%,X6SA
PVNN_PCH_STBY            C3N24            1        CAP_A_0603V-22.0UF,4V,20%,X6S,A
PVNN_PCH_STBY            C3N27            1        CAP_A_0603V-22.0UF,4V,20%,X6S,A
PVNN_PCH_STBY            C3N28            1        CAP_A_0603V-22.0UF,4V,20%,X6S,A
PVNN_PCH_STBY            C3N30            1        CAP_A_0603V-22.0UF,4V,20%,X6S,A
PVNN_PCH_STBY            C3N31            1        CAP_A_0603V-22.0UF,4V,20%,X6S,A
PVNN_PCH_STBY            C7A27            1        CAPP_SM-470UF,2V,20%,ALUM,6990A
PVNN_PCH_STBY            C7A30            1        CAP_0805LF-22UF,4V,20%,X6S,C95A
PVNN_PCH_STBY            C7A31            1        CAP_0805-47UF,4V,20%,X6S,C9533A
PVNN_PCH_STBY            C7A32            1        CAP_0805-47UF,4V,20%,X6S,C9533A
PVNN_PCH_STBY            C7A33            1        CAP_0805-47UF,4V,20%,X6S,C9533A
PVNN_PCH_STBY            C7A36            1        CAP_A_0603V-22.0UF,4V,20%,X6S,A
PVNN_PCH_STBY            C7B4             1        CAP_0805-47UF,4V,20%,X6S,C9533A
PVNN_PCH_STBY            C7C9             1        CAP_A_0603V-22.0UF,4V,20%,X6S,A
PVNN_PCH_STBY            EU7A3            1        IR354XX_SM-IR35412,IC,H73684-0A
PVNN_PCH_STBY            FB1U4            2        FERRITE_SMLF-30,FB,693286-021
PVNN_PCH_STBY            L7A2             2        INDUCTOR_SM-0.3UH,IND,D92183-0A
PVNN_PCH_STBY            R7A13            2        RES_0402-100.0,1%,1/16W,CHIP,GA
PVNN_PCH_STBY            U7C1             AA29     LBG_CORE_QAT_EXT_D_BGA1-IC,H91A
PVNN_PCH_STBY            U7C1             AA30     LBG_CORE_QAT_EXT_D_BGA1-IC,H91A
PVNN_PCH_STBY            U7C1             AA32     LBG_CORE_QAT_EXT_D_BGA1-IC,H91A
PVNN_PCH_STBY            U7C1             AA34     LBG_CORE_QAT_EXT_D_BGA1-IC,H91A
PVNN_PCH_STBY            U7C1             AA36     LBG_CORE_QAT_EXT_D_BGA1-IC,H91A
PVNN_PCH_STBY            U7C1             AA37     LBG_CORE_QAT_EXT_D_BGA1-IC,H91A
PVNN_PCH_STBY            U7C1             AA39     LBG_CORE_QAT_EXT_D_BGA1-IC,H91A
PVNN_PCH_STBY            U7C1             AA41     LBG_CORE_QAT_EXT_D_BGA1-IC,H91A
PVNN_PCH_STBY            U7C1             AC29     LBG_CORE_QAT_EXT_D_BGA1-IC,H91A
PVNN_PCH_STBY            U7C1             AC30     LBG_CORE_QAT_EXT_D_BGA1-IC,H91A
PVNN_PCH_STBY            U7C1             AC32     LBG_CORE_QAT_EXT_D_BGA1-IC,H91A
PVNN_PCH_STBY            U7C1             AC34     LBG_CORE_QAT_EXT_D_BGA1-IC,H91A
PVNN_PCH_STBY            U7C1             AC36     LBG_CORE_QAT_EXT_D_BGA1-IC,H91A
PVNN_PCH_STBY            U7C1             AC37     LBG_CORE_QAT_EXT_D_BGA1-IC,H91A
PVNN_PCH_STBY            U7C1             AC39     LBG_CORE_QAT_EXT_D_BGA1-IC,H91A
PVNN_PCH_STBY            U7C1             AC41     LBG_CORE_QAT_EXT_D_BGA1-IC,H91A
PVNN_PCH_STBY            U7C1             AE30     LBG_CORE_QAT_EXT_D_BGA1-IC,H91A
PVNN_PCH_STBY            U7C1             AE32     LBG_CORE_QAT_EXT_D_BGA1-IC,H91A
PVNN_PCH_STBY            U7C1             AE34     LBG_CORE_QAT_EXT_D_BGA1-IC,H91A
PVNN_PCH_STBY            U7C1             AE36     LBG_CORE_QAT_EXT_D_BGA1-IC,H91A
PVNN_PCH_STBY            U7C1             AE37     LBG_CORE_QAT_EXT_D_BGA1-IC,H91A
PVNN_PCH_STBY            U7C1             AE39     LBG_CORE_QAT_EXT_D_BGA1-IC,H91A
PVNN_PCH_STBY            U7C1             AE41     LBG_CORE_QAT_EXT_D_BGA1-IC,H91A
PVNN_PCH_STBY            U7C1             AG32     LBG_CORE_QAT_EXT_D_BGA1-IC,H91A
PVNN_PCH_STBY            U7C1             AG34     LBG_CORE_QAT_EXT_D_BGA1-IC,H91A
PVNN_PCH_STBY            U7C1             AG36     LBG_CORE_QAT_EXT_D_BGA1-IC,H91A
PVNN_PCH_STBY            U7C1             AG37     LBG_CORE_QAT_EXT_D_BGA1-IC,H91A
PVNN_PCH_STBY            U7C1             AG39     LBG_CORE_QAT_EXT_D_BGA1-IC,H91A
PVNN_PCH_STBY            U7C1             AK32     LBG_CORE_QAT_EXT_D_BGA1-IC,H91A
PVNN_PCH_STBY            U7C1             AK34     LBG_CORE_QAT_EXT_D_BGA1-IC,H91A
PVNN_PCH_STBY            U7C1             AK37     LBG_CORE_QAT_EXT_D_BGA1-IC,H91A
PVNN_PCH_STBY            U7C1             AK39     LBG_CORE_QAT_EXT_D_BGA1-IC,H91A
PVNN_PCH_STBY            U7C1             AM32     LBG_CORE_QAT_EXT_D_BGA1-IC,H91A
PVNN_PCH_STBY            U7C1             AM34     LBG_CORE_QAT_EXT_D_BGA1-IC,H91A
PVNN_PCH_STBY            U7C1             AM36     LBG_CORE_QAT_EXT_D_BGA1-IC,H91A
PVNN_PCH_STBY            U7C1             AM37     LBG_CORE_QAT_EXT_D_BGA1-IC,H91A
PVNN_PCH_STBY            U7C1             AM39     LBG_CORE_QAT_EXT_D_BGA1-IC,H91A
PVNN_PCH_STBY            U7C1             AP32     LBG_CORE_QAT_EXT_D_BGA1-IC,H91A
PVNN_PCH_STBY            U7C1             AP34     LBG_CORE_QAT_EXT_D_BGA1-IC,H91A
PVNN_PCH_STBY            U7C1             AP36     LBG_CORE_QAT_EXT_D_BGA1-IC,H91A
PVNN_PCH_STBY            U7C1             AP37     LBG_CORE_QAT_EXT_D_BGA1-IC,H91A
PVNN_PCH_STBY            U7C1             AP39     LBG_CORE_QAT_EXT_D_BGA1-IC,H91A
PVNN_PCH_STBY            U7C1             AT32     LBG_CORE_QAT_EXT_D_BGA1-IC,H91A
PVNN_PCH_STBY            U7C1             AT34     LBG_CORE_QAT_EXT_D_BGA1-IC,H91A
PVNN_PCH_STBY            U7C1             AT36     LBG_CORE_QAT_EXT_D_BGA1-IC,H91A
PVNN_PCH_STBY            U7C1             AU32     LBG_CORE_QAT_EXT_D_BGA1-IC,H91A
PVNN_PCH_STBY            U7C1             AU34     LBG_CORE_QAT_EXT_D_BGA1-IC,H91A
PVNN_PCH_STBY            U7C1             AU36     LBG_CORE_QAT_EXT_D_BGA1-IC,H91A
PVNN_PCH_STBY            U7C1             U27      LBG_CORE_QAT_EXT_D_BGA1-IC,H91A
PVNN_PCH_STBY            U7C1             U31      LBG_CORE_QAT_EXT_D_BGA1-IC,H91A
PVNN_PCH_STBY            U7C1             U35      LBG_CORE_QAT_EXT_D_BGA1-IC,H91A
PVNN_PCH_STBY            U7C1             U38      LBG_CORE_QAT_EXT_D_BGA1-IC,H91A
PVNN_PCH_STBY            U7C1             V29      LBG_CORE_QAT_EXT_D_BGA1-IC,H91A
PVNN_PCH_STBY            U7C1             V33      LBG_CORE_QAT_EXT_D_BGA1-IC,H91A
PVNN_PCH_STBY            U7C1             V40      LBG_CORE_QAT_EXT_D_BGA1-IC,H91A
PVNN_PCH_STBY            U7C1             Y29      LBG_CORE_QAT_EXT_D_BGA1-IC,H91A
PVNN_PCH_STBY            U7C1             Y30      LBG_CORE_QAT_EXT_D_BGA1-IC,H91A
PVNN_PCH_STBY            U7C1             Y32      LBG_CORE_QAT_EXT_D_BGA1-IC,H91A
PVNN_PCH_STBY            U7C1             Y34      LBG_CORE_QAT_EXT_D_BGA1-IC,H91A
PVNN_PCH_STBY            U7C1             Y36      LBG_CORE_QAT_EXT_D_BGA1-IC,H91A
PVNN_PCH_STBY            U7C1             Y37      LBG_CORE_QAT_EXT_D_BGA1-IC,H91A
PVNN_PCH_STBY            U7C1             Y39      LBG_CORE_QAT_EXT_D_BGA1-IC,H91A
PVNN_PCH_STBY            U7C1             Y41      LBG_CORE_QAT_EXT_D_BGA1-IC,H91A
PVPP_ABC                 C3T7             1        CAP_0805-47UF,4V,20%,X6S,C9533A
PVPP_ABC                 C3T9             1        CAP_0805-47UF,4V,20%,X6S,C9533A
PVPP_ABC                 C4T3             1        CAPP_7343-220UF,4V,20%,POSCAP,A
PVPP_ABC                 C4T5             1        CAP_0603LF-10UF,4V,20%,X6S,E15A
PVPP_ABC                 C4T6             1        CAP_0603LF-10UF,4V,20%,X6S,E15A
PVPP_ABC                 C4U1             1        CAP_0603LF-10UF,4V,20%,X6S,E15A
PVPP_ABC                 C4U2             1        CAP_0603LF-10UF,4V,20%,X6S,E15A
PVPP_ABC                 C4U3             1        CAP_0603LF-10UF,4V,20%,X6S,E15A
PVPP_ABC                 C4U4             1        CAP_0603LF-10UF,4V,20%,X6S,E15A
PVPP_ABC                 C6F3             1        CAP_A_0402V-0.1UF,16V,10%,X7R,A
PVPP_ABC                 C6F4             1        CAPP_7343LF-330UF,6.3V,20%,POSA
PVPP_ABC                 C6F5             1        CAP_0603LF-10UF,4V,20%,X6S,E15A
PVPP_ABC                 C6F6             1        CAP_0603LF-10UF,4V,20%,X6S,E15A
PVPP_ABC                 C6G1             1        CAP_0603LF-10UF,4V,20%,X6S,E15A
PVPP_ABC                 C6G2             1        CAP_0603LF-10UF,4V,20%,X6S,E15A
PVPP_ABC                 C6G4             1        CAP_0603LF-10UF,4V,20%,X6S,E15A
PVPP_ABC                 C6G5             1        CAP_0603LF-10UF,4V,20%,X6S,E15A
PVPP_ABC                 J4G1             142      SCONN288_H44441004_PIP-SCONN,HA
PVPP_ABC                 J4G1             143      SCONN288_H44441004_PIP-SCONN,HA
PVPP_ABC                 J4G1             284      SCONN288_H44441004_PIP-SCONN,HA
PVPP_ABC                 J4G1             286      SCONN288_H44441004_PIP-SCONN,HA
PVPP_ABC                 J4G1             287      SCONN288_H44441004_PIP-SCONN,HA
PVPP_ABC                 J4G1             288      SCONN288_H44441004_PIP-SCONN,HA
PVPP_ABC                 J4G2             140      SCONN288_H44441004_PIP-SCONN,HA
PVPP_ABC                 J4G2             142      SCONN288_H44441004_PIP-SCONN,HA
PVPP_ABC                 J4G2             143      SCONN288_H44441004_PIP-SCONN,HA
PVPP_ABC                 J4G2             284      SCONN288_H44441004_PIP-SCONN,HA
PVPP_ABC                 J4G2             286      SCONN288_H44441004_PIP-SCONN,HA
PVPP_ABC                 J4G2             287      SCONN288_H44441004_PIP-SCONN,HA
PVPP_ABC                 J4G2             288      SCONN288_H44441004_PIP-SCONN,HA
PVPP_ABC                 J4G3             142      SCONN288_H44441004_PIP-SCONN,HA
PVPP_ABC                 J4G3             143      SCONN288_H44441004_PIP-SCONN,HA
PVPP_ABC                 J4G3             238      SCONN288_H44441004_PIP-SCONN,HA
PVPP_ABC                 J4G3             284      SCONN288_H44441004_PIP-SCONN,HA
PVPP_ABC                 J4G3             286      SCONN288_H44441004_PIP-SCONN,HA
PVPP_ABC                 J4G3             287      SCONN288_H44441004_PIP-SCONN,HA
PVPP_ABC                 J4G3             288      SCONN288_H44441004_PIP-SCONN,HA
PVPP_ABC                 J6T1             139      SCONN288_H44441003_PIP-SCONN,HA
PVPP_ABC                 J6T1             142      SCONN288_H44441003_PIP-SCONN,HA
PVPP_ABC                 J6T1             143      SCONN288_H44441003_PIP-SCONN,HA
PVPP_ABC                 J6T1             284      SCONN288_H44441003_PIP-SCONN,HA
PVPP_ABC                 J6T1             286      SCONN288_H44441003_PIP-SCONN,HA
PVPP_ABC                 J6T1             287      SCONN288_H44441003_PIP-SCONN,HA
PVPP_ABC                 J6T1             288      SCONN288_H44441003_PIP-SCONN,HA
PVPP_ABC                 J6U1             139      SCONN288_H44441003_PIP-SCONN,HA
PVPP_ABC                 J6U1             140      SCONN288_H44441003_PIP-SCONN,HA
PVPP_ABC                 J6U1             142      SCONN288_H44441003_PIP-SCONN,HA
PVPP_ABC                 J6U1             143      SCONN288_H44441003_PIP-SCONN,HA
PVPP_ABC                 J6U1             284      SCONN288_H44441003_PIP-SCONN,HA
PVPP_ABC                 J6U1             286      SCONN288_H44441003_PIP-SCONN,HA
PVPP_ABC                 J6U1             287      SCONN288_H44441003_PIP-SCONN,HA
PVPP_ABC                 J6U1             288      SCONN288_H44441003_PIP-SCONN,HA
PVPP_ABC                 J6U2             139      SCONN288_H44441003_PIP-SCONN,HA
PVPP_ABC                 J6U2             142      SCONN288_H44441003_PIP-SCONN,HA
PVPP_ABC                 J6U2             143      SCONN288_H44441003_PIP-SCONN,HA
PVPP_ABC                 J6U2             238      SCONN288_H44441003_PIP-SCONN,HA
PVPP_ABC                 J6U2             284      SCONN288_H44441003_PIP-SCONN,HA
PVPP_ABC                 J6U2             286      SCONN288_H44441003_PIP-SCONN,HA
PVPP_ABC                 J6U2             287      SCONN288_H44441003_PIP-SCONN,HA
PVPP_ABC                 J6U2             288      SCONN288_H44441003_PIP-SCONN,HA
PVPP_ABC                 J8B1             21       SCONN24_H46321001_SM-SCONN,H46A
PVPP_ABC                 L7F1             2        INDUCTOR_SM-0.47UH,IND,E13358-A
PVPP_ABC                 R3R16            1        RES_0402-4.75K,1%,1/16W,CHIP,GA
PVPP_ABC                 R4T7             1        RES_0402-665,1.0%,1/16W,CHIP,GA
PVPP_ABC                 R4T8             1        RES_0402-665,1.0%,1/16W,CHIP,GA
PVPP_ABC                 R4U2             1        RES_0402-2.21K,1%,1/16W,CHIP,GA
PVPP_ABC                 R4U3             1        RES_0402-4.75K,1%,1/16W,CHIP,GA
PVPP_ABC                 R6F3             1        RES_0402-10.0K,1%,1/16W,CHIP,GA
PVPP_ABC                 R7F10            1        RES_0603-120.0,1%,1/10W,CHIP,GA
PVPP_ABC                 R7F12            1        RES_0402-0.0,5%,1/16W,CHIP,G21A
PVPP_ABC                 R8B3             1        RES_0402-4.75K,1%,1/16W,CHIP,GA
PVPP_ABC                 R8B5             1        RES_0402-4.75K,1%,1/16W,CHIP,GA
PVPP_ABC                 R8B6             1        RES_0402-1.8K,1%,1/16W,CHIP,G2A
PVPP_ABC                 R8B7             1        RES_0402-1.8K,1%,1/16W,CHIP,G2A
PVPP_ABC                 R8B8             1        RES_0402-4.75K,1%,1/16W,CHIP,GA
PVPP_ABC                 R8B10            1        RES_0402-4.75K,1%,1/16W,CHIP,GA
PVPP_ABC                 R8B11            1        RES_0402-1.8K,1%,1/16W,CHIP,G2A
PVPP_ABC                 R8B13            1        RES_0402-1.8K,1%,1/16W,CHIP,G2A
PVPP_ABC                 R8B16            1        RES_0402-4.75K,1%,1/16W,CHIP,GA
PVPP_ABC                 R8B17            1        RES_0402-4.75K,1%,1/16W,CHIP,GA
PVPP_ABC                 R8B18            1        RES_0402-4.75K,1%,1/16W,CHIP,GA
PVPP_ABC                 R8B19            1        RES_0402-4.75K,1%,1/16W,CHIP,GA
PVPP_ABC                 U5D1             A8       SKX_EXT_B_BGA1-IC,TBD
PVPP_ABC                 U5D1             A10      SKX_EXT_B_BGA1-IC,TBD
PVPP_ABC                 U5D1             A12      SKX_EXT_B_BGA1-IC,TBD
PVPP_ABC                 U5D1             B11      SKX_EXT_B_BGA1-IC,TBD
PVPP_ABC                 U6F1             8        PCA9617_SSOP-IC,G81764-001-GNDA
PVPP_DEF                 C4L1             1        CAP_0603LF-10UF,4V,20%,X6S,E15A
PVPP_DEF                 C4L2             1        CAP_0603LF-10UF,4V,20%,X6S,E15A
PVPP_DEF                 C4L3             1        CAP_0603LF-10UF,4V,20%,X6S,E15A
PVPP_DEF                 C4L4             1        CAP_0603LF-10UF,4V,20%,X6S,E15A
PVPP_DEF                 C4M1             1        CAPP_7343-220UF,4V,20%,POSCAP,A
PVPP_DEF                 C4M3             1        CAP_0603LF-10UF,4V,20%,X6S,E15A
PVPP_DEF                 C4M4             1        CAP_0603LF-10UF,4V,20%,X6S,E15A
PVPP_DEF                 C6A2             1        CAP_0603LF-10UF,4V,20%,X6S,E15A
PVPP_DEF                 C6A3             1        CAP_0603LF-10UF,4V,20%,X6S,E15A
PVPP_DEF                 C6A6             1        CAP_0603LF-10UF,4V,20%,X6S,E15A
PVPP_DEF                 C6A7             1        CAP_0603LF-10UF,4V,20%,X6S,E15A
PVPP_DEF                 C6B1             1        CAP_0603LF-10UF,4V,20%,X6S,E15A
PVPP_DEF                 C6B2             1        CAP_0603LF-10UF,4V,20%,X6S,E15A
PVPP_DEF                 C6B3             1        CAP_0805-47UF,4V,20%,X6S,C9533A
PVPP_DEF                 C6B7             1        CAPP_7343LF-330UF,6.3V,20%,POSA
PVPP_DEF                 C7B7             1        CAP_0805-47UF,4V,20%,X6S,C9533A
PVPP_DEF                 C7E2             1        CAP_A_0402V-0.1UF,16V,10%,X7R,A
PVPP_DEF                 J4A1             142      SCONN288_H44441004_PIP-SCONN,HA
PVPP_DEF                 J4A1             143      SCONN288_H44441004_PIP-SCONN,HA
PVPP_DEF                 J4A1             238      SCONN288_H44441004_PIP-SCONN,HA
PVPP_DEF                 J4A1             284      SCONN288_H44441004_PIP-SCONN,HA
PVPP_DEF                 J4A1             286      SCONN288_H44441004_PIP-SCONN,HA
PVPP_DEF                 J4A1             287      SCONN288_H44441004_PIP-SCONN,HA
PVPP_DEF                 J4A1             288      SCONN288_H44441004_PIP-SCONN,HA
PVPP_DEF                 J4A2             140      SCONN288_H44441004_PIP-SCONN,HA
PVPP_DEF                 J4A2             142      SCONN288_H44441004_PIP-SCONN,HA
PVPP_DEF                 J4A2             143      SCONN288_H44441004_PIP-SCONN,HA
PVPP_DEF                 J4A2             284      SCONN288_H44441004_PIP-SCONN,HA
PVPP_DEF                 J4A2             286      SCONN288_H44441004_PIP-SCONN,HA
PVPP_DEF                 J4A2             287      SCONN288_H44441004_PIP-SCONN,HA
PVPP_DEF                 J4A2             288      SCONN288_H44441004_PIP-SCONN,HA
PVPP_DEF                 J4B1             142      SCONN288_H44441004_PIP-SCONN,HA
PVPP_DEF                 J4B1             143      SCONN288_H44441004_PIP-SCONN,HA
PVPP_DEF                 J4B1             284      SCONN288_H44441004_PIP-SCONN,HA
PVPP_DEF                 J4B1             286      SCONN288_H44441004_PIP-SCONN,HA
PVPP_DEF                 J4B1             287      SCONN288_H44441004_PIP-SCONN,HA
PVPP_DEF                 J4B1             288      SCONN288_H44441004_PIP-SCONN,HA
PVPP_DEF                 J6L1             139      SCONN288_H44441003_PIP-SCONN,HA
PVPP_DEF                 J6L1             142      SCONN288_H44441003_PIP-SCONN,HA
PVPP_DEF                 J6L1             143      SCONN288_H44441003_PIP-SCONN,HA
PVPP_DEF                 J6L1             238      SCONN288_H44441003_PIP-SCONN,HA
PVPP_DEF                 J6L1             284      SCONN288_H44441003_PIP-SCONN,HA
PVPP_DEF                 J6L1             286      SCONN288_H44441003_PIP-SCONN,HA
PVPP_DEF                 J6L1             287      SCONN288_H44441003_PIP-SCONN,HA
PVPP_DEF                 J6L1             288      SCONN288_H44441003_PIP-SCONN,HA
PVPP_DEF                 J6L2             139      SCONN288_H44441003_PIP-SCONN,HA
PVPP_DEF                 J6L2             140      SCONN288_H44441003_PIP-SCONN,HA
PVPP_DEF                 J6L2             142      SCONN288_H44441003_PIP-SCONN,HA
PVPP_DEF                 J6L2             143      SCONN288_H44441003_PIP-SCONN,HA
PVPP_DEF                 J6L2             284      SCONN288_H44441003_PIP-SCONN,HA
PVPP_DEF                 J6L2             286      SCONN288_H44441003_PIP-SCONN,HA
PVPP_DEF                 J6L2             287      SCONN288_H44441003_PIP-SCONN,HA
PVPP_DEF                 J6L2             288      SCONN288_H44441003_PIP-SCONN,HA
PVPP_DEF                 J6M1             139      SCONN288_H44441003_PIP-SCONN,HA
PVPP_DEF                 J6M1             142      SCONN288_H44441003_PIP-SCONN,HA
PVPP_DEF                 J6M1             143      SCONN288_H44441003_PIP-SCONN,HA
PVPP_DEF                 J6M1             284      SCONN288_H44441003_PIP-SCONN,HA
PVPP_DEF                 J6M1             286      SCONN288_H44441003_PIP-SCONN,HA
PVPP_DEF                 J6M1             287      SCONN288_H44441003_PIP-SCONN,HA
PVPP_DEF                 J6M1             288      SCONN288_H44441003_PIP-SCONN,HA
PVPP_DEF                 L7B1             2        INDUCTOR_SM-0.47UH,IND,E13358-A
PVPP_DEF                 R3R5             1        RES_0402-665,1.0%,1/16W,CHIP,GA
PVPP_DEF                 R3R12            1        RES_0402-665,1.0%,1/16W,CHIP,GA
PVPP_DEF                 R7B10            1        RES_0603-120.0,1%,1/10W,CHIP,GA
PVPP_DEF                 R7B11            1        RES_0402-0.0,5%,1/16W,CHIP,G21A
PVPP_DEF                 U7E1             8        PCA9617_SSOP-IC,G81764-001-GNDA
PVPP_GHJ                 C3F3             1        CAP_0603LF-10UF,4V,20%,X6S,E15A
PVPP_GHJ                 C3F4             1        CAP_0603LF-10UF,4V,20%,X6S,E15A
PVPP_GHJ                 C3G3             1        CAP_0603LF-10UF,4V,20%,X6S,E15A
PVPP_GHJ                 C3G4             1        CAP_0603LF-10UF,4V,20%,X6S,E15A
PVPP_GHJ                 C3G7             1        CAP_0603LF-10UF,4V,20%,X6S,E15A
PVPP_GHJ                 C3G8             1        CAP_0603LF-10UF,4V,20%,X6S,E15A
PVPP_GHJ                 C4F7             1        CAPP_7343LF-330UF,6.3V,20%,POSA
PVPP_GHJ                 C4F11            1        CAPP_7343-220UF,4V,20%,POSCAP,A
PVPP_GHJ                 C4G25            1        CAP_A_0402V-0.1UF,16V,10%,X7R,A
PVPP_GHJ                 C6U2             1        CAP_0805-47UF,4V,20%,X6S,C9533A
PVPP_GHJ                 C6U3             1        CAP_0805-47UF,4V,20%,X6S,C9533A
PVPP_GHJ                 C7T2             1        CAP_0603LF-10UF,4V,20%,X6S,E15A
PVPP_GHJ                 C7T3             1        CAP_0603LF-10UF,4V,20%,X6S,E15A
PVPP_GHJ                 C7U3             1        CAP_0603LF-10UF,4V,20%,X6S,E15A
PVPP_GHJ                 C7U4             1        CAP_0603LF-10UF,4V,20%,X6S,E15A
PVPP_GHJ                 C7U5             1        CAP_0603LF-10UF,4V,20%,X6S,E15A
PVPP_GHJ                 C7U6             1        CAP_0603LF-10UF,4V,20%,X6S,E15A
PVPP_GHJ                 J1G1             142      SCONN288_H44441004_PIP-SCONN,HA
PVPP_GHJ                 J1G1             143      SCONN288_H44441004_PIP-SCONN,HA
PVPP_GHJ                 J1G1             284      SCONN288_H44441004_PIP-SCONN,HA
PVPP_GHJ                 J1G1             286      SCONN288_H44441004_PIP-SCONN,HA
PVPP_GHJ                 J1G1             287      SCONN288_H44441004_PIP-SCONN,HA
PVPP_GHJ                 J1G1             288      SCONN288_H44441004_PIP-SCONN,HA
PVPP_GHJ                 J1G2             140      SCONN288_H44441004_PIP-SCONN,HA
PVPP_GHJ                 J1G2             142      SCONN288_H44441004_PIP-SCONN,HA
PVPP_GHJ                 J1G2             143      SCONN288_H44441004_PIP-SCONN,HA
PVPP_GHJ                 J1G2             284      SCONN288_H44441004_PIP-SCONN,HA
PVPP_GHJ                 J1G2             286      SCONN288_H44441004_PIP-SCONN,HA
PVPP_GHJ                 J1G2             287      SCONN288_H44441004_PIP-SCONN,HA
PVPP_GHJ                 J1G2             288      SCONN288_H44441004_PIP-SCONN,HA
PVPP_GHJ                 J1G3             142      SCONN288_H44441004_PIP-SCONN,HA
PVPP_GHJ                 J1G3             143      SCONN288_H44441004_PIP-SCONN,HA
PVPP_GHJ                 J1G3             238      SCONN288_H44441004_PIP-SCONN,HA
PVPP_GHJ                 J1G3             284      SCONN288_H44441004_PIP-SCONN,HA
PVPP_GHJ                 J1G3             286      SCONN288_H44441004_PIP-SCONN,HA
PVPP_GHJ                 J1G3             287      SCONN288_H44441004_PIP-SCONN,HA
PVPP_GHJ                 J1G3             288      SCONN288_H44441004_PIP-SCONN,HA
PVPP_GHJ                 J9T1             139      SCONN288_H44441003_PIP-SCONN,HA
PVPP_GHJ                 J9T1             142      SCONN288_H44441003_PIP-SCONN,HA
PVPP_GHJ                 J9T1             143      SCONN288_H44441003_PIP-SCONN,HA
PVPP_GHJ                 J9T1             284      SCONN288_H44441003_PIP-SCONN,HA
PVPP_GHJ                 J9T1             286      SCONN288_H44441003_PIP-SCONN,HA
PVPP_GHJ                 J9T1             287      SCONN288_H44441003_PIP-SCONN,HA
PVPP_GHJ                 J9T1             288      SCONN288_H44441003_PIP-SCONN,HA
PVPP_GHJ                 J9U1             139      SCONN288_H44441003_PIP-SCONN,HA
PVPP_GHJ                 J9U1             140      SCONN288_H44441003_PIP-SCONN,HA
PVPP_GHJ                 J9U1             142      SCONN288_H44441003_PIP-SCONN,HA
PVPP_GHJ                 J9U1             143      SCONN288_H44441003_PIP-SCONN,HA
PVPP_GHJ                 J9U1             284      SCONN288_H44441003_PIP-SCONN,HA
PVPP_GHJ                 J9U1             286      SCONN288_H44441003_PIP-SCONN,HA
PVPP_GHJ                 J9U1             287      SCONN288_H44441003_PIP-SCONN,HA
PVPP_GHJ                 J9U1             288      SCONN288_H44441003_PIP-SCONN,HA
PVPP_GHJ                 J9U2             139      SCONN288_H44441003_PIP-SCONN,HA
PVPP_GHJ                 J9U2             142      SCONN288_H44441003_PIP-SCONN,HA
PVPP_GHJ                 J9U2             143      SCONN288_H44441003_PIP-SCONN,HA
PVPP_GHJ                 J9U2             238      SCONN288_H44441003_PIP-SCONN,HA
PVPP_GHJ                 J9U2             284      SCONN288_H44441003_PIP-SCONN,HA
PVPP_GHJ                 J9U2             286      SCONN288_H44441003_PIP-SCONN,HA
PVPP_GHJ                 J9U2             287      SCONN288_H44441003_PIP-SCONN,HA
PVPP_GHJ                 J9U2             288      SCONN288_H44441003_PIP-SCONN,HA
PVPP_GHJ                 L4G1             2        INDUCTOR_SM-0.47UH,IND,E13358-A
PVPP_GHJ                 R4G6             1        RES_0603-120.0,1%,1/10W,CHIP,GA
PVPP_GHJ                 R4G8             1        RES_0402-0.0,5%,1/16W,CHIP,G21A
PVPP_GHJ                 R6U17            1        RES_0402-665,1.0%,1/16W,CHIP,GA
PVPP_GHJ                 R6U18            1        RES_0402-665,1.0%,1/16W,CHIP,GA
PVPP_GHJ                 U2D1             A8       SKX_EXT_B_BGA1-IC,TBD
PVPP_GHJ                 U2D1             A10      SKX_EXT_B_BGA1-IC,TBD
PVPP_GHJ                 U2D1             A12      SKX_EXT_B_BGA1-IC,TBD
PVPP_GHJ                 U2D1             B11      SKX_EXT_B_BGA1-IC,TBD
PVPP_GHJ                 U4G1             8        PCA9617_SSOP-IC,G81764-001-GNDA
PVPP_KLM                 C3A3             1        CAP_0603LF-10UF,4V,20%,X6S,E15A
PVPP_KLM                 C3A4             1        CAP_0603LF-10UF,4V,20%,X6S,E15A
PVPP_KLM                 C3A7             1        CAP_0603LF-10UF,4V,20%,X6S,E15A
PVPP_KLM                 C3A8             1        CAP_0603LF-10UF,4V,20%,X6S,E15A
PVPP_KLM                 C3B1             1        CAP_0603LF-10UF,4V,20%,X6S,E15A
PVPP_KLM                 C3B2             1        CAP_0603LF-10UF,4V,20%,X6S,E15A
PVPP_KLM                 C3B3             1        CAPP_7343LF-330UF,6.3V,20%,POSA
PVPP_KLM                 C3B5             1        CAP_A_0402V-0.1UF,16V,10%,X7R,A
PVPP_KLM                 C4B2             1        CAP_0805-47UF,4V,20%,X6S,C9533A
PVPP_KLM                 C4B3             1        CAP_0805-47UF,4V,20%,X6S,C9533A
PVPP_KLM                 C6L8             1        CAPP_7343-220UF,4V,20%,POSCAP,A
PVPP_KLM                 C7L2             1        CAP_0603LF-10UF,4V,20%,X6S,E15A
PVPP_KLM                 C7L3             1        CAP_0603LF-10UF,4V,20%,X6S,E15A
PVPP_KLM                 C7L6             1        CAP_0603LF-10UF,4V,20%,X6S,E15A
PVPP_KLM                 C7L7             1        CAP_0603LF-10UF,4V,20%,X6S,E15A
PVPP_KLM                 C7M3             1        CAP_0603LF-10UF,4V,20%,X6S,E15A
PVPP_KLM                 C7M4             1        CAP_0603LF-10UF,4V,20%,X6S,E15A
PVPP_KLM                 J1A1             142      SCONN288_H44441004_PIP-SCONN,HA
PVPP_KLM                 J1A1             143      SCONN288_H44441004_PIP-SCONN,HA
PVPP_KLM                 J1A1             238      SCONN288_H44441004_PIP-SCONN,HA
PVPP_KLM                 J1A1             284      SCONN288_H44441004_PIP-SCONN,HA
PVPP_KLM                 J1A1             286      SCONN288_H44441004_PIP-SCONN,HA
PVPP_KLM                 J1A1             287      SCONN288_H44441004_PIP-SCONN,HA
PVPP_KLM                 J1A1             288      SCONN288_H44441004_PIP-SCONN,HA
PVPP_KLM                 J1A2             140      SCONN288_H44441004_PIP-SCONN,HA
PVPP_KLM                 J1A2             142      SCONN288_H44441004_PIP-SCONN,HA
PVPP_KLM                 J1A2             143      SCONN288_H44441004_PIP-SCONN,HA
PVPP_KLM                 J1A2             284      SCONN288_H44441004_PIP-SCONN,HA
PVPP_KLM                 J1A2             286      SCONN288_H44441004_PIP-SCONN,HA
PVPP_KLM                 J1A2             287      SCONN288_H44441004_PIP-SCONN,HA
PVPP_KLM                 J1A2             288      SCONN288_H44441004_PIP-SCONN,HA
PVPP_KLM                 J1B1             142      SCONN288_H44441004_PIP-SCONN,HA
PVPP_KLM                 J1B1             143      SCONN288_H44441004_PIP-SCONN,HA
PVPP_KLM                 J1B1             284      SCONN288_H44441004_PIP-SCONN,HA
PVPP_KLM                 J1B1             286      SCONN288_H44441004_PIP-SCONN,HA
PVPP_KLM                 J1B1             287      SCONN288_H44441004_PIP-SCONN,HA
PVPP_KLM                 J1B1             288      SCONN288_H44441004_PIP-SCONN,HA
PVPP_KLM                 J9L1             139      SCONN288_H44441003_PIP-SCONN,HA
PVPP_KLM                 J9L1             142      SCONN288_H44441003_PIP-SCONN,HA
PVPP_KLM                 J9L1             143      SCONN288_H44441003_PIP-SCONN,HA
PVPP_KLM                 J9L1             238      SCONN288_H44441003_PIP-SCONN,HA
PVPP_KLM                 J9L1             284      SCONN288_H44441003_PIP-SCONN,HA
PVPP_KLM                 J9L1             286      SCONN288_H44441003_PIP-SCONN,HA
PVPP_KLM                 J9L1             287      SCONN288_H44441003_PIP-SCONN,HA
PVPP_KLM                 J9L1             288      SCONN288_H44441003_PIP-SCONN,HA
PVPP_KLM                 J9L2             139      SCONN288_H44441003_PIP-SCONN,HA
PVPP_KLM                 J9L2             140      SCONN288_H44441003_PIP-SCONN,HA
PVPP_KLM                 J9L2             142      SCONN288_H44441003_PIP-SCONN,HA
PVPP_KLM                 J9L2             143      SCONN288_H44441003_PIP-SCONN,HA
PVPP_KLM                 J9L2             284      SCONN288_H44441003_PIP-SCONN,HA
PVPP_KLM                 J9L2             286      SCONN288_H44441003_PIP-SCONN,HA
PVPP_KLM                 J9L2             287      SCONN288_H44441003_PIP-SCONN,HA
PVPP_KLM                 J9L2             288      SCONN288_H44441003_PIP-SCONN,HA
PVPP_KLM                 J9M1             139      SCONN288_H44441003_PIP-SCONN,HA
PVPP_KLM                 J9M1             142      SCONN288_H44441003_PIP-SCONN,HA
PVPP_KLM                 J9M1             143      SCONN288_H44441003_PIP-SCONN,HA
PVPP_KLM                 J9M1             284      SCONN288_H44441003_PIP-SCONN,HA
PVPP_KLM                 J9M1             286      SCONN288_H44441003_PIP-SCONN,HA
PVPP_KLM                 J9M1             287      SCONN288_H44441003_PIP-SCONN,HA
PVPP_KLM                 J9M1             288      SCONN288_H44441003_PIP-SCONN,HA
PVPP_KLM                 L4A1             2        INDUCTOR_SM-0.47UH,IND,E13358-A
PVPP_KLM                 R4B2             1        RES_0603-120.0,1%,1/10W,CHIP,GA
PVPP_KLM                 R4B3             1        RES_0402-0.0,5%,1/16W,CHIP,G21A
PVPP_KLM                 R6M9             1        RES_0402-4.75K,1%,1/16W,CHIP,GA
PVPP_KLM                 R7M1             1        RES_0402-665,1.0%,1/16W,CHIP,GA
PVPP_KLM                 R7M6             1        RES_0402-665,1.0%,1/16W,CHIP,GA
PVPP_KLM                 U3B1             8        PCA9617_SSOP-IC,G81764-001-GNDA
PVSA_CPU0                C4C11            1        CAP_A_0603V-22.0UF,4V,20%,X6S,A
PVSA_CPU0                C5D10            1        CAP_0603LF-10UF,4V,20%,X6S,E15A
PVSA_CPU0                C5D11            1        CAP_0603LF-10UF,4V,20%,X6S,E15A
PVSA_CPU0                C5D12            1        CAP_0603LF-10UF,4V,20%,X6S,E15A
PVSA_CPU0                C5D13            1        CAP_0603LF-10UF,4V,20%,X6S,E15A
PVSA_CPU0                C5P7             1        CAP_0805LF-22UF,4V,20%,X6S,C95A
PVSA_CPU0                C5P8             1        CAP_0805LF-22UF,4V,20%,X6S,C95A
PVSA_CPU0                C5P9             1        CAP_0805LF-22UF,4V,20%,X6S,C95A
PVSA_CPU0                C6N1             1        CAPP_3018-470UF,2.5V,20%,ALUM,A
PVSA_CPU0                C6N4             1        CAPP_3018-470UF,2.5V,20%,ALUM,A
PVSA_CPU0                C6N7             1        CAP_A_0603V-22.0UF,4V,20%,X6S,A
PVSA_CPU0                EU4C1            1        IR354XX_SM-IR35412,IC,H73684-0A
PVSA_CPU0                L4C2             2        INDUCTOR_SM-0.3UH,IND,D92183-0A
PVSA_CPU0                R4C5             2        RES_0402-100.0,1%,1/16W,CHIP,GA
PVSA_CPU0                R6N4             1        RES_0402-51.1,1.0%,1/16W,CHIP,A
PVSA_CPU0                U5D1             CB65     SKX_EXT_B_BGA1-IC,TBD
PVSA_CPU0                U5D1             CB67     SKX_EXT_B_BGA1-IC,TBD
PVSA_CPU0                U5D1             CB69     SKX_EXT_B_BGA1-IC,TBD
PVSA_CPU0                U5D1             CC66     SKX_EXT_B_BGA1-IC,TBD
PVSA_CPU0                U5D1             CC68     SKX_EXT_B_BGA1-IC,TBD
PVSA_CPU0                U5D1             CC70     SKX_EXT_B_BGA1-IC,TBD
PVSA_CPU0                U5D1             CD65     SKX_EXT_B_BGA1-IC,TBD
PVSA_CPU0                U5D1             CD67     SKX_EXT_B_BGA1-IC,TBD
PVSA_CPU0                U5D1             CD69     SKX_EXT_B_BGA1-IC,TBD
PVSA_CPU0                U5D1             CD71     SKX_EXT_B_BGA1-IC,TBD
PVSA_CPU0                U5D1             CE64     SKX_EXT_B_BGA1-IC,TBD
PVSA_CPU0                U5D1             CE66     SKX_EXT_B_BGA1-IC,TBD
PVSA_CPU0                U5D1             CE68     SKX_EXT_B_BGA1-IC,TBD
PVSA_CPU0                U5D1             CE72     SKX_EXT_B_BGA1-IC,TBD
PVSA_CPU0                U5D1             CE74     SKX_EXT_B_BGA1-IC,TBD
PVSA_CPU0                U5D1             CF65     SKX_EXT_B_BGA1-IC,TBD
PVSA_CPU0                U5D1             CF67     SKX_EXT_B_BGA1-IC,TBD
PVSA_CPU0                U5D1             CF73     SKX_EXT_B_BGA1-IC,TBD
PVSA_CPU0                U5D1             CF75     SKX_EXT_B_BGA1-IC,TBD
PVSA_CPU0                U5D1             CG64     SKX_EXT_B_BGA1-IC,TBD
PVSA_CPU0                U5D1             CG66     SKX_EXT_B_BGA1-IC,TBD
PVSA_CPU0                U5D1             CG74     SKX_EXT_B_BGA1-IC,TBD
PVSA_CPU0                U5D1             CH65     SKX_EXT_B_BGA1-IC,TBD
PVSA_CPU0                U5D1             CH75     SKX_EXT_B_BGA1-IC,TBD
PVSA_CPU0                U5D1             CJ64     SKX_EXT_B_BGA1-IC,TBD
PVSA_CPU0                U5D1             CJ66     SKX_EXT_B_BGA1-IC,TBD
PVSA_CPU1                C1C19            1        CAP_A_0603V-22.0UF,4V,20%,X6S,A
PVSA_CPU1                C2D8             1        CAP_0603LF-10UF,4V,20%,X6S,E15A
PVSA_CPU1                C2D9             1        CAP_0603LF-10UF,4V,20%,X6S,E15A
PVSA_CPU1                C2D10            1        CAP_0603LF-10UF,4V,20%,X6S,E15A
PVSA_CPU1                C2D11            1        CAP_0603LF-10UF,4V,20%,X6S,E15A
PVSA_CPU1                C8P5             1        CAP_0805LF-22UF,4V,20%,X6S,C95A
PVSA_CPU1                C8P6             1        CAP_0805LF-22UF,4V,20%,X6S,C95A
PVSA_CPU1                C8P7             1        CAP_0805LF-22UF,4V,20%,X6S,C95A
PVSA_CPU1                C9N11            1        CAPP_3018-470UF,2.5V,20%,ALUM,A
PVSA_CPU1                C9N20            1        CAPP_3018-470UF,2.5V,20%,ALUM,A
PVSA_CPU1                C9N22            1        CAP_A_0603V-22.0UF,4V,20%,X6S,A
PVSA_CPU1                EU1C1            1        IR354XX_SM-IR35412,IC,H73684-0A
PVSA_CPU1                L1C1             2        INDUCTOR_SM-0.3UH,IND,D92183-0A
PVSA_CPU1                R1C12            2        RES_0402-100.0,1%,1/16W,CHIP,GA
PVSA_CPU1                R9N4             1        RES_0402-51.1,1.0%,1/16W,CHIP,A
PVSA_CPU1                U2D1             CB65     SKX_EXT_B_BGA1-IC,TBD
PVSA_CPU1                U2D1             CB67     SKX_EXT_B_BGA1-IC,TBD
PVSA_CPU1                U2D1             CB69     SKX_EXT_B_BGA1-IC,TBD
PVSA_CPU1                U2D1             CC66     SKX_EXT_B_BGA1-IC,TBD
PVSA_CPU1                U2D1             CC68     SKX_EXT_B_BGA1-IC,TBD
PVSA_CPU1                U2D1             CC70     SKX_EXT_B_BGA1-IC,TBD
PVSA_CPU1                U2D1             CD65     SKX_EXT_B_BGA1-IC,TBD
PVSA_CPU1                U2D1             CD67     SKX_EXT_B_BGA1-IC,TBD
PVSA_CPU1                U2D1             CD69     SKX_EXT_B_BGA1-IC,TBD
PVSA_CPU1                U2D1             CD71     SKX_EXT_B_BGA1-IC,TBD
PVSA_CPU1                U2D1             CE64     SKX_EXT_B_BGA1-IC,TBD
PVSA_CPU1                U2D1             CE66     SKX_EXT_B_BGA1-IC,TBD
PVSA_CPU1                U2D1             CE68     SKX_EXT_B_BGA1-IC,TBD
PVSA_CPU1                U2D1             CE72     SKX_EXT_B_BGA1-IC,TBD
PVSA_CPU1                U2D1             CE74     SKX_EXT_B_BGA1-IC,TBD
PVSA_CPU1                U2D1             CF65     SKX_EXT_B_BGA1-IC,TBD
PVSA_CPU1                U2D1             CF67     SKX_EXT_B_BGA1-IC,TBD
PVSA_CPU1                U2D1             CF73     SKX_EXT_B_BGA1-IC,TBD
PVSA_CPU1                U2D1             CF75     SKX_EXT_B_BGA1-IC,TBD
PVSA_CPU1                U2D1             CG64     SKX_EXT_B_BGA1-IC,TBD
PVSA_CPU1                U2D1             CG66     SKX_EXT_B_BGA1-IC,TBD
PVSA_CPU1                U2D1             CG74     SKX_EXT_B_BGA1-IC,TBD
PVSA_CPU1                U2D1             CH65     SKX_EXT_B_BGA1-IC,TBD
PVSA_CPU1                U2D1             CH75     SKX_EXT_B_BGA1-IC,TBD
PVSA_CPU1                U2D1             CJ64     SKX_EXT_B_BGA1-IC,TBD
PVSA_CPU1                U2D1             CJ66     SKX_EXT_B_BGA1-IC,TBD
PVTT_ABC                 C4G24            1        CAP_0805LF-22UF,4V,20%,X6S,C95A
PVTT_ABC                 C5T3             1        CAP_A_0603V-47UF,4V,20%,X5R,60A
PVTT_ABC                 C5U12            1        CAP_A_0603V-47UF,4V,20%,X5R,60A
PVTT_ABC                 C5U16            1        CAP_A_0603V-47UF,4V,20%,X5R,60A
PVTT_ABC                 EU4G3            9        MIC5166_DFN-IC,H55101-001
PVTT_ABC                 J4G1             77       SCONN288_H44441004_PIP-SCONN,HA
PVTT_ABC                 J4G1             221      SCONN288_H44441004_PIP-SCONN,HA
PVTT_ABC                 J4G2             77       SCONN288_H44441004_PIP-SCONN,HA
PVTT_ABC                 J4G2             221      SCONN288_H44441004_PIP-SCONN,HA
PVTT_ABC                 J4G3             77       SCONN288_H44441004_PIP-SCONN,HA
PVTT_ABC                 J4G3             221      SCONN288_H44441004_PIP-SCONN,HA
PVTT_ABC                 J6T1             77       SCONN288_H44441003_PIP-SCONN,HA
PVTT_ABC                 J6T1             221      SCONN288_H44441003_PIP-SCONN,HA
PVTT_ABC                 J6U1             77       SCONN288_H44441003_PIP-SCONN,HA
PVTT_ABC                 J6U1             221      SCONN288_H44441003_PIP-SCONN,HA
PVTT_ABC                 J6U2             77       SCONN288_H44441003_PIP-SCONN,HA
PVTT_ABC                 J6U2             221      SCONN288_H44441003_PIP-SCONN,HA
PVTT_ABC                 R6U16            2        RES_0402-51.1,1.0%,1/16W,CHIP,A
PVTT_ABC                 SH5U1            2        SHUNT_SH0201-EMPTY,N_A
PVTT_DEF                 C4A1             1        CAP_0805LF-22UF,4V,20%,X6S,C95A
PVTT_DEF                 C5L4             1        CAP_A_0603V-47UF,4V,20%,X5R,60A
PVTT_DEF                 C5L5             1        CAP_A_0603V-47UF,4V,20%,X5R,60A
PVTT_DEF                 C5M13            1        CAP_A_0603V-47UF,4V,20%,X5R,60A
PVTT_DEF                 EU4A1            9        MIC5166_DFN-IC,H55101-001
PVTT_DEF                 J4A1             77       SCONN288_H44441004_PIP-SCONN,HA
PVTT_DEF                 J4A1             221      SCONN288_H44441004_PIP-SCONN,HA
PVTT_DEF                 J4A2             77       SCONN288_H44441004_PIP-SCONN,HA
PVTT_DEF                 J4A2             221      SCONN288_H44441004_PIP-SCONN,HA
PVTT_DEF                 J4B1             77       SCONN288_H44441004_PIP-SCONN,HA
PVTT_DEF                 J4B1             221      SCONN288_H44441004_PIP-SCONN,HA
PVTT_DEF                 J6L1             77       SCONN288_H44441003_PIP-SCONN,HA
PVTT_DEF                 J6L1             221      SCONN288_H44441003_PIP-SCONN,HA
PVTT_DEF                 J6L2             77       SCONN288_H44441003_PIP-SCONN,HA
PVTT_DEF                 J6L2             221      SCONN288_H44441003_PIP-SCONN,HA
PVTT_DEF                 J6M1             77       SCONN288_H44441003_PIP-SCONN,HA
PVTT_DEF                 J6M1             221      SCONN288_H44441003_PIP-SCONN,HA
PVTT_DEF                 R4A1             2        RES_0402-51.1,1.0%,1/16W,CHIP,A
PVTT_DEF                 SH5L1            2        SHUNT_SH0201-EMPTY,N_A
PVTT_GHJ                 C2F2             1        CAP_A_0603V-47UF,4V,20%,X5R,60A
PVTT_GHJ                 C4G20            1        CAP_0805LF-22UF,4V,20%,X6S,C95A
PVTT_GHJ                 C8T3             1        CAP_A_0603V-47UF,4V,20%,X5R,60A
PVTT_GHJ                 C8U10            1        CAP_A_0603V-47UF,4V,20%,X5R,60A
PVTT_GHJ                 EU4G2            9        MIC5166_DFN-IC,H55101-001
PVTT_GHJ                 J1G1             77       SCONN288_H44441004_PIP-SCONN,HA
PVTT_GHJ                 J1G1             221      SCONN288_H44441004_PIP-SCONN,HA
PVTT_GHJ                 J1G2             77       SCONN288_H44441004_PIP-SCONN,HA
PVTT_GHJ                 J1G2             221      SCONN288_H44441004_PIP-SCONN,HA
PVTT_GHJ                 J1G3             77       SCONN288_H44441004_PIP-SCONN,HA
PVTT_GHJ                 J1G3             221      SCONN288_H44441004_PIP-SCONN,HA
PVTT_GHJ                 J9T1             77       SCONN288_H44441003_PIP-SCONN,HA
PVTT_GHJ                 J9T1             221      SCONN288_H44441003_PIP-SCONN,HA
PVTT_GHJ                 J9U1             77       SCONN288_H44441003_PIP-SCONN,HA
PVTT_GHJ                 J9U1             221      SCONN288_H44441003_PIP-SCONN,HA
PVTT_GHJ                 J9U2             77       SCONN288_H44441003_PIP-SCONN,HA
PVTT_GHJ                 J9U2             221      SCONN288_H44441003_PIP-SCONN,HA
PVTT_GHJ                 R6U8             2        RES_0402-51.1,1.0%,1/16W,CHIP,A
PVTT_GHJ                 SH8U1            2        SHUNT_SH0201-EMPTY,N_A
PVTT_KLM                 C4A13            1        CAP_0805LF-22UF,4V,20%,X6S,C95A
PVTT_KLM                 C8L3             1        CAP_A_0603V-47UF,4V,20%,X5R,60A
PVTT_KLM                 C8L4             1        CAP_A_0603V-47UF,4V,20%,X5R,60A
PVTT_KLM                 C8M12            1        CAP_A_0603V-47UF,4V,20%,X5R,60A
PVTT_KLM                 EU4A2            9        MIC5166_DFN-IC,H55101-001
PVTT_KLM                 J1A1             77       SCONN288_H44441004_PIP-SCONN,HA
PVTT_KLM                 J1A1             221      SCONN288_H44441004_PIP-SCONN,HA
PVTT_KLM                 J1A2             77       SCONN288_H44441004_PIP-SCONN,HA
PVTT_KLM                 J1A2             221      SCONN288_H44441004_PIP-SCONN,HA
PVTT_KLM                 J1B1             77       SCONN288_H44441004_PIP-SCONN,HA
PVTT_KLM                 J1B1             221      SCONN288_H44441004_PIP-SCONN,HA
PVTT_KLM                 J9L1             77       SCONN288_H44441003_PIP-SCONN,HA
PVTT_KLM                 J9L1             221      SCONN288_H44441003_PIP-SCONN,HA
PVTT_KLM                 J9L2             77       SCONN288_H44441003_PIP-SCONN,HA
PVTT_KLM                 J9L2             221      SCONN288_H44441003_PIP-SCONN,HA
PVTT_KLM                 J9M1             77       SCONN288_H44441003_PIP-SCONN,HA
PVTT_KLM                 J9M1             221      SCONN288_H44441003_PIP-SCONN,HA
PVTT_KLM                 R6L7             2        RES_0402-51.1,1.0%,1/16W,CHIP,A
PVTT_KLM                 SH8L1            2        SHUNT_SH0201-EMPTY,N_A
PWRGD_CPU0_DRAMPWROK_ABC_G R3P38            2        RES_0402-64.9,1.0%,1/16W,CHIP,A
PWRGD_CPU0_DRAMPWROK_ABC_G U3P1             3        GTL2014_SM-IC,D66151-001
PWRGD_CPU0_DRAMPWROK_ABC_G U5D1             AN30     SKX_EXT_B_BGA1-IC,TBD
PWRGD_CPU0_DRAMPWROK_DEF_G R3P29            2        RES_0402-64.9,1.0%,1/16W,CHIP,A
PWRGD_CPU0_DRAMPWROK_DEF_G U3P1             2        GTL2014_SM-IC,D66151-001
PWRGD_CPU0_DRAMPWROK_DEF_G U5D1             CR28     SKX_EXT_B_BGA1-IC,TBD
PWRGD_CPU0_G             R6D8             2        RES_0402-49.9,1%,1/16W,CHIP,G2A
PWRGD_CPU0_G             R9B14            1        RES_0402-1.00K,1%,1/16W,CHIP,GA
PWRGD_CPU0_G             U3P1             6        GTL2014_SM-IC,D66151-001
PWRGD_CPU0_G             U5D1             BC24     SKX_EXT_B_BGA1-IC,TBD
PWRGD_CPU0_G_R           J9B4             7        SCONN10_C12536004_SMLF-CONN,C1A
PWRGD_CPU0_G_R           R9B14            2        RES_0402-1.00K,1%,1/16W,CHIP,GA
PWRGD_CPU0_LVC3          U3P1             9        GTL2014_SM-IC,D66151-001
PWRGD_CPU0_LVC3          U8D7             L5       LCMXO2_A_256BGA-IC,H63395-001
PWRGD_CPU1_DRAMPWROK_GHJ_G R3D21            2        RES_0402-64.9,1.0%,1/16W,CHIP,A
PWRGD_CPU1_DRAMPWROK_GHJ_G U2D1             AN30     SKX_EXT_B_BGA1-IC,TBD
PWRGD_CPU1_DRAMPWROK_GHJ_G U4C2             3        GTL2014_SM-IC,D66151-001
PWRGD_CPU1_DRAMPWROK_KLM_G R7M9             2        RES_0402-64.9,1.0%,1/16W,CHIP,A
PWRGD_CPU1_DRAMPWROK_KLM_G U2D1             CR28     SKX_EXT_B_BGA1-IC,TBD
PWRGD_CPU1_DRAMPWROK_KLM_G U4C2             2        GTL2014_SM-IC,D66151-001
PWRGD_CPU1_G             R3D15            2        RES_0402-49.9,1%,1/16W,CHIP,G2A
PWRGD_CPU1_G             U2D1             BC24     SKX_EXT_B_BGA1-IC,TBD
PWRGD_CPU1_G             U4C2             6        GTL2014_SM-IC,D66151-001
PWRGD_CPU1_LVC3          U4C2             9        GTL2014_SM-IC,D66151-001
PWRGD_CPU1_LVC3          U8D7             M10      LCMXO2_A_256BGA-IC,H63395-001
PWRGD_CPUPWRGD           R3R3             2        RES_0402-33.2,1%,1/16W,CHIP,G2A
PWRGD_CPUPWRGD           U8D7             F13      LCMXO2_A_256BGA-IC,H63395-001
PWRGD_CPUPWRGD_GTL       U3P2             2        GTL2014_SM-IC,D66151-001
PWRGD_CPUPWRGD_GTL       U7C1             R9       LBG_CORE_QAT_EXT_D_BGA1-IC,H91A
PWRGD_CPUPWRGD_R1        R3R3             1        RES_0402-33.2,1%,1/16W,CHIP,G2A
PWRGD_CPUPWRGD_R1        U3P2             13       GTL2014_SM-IC,D66151-001
PWRGD_DRAMPWRGD          U3P1             12       GTL2014_SM-IC,D66151-001
PWRGD_DRAMPWRGD          U3P1             13       GTL2014_SM-IC,D66151-001
PWRGD_DRAMPWRGD          U4C2             12       GTL2014_SM-IC,D66151-001
PWRGD_DRAMPWRGD          U4C2             13       GTL2014_SM-IC,D66151-001
PWRGD_DRAMPWRGD          U8D7             T15      LCMXO2_A_256BGA-IC,H63395-001
PWRGD_DSW_PWROK          CR7E1            2        DIODE_SMLF-BAT54WS,IC,C73510-0A
PWRGD_DSW_PWROK          EU9F3            24       PI7C9X1172_QFN-IC,H66899-001
PWRGD_DSW_PWROK          R3P44            2        RES_0402-4.75K,1%,1/16W,CHIP,GA
PWRGD_DSW_PWROK          U7C1             K13      LBG_CORE_QAT_EXT_D_BGA1-IC,H91A
PWRGD_DSW_PWROK          U7D3             4        ADM1085_SMT-IC,H46130-001
PWRGD_DSW_PWROK          U8D2             2        TTL1G07_A_SOP-74LVC1G07,IC,C88B
PWRGD_DSW_PWROK          U8D7             B11      LCMXO2_A_256BGA-IC,H63395-001
PWRGD_DSW_PWROK          U9P2             6        TPS3700_SM-IC,H69492-001
PWRGD_P12V_HSC           C8E3             1        CAP_A_0402V-0.1UF,16V,10%,X7R,A
PWRGD_P12V_HSC           CR8E1            1        DIODE_SMLF-BAT54WS,IC,C73510-0A
PWRGD_P12V_HSC           R1D33            2        RES_0402-33.2,1%,1/16W,CHIP,G2A
PWRGD_P12V_HSC           U8E2             3        ADM809_SMLF-IC,D23047-001-GND=A
PWRGD_P12V_HSC_DLY       C8E13            1        CAP_0402LF-1000PF,50V,10%,EMPTA
PWRGD_P12V_HSC_DLY       CR8E1            2        DIODE_SMLF-BAT54WS,IC,C73510-0A
PWRGD_P12V_HSC_DLY       R8E7             2        RES_0402-22.1,1.0%,1/16W,CHIP,A
PWRGD_P12V_HSC_DLY       R8E33            1        RES_0402-0.0,5%,1/16W,CHIP,G21A
PWRGD_P12V_HSC_DLY       U8E1             10       TTL08_QFN15-74LVC08A,IC,D90404B
PWRGD_P12V_HSC_DLY_R     R8E7             1        RES_0402-22.1,1.0%,1/16W,CHIP,A
PWRGD_P12V_HSC_DLY_R     U8E2             2        ADM809_SMLF-IC,D23047-001-GND=A
PWRGD_P12V_MAIN          R8D42            2        RES_0402-100.0,1%,1/16W,CHIP,GA
PWRGD_P12V_MAIN          U8D7             B5       LCMXO2_A_256BGA-IC,H63395-001
PWRGD_P12V_MAIN_R        R8D41            2        RES_0402-10.0K,1%,1/16W,CHIP,GA
PWRGD_P12V_MAIN_R        R8D42            1        RES_0402-100.0,1%,1/16W,CHIP,GA
PWRGD_P12V_MAIN_R        U8D8             6        TPS3700_SM-IC,H69492-001
PWRGD_P12V_R             EU1D2            18       ADM1278_SM-IC,G99251-001
PWRGD_P12V_R             R1D31            1        RES_0402-6.19K,1%,1/16W,CHIP,GA
PWRGD_P12V_R             R1D33            1        RES_0402-33.2,1%,1/16W,CHIP,G2A
PWRGD_P12V_R             R9P18            2        RES_0402-15.0K,1%,1/16W,CHIP,GA
PWRGD_P1V26_BMC_STBY     R9F11            2        RES_0402-22.1,1.0%,1/16W,CHIP,A
PWRGD_P1V26_BMC_STBY     U8D7             E7       LCMXO2_A_256BGA-IC,H63395-001
PWRGD_P1V26_BMC_STBY_R   C9F8             1        CAP_0402LF-1000PF,50V,10%,X7R,A
PWRGD_P1V26_BMC_STBY_R   EU9F1            5        RT9059_DFN-IC,H65765-001
PWRGD_P1V26_BMC_STBY_R   R9F11            1        RES_0402-22.1,1.0%,1/16W,CHIP,A
PWRGD_P1V26_BMC_STBY_R   R9F13            2        RES_0402-10.0K,1%,1/16W,CHIP,GA
PWRGD_P1V538_BMC_STBY    C9F9             1        CAP_0402LF-1000PF,50V,10%,EMPTA
PWRGD_P1V538_BMC_STBY    EU9F1            6        RT9059_DFN-IC,H65765-001
PWRGD_P1V538_BMC_STBY    R1T9             2        RES_0402-22.1,1.0%,1/16W,CHIP,A
PWRGD_P1V538_BMC_STBY_R  C9F10            1        CAP_0402LF-1000PF,50V,10%,X7R,A
PWRGD_P1V538_BMC_STBY_R  EU9F2            5        RT9059_DFN-IC,H65765-001
PWRGD_P1V538_BMC_STBY_R  R1T9             1        RES_0402-22.1,1.0%,1/16W,CHIP,A
PWRGD_P1V538_BMC_STBY_R  R9F12            2        RES_0402-10.0K,1%,1/16W,CHIP,GA
PWRGD_P1V8MCP_CPU0       J6B1             B15      SCONN120_H61426002_SM-CONN,H61A
PWRGD_P1V8MCP_CPU0       U8D7             D15      LCMXO2_A_256BGA-IC,H63395-001
PWRGD_P1V8MCP_CPU1       J4B2             B15      SCONN120_H61426002_SM-CONN,H61A
PWRGD_P1V8MCP_CPU1       U8D7             D16      LCMXO2_A_256BGA-IC,H63395-001
PWRGD_P1V8_PCH_STBY      R2L17            1        RES_0402-0.0,5%,1/16W,CHIP,G21A
PWRGD_P1V8_PCH_STBY      R8A11            2        RES_0402-22.1,1.0%,1/16W,CHIP,A
PWRGD_P1V8_PCH_STBY_R    C8A11            1        CAP_0402LF-1000PF,50V,10%,X7R,A
PWRGD_P1V8_PCH_STBY_R    EU8A2            5        RT9059_DFN-IC,H65765-001
PWRGD_P1V8_PCH_STBY_R    R8A10            2        RES_0402-5.11K,1%,1/16W,CHIP,GA
PWRGD_P1V8_PCH_STBY_R    R8A11            1        RES_0402-22.1,1.0%,1/16W,CHIP,A
PWRGD_P3V3               R1L12            1        RES_0402-0.0,5%,1/16W,CHIP,G21A
PWRGD_P3V3               R1L16            2        RES_0402-49.9,1%,1/16W,CHIP,G2A
PWRGD_P3V3               U8D7             H6       LCMXO2_A_256BGA-IC,H63395-001
PWRGD_P3V3_R             R1L12            2        RES_0402-0.0,5%,1/16W,CHIP,G21A
PWRGD_P3V3_R             U1L2             1        TTL1G86_SOTLF-74AHCT1G86,IC,D3B
PWRGD_P3V3_R1            R1L16            1        RES_0402-49.9,1%,1/16W,CHIP,G2A
PWRGD_P3V3_R1            U1L3             2        ADM809_SMLF-IC,D23047-001-GND=A
PWRGD_P3V3_STBY          C8A10            1        CAP_0402LF-1000PF,50V,10%,EMPTA
PWRGD_P3V3_STBY          C9F6             1        CAP_0402LF-1000PF,50V,10%,EMPTA
PWRGD_P3V3_STBY          CR7E1            1        DIODE_SMLF-BAT54WS,IC,C73510-0A
PWRGD_P3V3_STBY          EU8A2            6        RT9059_DFN-IC,H65765-001
PWRGD_P3V3_STBY          EU8F2            40       ICS9FGP204_MLFP-IC,E95226-001
PWRGD_P3V3_STBY          EU9F2            6        RT9059_DFN-IC,H65765-001
PWRGD_P3V3_STBY          J7G2             5        CONN8_C77962004_PIP-CONN,C7796A
PWRGD_P3V3_STBY          R3P50            2        RES_0402-10.0K,1%,1/16W,EMPTY,A
PWRGD_P3V3_STBY          R8F10            2        RES_0402-22.1,1.0%,1/16W,CHIP,A
PWRGD_P3V3_STBY          U7D3             1        ADM1085_SMT-IC,H46130-001
PWRGD_P3V3_STBY          U8D7             L12      LCMXO2_A_256BGA-IC,H63395-001
PWRGD_P3V3_STBY_R        C8F2             1        CAP_0402LF-1000PF,50V,10%,X7R,A
PWRGD_P3V3_STBY_R        EU8F1            9        RT8240_QFN-IC,H66262-001
PWRGD_P3V3_STBY_R        R8F5             2        RES_0402-1.00K,1%,1/16W,CHIP,GA
PWRGD_P3V3_STBY_R        R8F10            1        RES_0402-22.1,1.0%,1/16W,CHIP,A
PWRGD_P5V                R2P20            2        RES_0402-100.0,1%,1/16W,CHIP,GA
PWRGD_P5V                U8D7             J6       LCMXO2_A_256BGA-IC,H63395-001
PWRGD_P5V_N              Q2P2             1        FET_N_SOT23-2N7002,FET,C79254-A
PWRGD_P5V_N              R2P18            2        RES_0402-10.0K,1%,1/16W,CHIP,GA
PWRGD_P5V_N              U8D8             1        TPS3700_SM-IC,H69492-001
PWRGD_P5V_R              Q2P2             3        FET_N_SOT23-2N7002,FET,C79254-A
PWRGD_P5V_R              R2P20            1        RES_0402-100.0,1%,1/16W,CHIP,GA
PWRGD_P5V_R              R2P21            2        RES_0402-10.0K,1%,1/16W,CHIP,GA
PWRGD_P5V_STBY           C8E17            1        CAP_0402LF-1000PF,50V,10%,EMPTA
PWRGD_P5V_STBY           R7E15            2        RES_0402-22.1,1.0%,1/16W,CHIP,A
PWRGD_P5V_STBY           R8F1             1        RES_0402-10.0K,1%,1/16W,EMPTY,A
PWRGD_P5V_STBY           R8F2             1        RES_0402-0.0,5%,1/16W,CHIP,G21A
PWRGD_P5V_STBY_R         C7E10            1        CAP_0402LF-1000PF,50V,10%,X7R,A
PWRGD_P5V_STBY_R         EU7E2            14       TPS54821_LCC-IC,H63269-001
PWRGD_P5V_STBY_R         R7E12            2        RES_0402-1.00K,1%,1/16W,CHIP,GA
PWRGD_P5V_STBY_R         R7E15            1        RES_0402-22.1,1.0%,1/16W,CHIP,A
PWRGD_PCH_PWROK          R3N3             2        RES_0402-2.0K,1%,1/16W,CHIP,G2A
PWRGD_PCH_PWROK          U7C1             R17      LBG_CORE_QAT_EXT_D_BGA1-IC,H91A
PWRGD_PCH_PWROK          U8D7             C16      LCMXO2_A_256BGA-IC,H63395-001
PWRGD_PCH_PWROK          U9F4             C15      AST1250_BGA-IC,G85138-002
PWRGD_PVCCIN_CPU0        R4D63            2        RES_0402-22.1,1.0%,1/16W,CHIP,A
PWRGD_PVCCIN_CPU0        U1L1             1        TTL3126_QFNLF-74CBTLV3126,IC,DB
PWRGD_PVCCIN_CPU0        U1L1             4        TTL3126_QFNLF-74CBTLV3126,IC,DB
PWRGD_PVCCIN_CPU0        U1L1             10       TTL3126_QFNLF-74CBTLV3126,IC,DB
PWRGD_PVCCIN_CPU0        U1L1             13       TTL3126_QFNLF-74CBTLV3126,IC,DB
PWRGD_PVCCIN_CPU0        U1L5             1        TTL3126_QFNLF-74CBTLV3126,IC,DB
PWRGD_PVCCIN_CPU0        U1L5             4        TTL3126_QFNLF-74CBTLV3126,IC,DB
PWRGD_PVCCIN_CPU0        U1L5             10       TTL3126_QFNLF-74CBTLV3126,IC,DB
PWRGD_PVCCIN_CPU0        U1L5             13       TTL3126_QFNLF-74CBTLV3126,IC,DB
PWRGD_PVCCIN_CPU0        U8D7             K5       LCMXO2_A_256BGA-IC,H63395-001
PWRGD_PVCCIN_CPU1        R1C30            2        RES_0402-22.1,1.0%,1/16W,CHIP,A
PWRGD_PVCCIN_CPU1        U8D7             N1       LCMXO2_A_256BGA-IC,H63395-001
PWRGD_PVCCIOMCP_CPU0     J6B1             B16      SCONN120_H61426002_SM-CONN,H61A
PWRGD_PVCCIOMCP_CPU0     U8D7             N6       LCMXO2_A_256BGA-IC,H63395-001
PWRGD_PVCCIOMCP_CPU1     J4B2             B16      SCONN120_H61426002_SM-CONN,H61A
PWRGD_PVCCIOMCP_CPU1     U8D7             T5       LCMXO2_A_256BGA-IC,H63395-001
PWRGD_PVCCIO_CPU0        R3P20            2        RES_0402-22.1,1.0%,1/16W,CHIP,A
PWRGD_PVCCIO_CPU0        U7D1             1        74CBTLV1G125_SMLF-IC,C88177-00A
PWRGD_PVCCIO_CPU0        U8D7             L8       LCMXO2_A_256BGA-IC,H63395-001
PWRGD_PVCCIO_CPU0_R      C3P6             1        CAP_0402LF-1000PF,50V,10%,X7R,A
PWRGD_PVCCIO_CPU0_R      EU3P1            9        PXE1110B_QFN-IC,H89187-001
PWRGD_PVCCIO_CPU0_R      R3P20            1        RES_0402-22.1,1.0%,1/16W,CHIP,A
PWRGD_PVCCIO_CPU0_R      R3P25            2        RES_0402-1.00K,1%,1/16W,CHIP,GA
PWRGD_PVCCIO_CPU1        R4D46            2        RES_0402-22.1,1.0%,1/16W,CHIP,A
PWRGD_PVCCIO_CPU1        U8D7             L16      LCMXO2_A_256BGA-IC,H63395-001
PWRGD_PVCCIO_CPU1_R      C4D33            1        CAP_0402LF-1000PF,50V,10%,X7R,A
PWRGD_PVCCIO_CPU1_R      EU4D5            9        PXE1110B_QFN-IC,H89187-001
PWRGD_PVCCIO_CPU1_R      R4D42            2        RES_0402-1.00K,1%,1/16W,CHIP,GA
PWRGD_PVCCIO_CPU1_R      R4D46            1        RES_0402-22.1,1.0%,1/16W,CHIP,A
PWRGD_PVCCMCP_CPU0       J6B1             D20      SCONN120_H61426002_SM-CONN,H61A
PWRGD_PVCCMCP_CPU0       U8D7             P5       LCMXO2_A_256BGA-IC,H63395-001
PWRGD_PVCCMCP_CPU1       J4B2             D20      SCONN120_H61426002_SM-CONN,H61A
PWRGD_PVCCMCP_CPU1       U8D7             L4       LCMXO2_A_256BGA-IC,H63395-001
PWRGD_PVDDQ_ABC          R4G23            1        RES_0402-0.0,5%,1/16W,CHIP,G21A
PWRGD_PVDDQ_ABC          R7F24            2        RES_0402-22.1,1.0%,1/16W,CHIP,A
PWRGD_PVDDQ_ABC_R        C7F14            1        CAP_0402LF-1000PF,50V,10%,X7R,A
PWRGD_PVDDQ_ABC_R        EU7G1            9        PXM1310B_QFN-IC,H89186-001
PWRGD_PVDDQ_ABC_R        R7F22            2        RES_0402-1.00K,1%,1/16W,CHIP,GA
PWRGD_PVDDQ_ABC_R        R7F24            1        RES_0402-22.1,1.0%,1/16W,CHIP,A
PWRGD_PVDDQ_DEF          R3M3             2        RES_0402-22.1,1.0%,1/16W,CHIP,A
PWRGD_PVDDQ_DEF          R4A2             1        RES_0402-0.0,5%,1/16W,CHIP,G21A
PWRGD_PVDDQ_DEF_R        C7B3             1        CAP_0402LF-1000PF,50V,10%,X7R,A
PWRGD_PVDDQ_DEF_R        EU7A5            9        PXM1310B_QFN-IC,H89186-001
PWRGD_PVDDQ_DEF_R        R3M3             1        RES_0402-22.1,1.0%,1/16W,CHIP,A
PWRGD_PVDDQ_DEF_R        R7B5             2        RES_0402-1.00K,1%,1/16W,CHIP,GA
PWRGD_PVDDQ_GHJ          R1G12            2        RES_0402-22.1,1.0%,1/16W,CHIP,A
PWRGD_PVDDQ_GHJ          R4G16            1        RES_0402-0.0,5%,1/16W,CHIP,G21A
PWRGD_PVDDQ_GHJ_R        C1G21            1        CAP_0402LF-1000PF,50V,10%,X7R,A
PWRGD_PVDDQ_GHJ_R        EU1G2            9        PXM1310B_QFN-IC,H89186-001
PWRGD_PVDDQ_GHJ_R        R1G12            1        RES_0402-22.1,1.0%,1/16W,CHIP,A
PWRGD_PVDDQ_GHJ_R        R1G16            2        RES_0402-1.00K,1%,1/16W,CHIP,GA
PWRGD_PVDDQ_KLM          R1B5             2        RES_0402-22.1,1.0%,1/16W,CHIP,A
PWRGD_PVDDQ_KLM          R4A3             1        RES_0402-0.0,5%,1/16W,CHIP,G21A
PWRGD_PVDDQ_KLM_R        C1B4             1        CAP_0402LF-1000PF,50V,10%,X7R,A
PWRGD_PVDDQ_KLM_R        EU1B1            9        PXM1310B_QFN-IC,H89186-001
PWRGD_PVDDQ_KLM_R        R1B2             2        RES_0402-1.00K,1%,1/16W,CHIP,GA
PWRGD_PVDDQ_KLM_R        R1B5             1        RES_0402-22.1,1.0%,1/16W,CHIP,A
PWRGD_PVNN_P1V05_PCH     R2L16            2        RES_0402-22.1,1.0%,1/16W,CHIP,A
PWRGD_PVNN_P1V05_PCH     U8D7             P8       LCMXO2_A_256BGA-IC,H63395-001
PWRGD_PVNN_PCH_R         C8A9             1        CAP_0402LF-1000PF,50V,10%,X7R,A
PWRGD_PVNN_PCH_R         EU8A1            9        PXE1110B_QFN-IC,H89187-001
PWRGD_PVNN_PCH_R         R2L16            1        RES_0402-22.1,1.0%,1/16W,CHIP,A
PWRGD_PVNN_PCH_R         R8A6             2        RES_0402-1.00K,1%,1/16W,CHIP,GA
PWRGD_PVPP_ABC           J8B1             19       SCONN24_H46321001_SM-SCONN,H46A
PWRGD_PVPP_ABC           R7F16            2        RES_0402-22.1,1.0%,1/16W,CHIP,A
PWRGD_PVPP_ABC           U8D7             N7       LCMXO2_A_256BGA-IC,H63395-001
PWRGD_PVPP_ABC_R         C7F11            1        CAP_0402LF-1000PF,50V,10%,X7R,A
PWRGD_PVPP_ABC_R         EU7F1            7        NCP3232L_SM-IC,H86355-001
PWRGD_PVPP_ABC_R         R7F16            1        RES_0402-22.1,1.0%,1/16W,CHIP,A
PWRGD_PVPP_ABC_R         R7F19            2        RES_0402-1.00K,1%,1/16W,CHIP,GA
PWRGD_PVPP_DEF           R7B12            2        RES_0402-22.1,1.0%,1/16W,CHIP,A
PWRGD_PVPP_DEF           U8D7             M6       LCMXO2_A_256BGA-IC,H63395-001
PWRGD_PVPP_DEF_R         C7B12            1        CAP_0402LF-1000PF,50V,10%,X7R,A
PWRGD_PVPP_DEF_R         EU7B1            7        NCP3232L_SM-IC,H86355-001
PWRGD_PVPP_DEF_R         R7B12            1        RES_0402-22.1,1.0%,1/16W,CHIP,A
PWRGD_PVPP_DEF_R         R7B17            2        RES_0402-1.00K,1%,1/16W,CHIP,GA
PWRGD_PVPP_GHJ           R4G12            2        RES_0402-22.1,1.0%,1/16W,CHIP,A
PWRGD_PVPP_GHJ           U8D7             M2       LCMXO2_A_256BGA-IC,H63395-001
PWRGD_PVPP_GHJ_R         C4G9             1        CAP_0402LF-1000PF,50V,10%,X7R,A
PWRGD_PVPP_GHJ_R         EU4G1            7        NCP3232L_SM-IC,H86355-001
PWRGD_PVPP_GHJ_R         R4G12            1        RES_0402-22.1,1.0%,1/16W,CHIP,A
PWRGD_PVPP_GHJ_R         R4G14            2        RES_0402-1.00K,1%,1/16W,CHIP,GA
PWRGD_PVPP_KLM           R4B7             2        RES_0402-22.1,1.0%,1/16W,CHIP,A
PWRGD_PVPP_KLM           U8D7             N2       LCMXO2_A_256BGA-IC,H63395-001
PWRGD_PVPP_KLM_R         C4B8             1        CAP_0402LF-1000PF,50V,10%,X7R,A
PWRGD_PVPP_KLM_R         EU4A3            7        NCP3232L_SM-IC,H86355-001
PWRGD_PVPP_KLM_R         R4B7             1        RES_0402-22.1,1.0%,1/16W,CHIP,A
PWRGD_PVPP_KLM_R         R4B10            2        RES_0402-1.00K,1%,1/16W,CHIP,GA
PWRGD_PVSA_CPU0          R4D65            2        RES_0402-33.2,1%,1/16W,CHIP,G2A
PWRGD_PVSA_CPU0          U8D7             L1       LCMXO2_A_256BGA-IC,H63395-001
PWRGD_PVSA_CPU0_R        EU4D4            15       PXE1610B_QFN-IC,H79206-001
PWRGD_PVSA_CPU0_R        R4D65            1        RES_0402-33.2,1%,1/16W,CHIP,G2A
PWRGD_PVSA_CPU0_R        R4E5             2        RES_0402-1.00K,1%,1/16W,CHIP,GA
PWRGD_PVSA_CPU1          R1D1             2        RES_0402-33.2,1%,1/16W,CHIP,G2A
PWRGD_PVSA_CPU1          U8D7             T4       LCMXO2_A_256BGA-IC,H63395-001
PWRGD_PVSA_CPU1_R        EU1C2            15       PXE1610B_QFN-IC,H79206-001
PWRGD_PVSA_CPU1_R        R1D1             1        RES_0402-33.2,1%,1/16W,CHIP,G2A
PWRGD_PVSA_CPU1_R        R1D8             2        RES_0402-1.00K,1%,1/16W,CHIP,GA
PWRGD_PVTT_ABC_CPU0_R    C4G14            1        CAP_0402LF-1000PF,50V,10%,X7R,A
PWRGD_PVTT_ABC_CPU0_R    EU4G3            5        MIC5166_DFN-IC,H55101-001
PWRGD_PVTT_ABC_CPU0_R    R4G18            2        RES_0402-10.0K,1%,1/16W,CHIP,GA
PWRGD_PVTT_ABC_CPU0_R    R4G19            1        RES_0402-33.2,1%,1/16W,CHIP,G2A
PWRGD_PVTT_CPU0          R4A6             2        RES_0402-33.2,1%,1/16W,CHIP,G2A
PWRGD_PVTT_CPU0          R4G19            2        RES_0402-33.2,1%,1/16W,CHIP,G2A
PWRGD_PVTT_CPU0          U8D7             B4       LCMXO2_A_256BGA-IC,H63395-001
PWRGD_PVTT_CPU1          R4A4             2        RES_0402-33.2,1%,1/16W,CHIP,G2A
PWRGD_PVTT_CPU1          R4G15            2        RES_0402-33.2,1%,1/16W,CHIP,G2A
PWRGD_PVTT_CPU1          U8D7             R7       LCMXO2_A_256BGA-IC,H63395-001
PWRGD_PVTT_DEF_CPU0_R    C4A12            1        CAP_0402LF-1000PF,50V,10%,X7R,A
PWRGD_PVTT_DEF_CPU0_R    EU4A1            5        MIC5166_DFN-IC,H55101-001
PWRGD_PVTT_DEF_CPU0_R    R4A6             1        RES_0402-33.2,1%,1/16W,CHIP,G2A
PWRGD_PVTT_DEF_CPU0_R    R6L9             2        RES_0402-10.0K,1%,1/16W,CHIP,GA
PWRGD_PVTT_GHJ_CPU1_R    C4G13            1        CAP_0402LF-1000PF,50V,10%,X7R,A
PWRGD_PVTT_GHJ_CPU1_R    EU4G2            5        MIC5166_DFN-IC,H55101-001
PWRGD_PVTT_GHJ_CPU1_R    R4G15            1        RES_0402-33.2,1%,1/16W,CHIP,G2A
PWRGD_PVTT_GHJ_CPU1_R    R4G17            2        RES_0402-10.0K,1%,1/16W,CHIP,GA
PWRGD_PVTT_KLM_CPU1_R    C4A3             1        CAP_0402LF-1000PF,50V,10%,X7R,A
PWRGD_PVTT_KLM_CPU1_R    EU4A2            5        MIC5166_DFN-IC,H55101-001
PWRGD_PVTT_KLM_CPU1_R    R4A4             1        RES_0402-33.2,1%,1/16W,CHIP,G2A
PWRGD_PVTT_KLM_CPU1_R    R4A5             2        RES_0402-10.0K,1%,1/16W,CHIP,GA
PWRGD_SYS_PWROK          R2N12            2        RES_0402-10.0K,1%,1/16W,EMPTY,A
PWRGD_SYS_PWROK          U7C1             BY19     LBG_CORE_QAT_EXT_D_BGA1-IC,H91A
PWRGD_SYS_PWROK          U8D7             D14      LCMXO2_A_256BGA-IC,H63395-001
PWRGD_SYS_PWROK          U9F4             B15      AST1250_BGA-IC,G85138-002
RCC_DFX_1940_1           TC1A1            2        RCC_DFX1940_ID4-EMPTY,N_A
RCC_DFX_1940_1           TC1A1            3        RCC_DFX1940_ID4-EMPTY,N_A
RCC_DFX_1940_2           TC9A1            2        RCC_DFX1940_ID4-EMPTY,N_A
RCC_DFX_1940_2           TC9A1            3        RCC_DFX1940_ID4-EMPTY,N_A
RCC_DFX_1940_3           TC9F1            2        RCC_DFX1940_ID4-EMPTY,N_A
RCC_DFX_1940_3           TC9F1            3        RCC_DFX1940_ID4-EMPTY,N_A
RCC_DFX_1940_4           TC1G1            2        RCC_DFX1940_ID4-EMPTY,N_A
RCC_DFX_1940_4           TC1G1            3        RCC_DFX1940_ID4-EMPTY,N_A
RMII_BMC_OCP_CRSDV       R1M15            1        RES_0402-0.0,5%,1/16W,CHIP,G21A
RMII_BMC_OCP_CRSDV       U9F4             A11      AST1250_BGA-IC,G85138-002
RMII_BMC_OCP_CRSDV_R     J9B3             27       SCONN120_A28699018_SM-SCONN,A2A
RMII_BMC_OCP_CRSDV_R     R1M15            2        RES_0402-0.0,5%,1/16W,CHIP,G21A
RMII_BMC_OCP_RXD0        R1M17            1        RES_0402-0.0,5%,1/16W,CHIP,G21A
RMII_BMC_OCP_RXD0        U9F4             C11      AST1250_BGA-IC,G85138-002
RMII_BMC_OCP_RXD0_R      J9B3             43       SCONN120_A28699018_SM-SCONN,A2A
RMII_BMC_OCP_RXD0_R      R1M17            2        RES_0402-0.0,5%,1/16W,CHIP,G21A
RMII_BMC_OCP_RXD1        R1M16            1        RES_0402-0.0,5%,1/16W,CHIP,G21A
RMII_BMC_OCP_RXD1        U9F4             B11      AST1250_BGA-IC,G85138-002
RMII_BMC_OCP_RXD1_R      J9B3             45       SCONN120_A28699018_SM-SCONN,A2A
RMII_BMC_OCP_RXD1_R      R1M16            2        RES_0402-0.0,5%,1/16W,CHIP,G21A
RMII_BMC_OCP_RXER        R1M18            2        RES_0402-0.0,5%,1/16W,CHIP,G21A
RMII_BMC_OCP_RXER        U9F4             E10      AST1250_BGA-IC,G85138-002
RMII_BMC_OCP_RXER_R      J9B3             36       SCONN120_A28699018_SM-SCONN,A2A
RMII_BMC_OCP_RXER_R      R1M18            1        RES_0402-0.0,5%,1/16W,CHIP,G21A
RMII_BMC_OCP_TXD0        J9B3             40       SCONN120_A28699018_SM-SCONN,A2A
RMII_BMC_OCP_TXD0        R8F31            2        RES_0402-22.1,1.0%,1/16W,CHIP,A
RMII_BMC_OCP_TXD0_R      R8F31            1        RES_0402-22.1,1.0%,1/16W,CHIP,A
RMII_BMC_OCP_TXD0_R      U9F4             C12      AST1250_BGA-IC,G85138-002
RMII_BMC_OCP_TXD1        J9B3             42       SCONN120_A28699018_SM-SCONN,A2A
RMII_BMC_OCP_TXD1        R8F28            2        RES_0402-22.1,1.0%,1/16W,CHIP,A
RMII_BMC_OCP_TXD1_R      R8F28            1        RES_0402-22.1,1.0%,1/16W,CHIP,A
RMII_BMC_OCP_TXD1_R      U9F4             D12      AST1250_BGA-IC,G85138-002
RMII_BMC_OCP_TXEN        J9B3             31       SCONN120_A28699018_SM-SCONN,A2A
RMII_BMC_OCP_TXEN        R8F30            2        RES_0402-22.1,1.0%,1/16W,CHIP,A
RMII_BMC_OCP_TXEN_R      R8F30            1        RES_0402-22.1,1.0%,1/16W,CHIP,A
RMII_BMC_OCP_TXEN_R      U9F4             A12      AST1250_BGA-IC,G85138-002
RMII_BMC_PCH_SPRNGVLLE_CRSDV R1T1             1        RES_0402-10.0K,1%,1/16W,CHIP,GA
RMII_BMC_PCH_SPRNGVLLE_CRSDV R3P2             1        RES_0402-0.0,5%,1/16W,CHIP,G21A
RMII_BMC_PCH_SPRNGVLLE_CRSDV R9F1             2        RES_0402-22.1,1.0%,1/16W,CHIP,A
RMII_BMC_PCH_SPRNGVLLE_CRSDV U9F4             D8       AST1250_BGA-IC,G85138-002
RMII_BMC_PCH_SPRNGVLLE_CRSDV_R EU9E1            3        SPRINGVILLE_SM1-IC,G47144-004
RMII_BMC_PCH_SPRNGVLLE_CRSDV_R R9F1             1        RES_0402-22.1,1.0%,1/16W,CHIP,A
RMII_BMC_PCH_SPRNGVLLE_CRSDV_R1 R3P2             2        RES_0402-0.0,5%,1/16W,CHIP,G21A
RMII_BMC_PCH_SPRNGVLLE_CRSDV_R1 U7C1             AN3      LBG_CORE_QAT_EXT_D_BGA1-IC,H91A
RMII_BMC_PCH_SPRNGVLLE_RXER R7C14            1        RES_0402-33.2,1%,1/16W,CHIP,G2A
RMII_BMC_PCH_SPRNGVLLE_RXER R7D13            2        RES_0402-8.2K,1%,1/16W,EMPTY,GA
RMII_BMC_PCH_SPRNGVLLE_RXER U9F4             C8       AST1250_BGA-IC,G85138-002
RMII_BMC_PCH_SPRNGVLLE_RXER_R R7C14            2        RES_0402-33.2,1%,1/16W,CHIP,G2A
RMII_BMC_PCH_SPRNGVLLE_RXER_R U7C1             AH2      LBG_CORE_QAT_EXT_D_BGA1-IC,H91A
RMII_BMC_PCH_SPRNGVLLE_TXD0 EU9E1            9        SPRINGVILLE_SM1-IC,G47144-004
RMII_BMC_PCH_SPRNGVLLE_TXD0 R1R4             2        RES_0402-10.0K,1%,1/16W,CHIP,GA
RMII_BMC_PCH_SPRNGVLLE_TXD0 R1T28            2        RES_0402-22.1,1.0%,1/16W,CHIP,A
RMII_BMC_PCH_SPRNGVLLE_TXD0 U7C1             AM2      LBG_CORE_QAT_EXT_D_BGA1-IC,H91A
RMII_BMC_PCH_SPRNGVLLE_TXD0_R R1T28            1        RES_0402-22.1,1.0%,1/16W,CHIP,A
RMII_BMC_PCH_SPRNGVLLE_TXD0_R U9F4             A10      AST1250_BGA-IC,G85138-002
RMII_BMC_PCH_SPRNGVLLE_TXD1 EU9E1            8        SPRINGVILLE_SM1-IC,G47144-004
RMII_BMC_PCH_SPRNGVLLE_TXD1 R2T45            2        RES_0402-22.1,1.0%,1/16W,CHIP,A
RMII_BMC_PCH_SPRNGVLLE_TXD1 R8F32            2        RES_0402-10.0K,1%,1/16W,CHIP,GA
RMII_BMC_PCH_SPRNGVLLE_TXD1 U7C1             AK2      LBG_CORE_QAT_EXT_D_BGA1-IC,H91A
RMII_BMC_PCH_SPRNGVLLE_TXD1_R R2T45            1        RES_0402-22.1,1.0%,1/16W,CHIP,A
RMII_BMC_PCH_SPRNGVLLE_TXD1_R U9F4             B10      AST1250_BGA-IC,G85138-002
RMII_BMC_PCH_SPRNGVLLE_TXEN EU9E1            7        SPRINGVILLE_SM1-IC,G47144-004
RMII_BMC_PCH_SPRNGVLLE_TXEN R8F33            2        RES_0402-22.1,1.0%,1/16W,CHIP,A
RMII_BMC_PCH_SPRNGVLLE_TXEN R9E13            1        RES_0402-10.0K,1%,1/16W,CHIP,GA
RMII_BMC_PCH_SPRNGVLLE_TXEN U7C1             AL3      LBG_CORE_QAT_EXT_D_BGA1-IC,H91A
RMII_BMC_SPRNGVLLE_TXEN_R R8F33            1        RES_0402-22.1,1.0%,1/16W,CHIP,A
RMII_BMC_SPRNGVLLE_TXEN_R U9F4             D9       AST1250_BGA-IC,G85138-002
RMII_PCH_SPRNGVLLE_ARB_IN R9E16            2        RES_0402-33.2,1%,1/16W,CHIP,G2A
RMII_PCH_SPRNGVLLE_ARB_IN U7C1             AJ3      LBG_CORE_QAT_EXT_D_BGA1-IC,H91A
RMII_PCH_SPRNGVLLE_ARB_IN_R EU9E1            44       SPRINGVILLE_SM1-IC,G47144-004
RMII_PCH_SPRNGVLLE_ARB_IN_R R9E16            1        RES_0402-33.2,1%,1/16W,CHIP,G2A
RMII_PCH_SPRNGVLLE_ARB_OUT EU9E1            43       SPRINGVILLE_SM1-IC,G47144-004
RMII_PCH_SPRNGVLLE_ARB_OUT R7D1             1        RES_0402-1.00K,1%,1/16W,CHIP,GA
RMII_PCH_SPRNGVLLE_ARB_OUT R8D11            1        RES_0402-33.2,1%,1/16W,CHIP,G2A
RMII_PCH_SPRNGVLLE_ARB_OUT R8D16            2        RES_0402-10.0K,1%,1/16W,EMPTY,A
RMII_PCH_SPRNGVLLE_ARB_OUT_R R8D11            2        RES_0402-33.2,1%,1/16W,CHIP,G2A
RMII_PCH_SPRNGVLLE_ARB_OUT_R U7C1             AK4      LBG_CORE_QAT_EXT_D_BGA1-IC,H91A
RMII_SPRNGVLLE_BMC_PCH_RXD0 R1R10            2        RES_0402-10.0K,1%,1/16W,CHIP,GA
RMII_SPRNGVLLE_BMC_PCH_RXD0 R3P3             1        RES_0402-0.0,5%,1/16W,CHIP,G21A
RMII_SPRNGVLLE_BMC_PCH_RXD0 R9E17            2        RES_0402-22.1,1.0%,1/16W,CHIP,A
RMII_SPRNGVLLE_BMC_PCH_RXD0 U9F4             A9       AST1250_BGA-IC,G85138-002
RMII_SPRNGVLLE_BMC_PCH_RXD0_R EU9E1            6        SPRINGVILLE_SM1-IC,G47144-004
RMII_SPRNGVLLE_BMC_PCH_RXD0_R R9E17            1        RES_0402-22.1,1.0%,1/16W,CHIP,A
RMII_SPRNGVLLE_BMC_PCH_RXD0_R1 R3P3             2        RES_0402-0.0,5%,1/16W,CHIP,G21A
RMII_SPRNGVLLE_BMC_PCH_RXD0_R1 U7C1             AL1      LBG_CORE_QAT_EXT_D_BGA1-IC,H91A
RMII_SPRNGVLLE_BMC_PCH_RXD1 R1R13            2        RES_0402-10.0K,1%,1/16W,CHIP,GA
RMII_SPRNGVLLE_BMC_PCH_RXD1 R2P1             1        RES_0402-0.0,5%,1/16W,CHIP,G21A
RMII_SPRNGVLLE_BMC_PCH_RXD1 R9E19            2        RES_0402-22.1,1.0%,1/16W,CHIP,A
RMII_SPRNGVLLE_BMC_PCH_RXD1 U9F4             E8       AST1250_BGA-IC,G85138-002
RMII_SPRNGVLLE_BMC_PCH_RXD1_R EU9E1            5        SPRINGVILLE_SM1-IC,G47144-004
RMII_SPRNGVLLE_BMC_PCH_RXD1_R R9E19            1        RES_0402-22.1,1.0%,1/16W,CHIP,A
RMII_SPRNGVLLE_BMC_PCH_RXD1_R1 R2P1             2        RES_0402-0.0,5%,1/16W,CHIP,G21A
RMII_SPRNGVLLE_BMC_PCH_RXD1_R1 U7C1             AN1      LBG_CORE_QAT_EXT_D_BGA1-IC,H91A
RST_BMC_DDR3_BUF_IN_N    R8D36            2        RES_0402-33.2,1%,1/16W,CHIP,G2A
RST_BMC_DDR3_BUF_IN_N    U9F3             2        TTL1G07_A_SOP-74LVC1G07,IC,C88B
RST_BMC_DDR3_N           R9F34            2        RES_0402-33.2,1%,1/16W,CHIP,G2A
RST_BMC_DDR3_N           U9F5             T2       K4B1G16_BGA1-IC,G38649-001
RST_BMC_DDR3_R_N         R9F29            2        RES_0402-4.75K,1%,1/16W,CHIP,GA
RST_BMC_DDR3_R_N         R9F34            1        RES_0402-33.2,1%,1/16W,CHIP,G2A
RST_BMC_DDR3_R_N         U9F3             4        TTL1G07_A_SOP-74LVC1G07,IC,C88B
RST_BMC_LVC3_N           R9F7             2        RES_0402-0.0,5%,1/16W,CHIP,G21A
RST_BMC_LVC3_N           U9F4             E19      AST1250_BGA-IC,G85138-002
RST_BMC_SRST_N           J8G2             3        CONN12_C73564003_PIP-CONN,C735A
RST_BMC_SRST_N           R7D23            1        RES_0402-0.0,5%,1/16W,CHIP,G21A
RST_BMC_SRST_N           R8D22            2        RES_0402-33.2,1%,1/16W,CHIP,G2A
RST_BMC_SRST_N           R9E14            1        RES_0402-0.0,5%,1/16W,CHIP,G21A
RST_BMC_SRST_N           U9F4             W20      AST1250_BGA-IC,G85138-002
RST_BMC_SRST_R2_N        R8D22            1        RES_0402-33.2,1%,1/16W,CHIP,G2A
RST_BMC_SRST_R2_N        R8D25            2        RES_0402-4.75K,1%,1/16W,CHIP,GA
RST_BMC_SRST_R2_N        R8D36            1        RES_0402-33.2,1%,1/16W,CHIP,G2A
RST_BMC_SRST_R2_N        U8D2             4        TTL1G07_A_SOP-74LVC1G07,IC,C88B
RST_BMC_SRST_R_N         R7D23            2        RES_0402-0.0,5%,1/16W,CHIP,G21A
RST_BMC_SRST_R_N         U7C1             M11      LBG_CORE_QAT_EXT_D_BGA1-IC,H91A
RST_BMC_SYSRST_BTN_OUT_B_N R2T18            2        RES_0402-49.9,1%,1/16W,CHIP,G2A
RST_BMC_SYSRST_BTN_OUT_B_N U7C1             BV19     LBG_CORE_QAT_EXT_D_BGA1-IC,H91A
RST_BMC_SYSRST_BTN_OUT_B_N U8D7             F14      LCMXO2_A_256BGA-IC,H63395-001
RST_BMC_SYSRST_BTN_OUT_B_R_N R2T18            1        RES_0402-49.9,1%,1/16W,CHIP,G2A
RST_BMC_SYSRST_BTN_OUT_B_R_N R2T22            2        RES_0402-10.0K,1%,1/16W,CHIP,GA
RST_BMC_SYSRST_BTN_OUT_B_R_N U8F3             6        TTL2G07_SOT23LF-74LVC2G07,IC,DB
RST_BMC_SYSRST_BTN_OUT_B_R_N U8G1             6        TTL2G07_SOT23LF-74LVC2G07,IC,DB
RST_BMC_SYSRST_BTN_OUT_N R2T35            2        RES_0402-4.75K,1%,1/16W,CHIP,GA
RST_BMC_SYSRST_BTN_OUT_N U8F3             1        TTL2G07_SOT23LF-74LVC2G07,IC,DB
RST_BMC_SYSRST_BTN_OUT_N U9F4             B16      AST1250_BGA-IC,G85138-002
RST_CD_CPU0_POR_N        R3R16            2        RES_0402-4.75K,1%,1/16W,CHIP,GA
RST_CD_CPU0_POR_N        U5D1             CF25     SKX_EXT_B_BGA1-IC,TBD
RST_CD_CPU0_POR_N        U8D7             N3       LCMXO2_A_256BGA-IC,H63395-001
RST_CD_CPU1_POR_N        R6M9             2        RES_0402-4.75K,1%,1/16W,CHIP,GA
RST_CD_CPU1_POR_N        U2D1             CF25     SKX_EXT_B_BGA1-IC,TBD
RST_CD_CPU1_POR_N        U8D7             P10      LCMXO2_A_256BGA-IC,H63395-001
RST_CPU0_G_N             R6D12            2        RES_0402-49.9,1%,1/16W,CHIP,G2A
RST_CPU0_G_N             U3P1             5        GTL2014_SM-IC,D66151-001
RST_CPU0_G_N             U5D1             AP21     SKX_EXT_B_BGA1-IC,TBD
RST_CPU0_LVC3_N          R3P34            2        RES_0402-0.0,5%,1/16W,CHIP,G21A
RST_CPU0_LVC3_N          U3P1             10       GTL2014_SM-IC,D66151-001
RST_CPU0_LVC3_R1_N       R3P34            1        RES_0402-0.0,5%,1/16W,CHIP,G21A
RST_CPU0_LVC3_R1_N       U8D7             R10      LCMXO2_A_256BGA-IC,H63395-001
RST_CPU1_G_N             R3D20            2        RES_0402-49.9,1%,1/16W,CHIP,G2A
RST_CPU1_G_N             U2D1             AP21     SKX_EXT_B_BGA1-IC,TBD
RST_CPU1_G_N             U4C2             5        GTL2014_SM-IC,D66151-001
RST_CPU1_LVC3_N          R3P35            2        RES_0402-0.0,5%,1/16W,CHIP,G21A
RST_CPU1_LVC3_N          U4C2             10       GTL2014_SM-IC,D66151-001
RST_CPU1_LVC3_R1_N       R3P35            1        RES_0402-0.0,5%,1/16W,CHIP,G21A
RST_CPU1_LVC3_R1_N       U8D7             N10      LCMXO2_A_256BGA-IC,H63395-001
RST_HFI0_CPU0_LVT2_N     J8B1             6        SCONN24_H46321001_SM-SCONN,H46A
RST_HFI0_CPU0_LVT2_N     R8B8             2        RES_0402-4.75K,1%,1/16W,CHIP,GA
RST_HFI0_CPU0_LVT2_N     U5D1             BN24     SKX_EXT_B_BGA1-IC,TBD
RST_HFI1_CPU0_LVT2_N     J8B1             14       SCONN24_H46321001_SM-SCONN,H46A
RST_HFI1_CPU0_LVT2_N     R8B16            2        RES_0402-4.75K,1%,1/16W,CHIP,GA
RST_HFI1_CPU0_LVT2_N     U5D1             BK23     SKX_EXT_B_BGA1-IC,TBD
RST_PCH_SYSRST_BTN_OUT_N R2U2             2        RES_0402-4.75K,1%,1/16W,CHIP,GA
RST_PCH_SYSRST_BTN_OUT_N U7C1             AD3      LBG_CORE_QAT_EXT_D_BGA1-IC,H91A
RST_PCH_SYSRST_BTN_OUT_N U8G1             1        TTL2G07_SOT23LF-74LVC2G07,IC,DB
RST_PCIE_CPU_DEV0_N      R1M14            1        RES_0402-200.0,1%,1/16W,CHIP,GA
RST_PCIE_CPU_DEV0_N      U8D7             D6       LCMXO2_A_256BGA-IC,H63395-001
RST_PCIE_CPU_DEV0_R_N    J9B3             33       SCONN120_A28699018_SM-SCONN,A2A
RST_PCIE_CPU_DEV0_R_N    R1M14            2        RES_0402-200.0,1%,1/16W,CHIP,GA
RST_PCIE_CPU_DEV1_N      R9E10            2        RES_0402-200.0,1%,1/16W,CHIP,GA
RST_PCIE_CPU_DEV1_N      U8D7             C1       LCMXO2_A_256BGA-IC,H63395-001
RST_PCIE_CPU_DEV1_R_N    J8E3             75       SCONN80_E67482007_SM-CONN,E674A
RST_PCIE_CPU_DEV1_R_N    R9E10            1        RES_0402-200.0,1%,1/16W,CHIP,GA
RST_PCIE_CPU_DEV2_N      R9E11            2        RES_0402-200.0,1%,1/16W,CHIP,GA
RST_PCIE_CPU_DEV2_N      U8D7             H3       LCMXO2_A_256BGA-IC,H63395-001
RST_PCIE_CPU_DEV2_R_N    J8E3             77       SCONN80_E67482007_SM-CONN,E674A
RST_PCIE_CPU_DEV2_R_N    R9E11            1        RES_0402-200.0,1%,1/16W,CHIP,GA
RST_PCIE_CPU_DEV3_N      R9E12            2        RES_0402-200.0,1%,1/16W,CHIP,GA
RST_PCIE_CPU_DEV3_N      U8D7             H1       LCMXO2_A_256BGA-IC,H63395-001
RST_PCIE_CPU_DEV3_R_N    J8E3             79       SCONN80_E67482007_SM-CONN,E674A
RST_PCIE_CPU_DEV3_R_N    R9E12            1        RES_0402-200.0,1%,1/16W,CHIP,GA
RST_PCIE_M2_DEV_N        J8F1             50       SCONN75K_H17033002_SMT1-SCONN,A
RST_PCIE_M2_DEV_N        U8D7             R6       LCMXO2_A_256BGA-IC,H63395-001
RST_PCIE_MIDPLANE_N      J1F1             I5       CONN76_H22707001_THMT1-CONN,H2A
RST_PCIE_MIDPLANE_N      U8D7             D9       LCMXO2_A_256BGA-IC,H63395-001
RST_PCIE_PCH_PERST_N     U7C1             AH4      LBG_CORE_QAT_EXT_D_BGA1-IC,H91A
RST_PCIE_PCH_PERST_N     U8D7             B1       LCMXO2_A_256BGA-IC,H63395-001
RST_PCIE_RISER1_PERST_N  R2U37            1        RES_0402-0.0,5%,1/16W,CHIP,G21A
RST_PCIE_RISER1_PERST_N  U8D7             M3       LCMXO2_A_256BGA-IC,H63395-001
RST_PCIE_RISER1_PERST_R_N J8G1             29       SCONN200_H68296001_SM-CONN,H68A
RST_PCIE_RISER1_PERST_R_N R2U37            2        RES_0402-0.0,5%,1/16W,CHIP,G21A
RST_PLTRST_BUF_N         J8E1             2        SCONN11_H67026001_SM-CONN,H670A
RST_PLTRST_BUF_N         Q8D2             1        FET_N_SOT23-2N7002,FET,C79254-A
RST_PLTRST_BUF_N         R9F4             1        RES_0402-100.0K,1%,1/16W,CHIP,A
RST_PLTRST_BUF_N         R9F7             1        RES_0402-0.0,5%,1/16W,CHIP,G21A
RST_PLTRST_BUF_N         U8D7             K11      LCMXO2_A_256BGA-IC,H63395-001
RST_PLTRST_BUF_N         U9F4             K19      AST1250_BGA-IC,G85138-002
RST_PLTRST_N             Q8E1             1        FET_N_SOT23LF-2N7002,FET,C7925A
RST_PLTRST_N             R1R1             1        RES_0402-0.0,5%,1/16W,CHIP,G21A
RST_PLTRST_N             U7C1             BN18     LBG_CORE_QAT_EXT_D_BGA1-IC,H91A
RST_PLTRST_N             U8D7             E15      LCMXO2_A_256BGA-IC,H63395-001
RST_PLTRST_SPRV_R_N      EU9E1            17       SPRINGVILLE_SM1-IC,G47144-004
RST_PLTRST_SPRV_R_N      R1R1             2        RES_0402-0.0,5%,1/16W,CHIP,G21A
RST_PLTRST_SPRV_R_N      R9E4             2        RES_0402-10.0K,1%,1/16W,CHIP,GA
RST_PLTRST_TOP_SWAP      Q8E1             3        FET_N_SOT23LF-2N7002,FET,C7925A
RST_PLTRST_TOP_SWAP      R8E14            2        RES_0402-4.75K,1%,1/16W,CHIP,GA
RST_PLTRST_TOP_SWAP      U8E3             1        TTL1G126_A_SOT-74HC1G126,IC,A7B
RST_RSMRST_DLY           Q8E2             1        FET_N_SOT23LF-2N7002,FET,C7925A
RST_RSMRST_DLY           U8D7             M1       LCMXO2_A_256BGA-IC,H63395-001
RST_RSMRST_N             R2R2             2        RES_0402-33.2,1%,1/16W,CHIP,G2A
RST_RSMRST_N             R7E18            2        RES_0402-4.75K,1%,1/16W,CHIP,GA
RST_RSMRST_N             R9A15            1        RES_0402-1.00K,1%,1/16W,CHIP,GA
RST_RSMRST_N             U7C1             P15      LBG_CORE_QAT_EXT_D_BGA1-IC,H91A
RST_RSMRST_R_N           R2R2             1        RES_0402-33.2,1%,1/16W,CHIP,G2A
RST_RSMRST_R_N           U8D7             G4       LCMXO2_A_256BGA-IC,H63395-001
RST_RTCRST_N             C7C19            1        CAP_A_0402V-1.0UF,6.3V,10%,X6SA
RST_RTCRST_N             J9G1             4        CONN12_C73564003_PIP-CONN,C735A
RST_RTCRST_N             R7C10            2        RES_0402-20.0K,1%,1/16W,CHIP,GA
RST_RTCRST_N             R7C11            2        RES_0402-1.0M,1%,1/16W,EMPTY,GA
RST_RTCRST_N             U7C1             P11      LBG_CORE_QAT_EXT_D_BGA1-IC,H91A
RST_SRTCRST_N            C3N32            1        CAP_A_0402V-1.0UF,6.3V,10%,X6SA
RST_SRTCRST_N            R3N4             2        RES_0402-20.0K,1%,1/16W,CHIP,GA
RST_SRTCRST_N            U7C1             G18      LBG_CORE_QAT_EXT_D_BGA1-IC,H91A
RST_SYSTEM_BTN_BUF_N     R9A9             1        RES_0402-100.0,1%,1/16W,CHIP,GA
RST_SYSTEM_BTN_BUF_N     U9A3             4        TTL2G14_SMLF-74LVC2G14,IC,D184B
RST_SYSTEM_BTN_N         R9A9             2        RES_0402-100.0,1%,1/16W,CHIP,GA
RST_SYSTEM_BTN_N         U7C1             BL11     LBG_CORE_QAT_EXT_D_BGA1-IC,H91A
RST_SYSTEM_BTN_N         U9F4             C16      AST1250_BGA-IC,G85138-002
SATA6G_P0_RX_C_DN        C2L17            2        CAP_A_0402V-0.01UF,25V,10%,X7RA
SATA6G_P0_RX_C_DN        J8A1             1B5      CONN72_G97614002_A_CP-CONN,G97A
SATA6G_P0_RX_C_DP        C2L19            2        CAP_A_0402V-0.01UF,25V,10%,X7RA
SATA6G_P0_RX_C_DP        J8A1             1B4      CONN72_G97614002_A_CP-CONN,G97A
SATA6G_P0_TX_C_DN        C2L40            1        CAP_A_0402V-0.01UF,25V,10%,X7RA
SATA6G_P0_TX_C_DN        J8A1             1D5      CONN72_G97614002_A_CP-CONN,G97A
SATA6G_P0_TX_C_DP        C2L39            1        CAP_A_0402V-0.01UF,25V,10%,X7RA
SATA6G_P0_TX_C_DP        J8A1             1D4      CONN72_G97614002_A_CP-CONN,G97A
SATA6G_P10_RX_C_DN       C2L36            2        CAP_A_0402V-0.01UF,25V,10%,X7RA
SATA6G_P10_RX_C_DN       J8A2             B8       CONN36_G97614001_CP-CONN,G9761A
SATA6G_P10_RX_C_DP       C2L35            2        CAP_A_0402V-0.01UF,25V,10%,X7RA
SATA6G_P10_RX_C_DP       J8A2             B7       CONN36_G97614001_CP-CONN,G9761A
SATA6G_P10_TX_C_DN       C1L13            1        CAP_A_0402V-0.01UF,25V,10%,X7RA
SATA6G_P10_TX_C_DN       J8A2             D8       CONN36_G97614001_CP-CONN,G9761A
SATA6G_P10_TX_C_DP       C1L12            1        CAP_A_0402V-0.01UF,25V,10%,X7RA
SATA6G_P10_TX_C_DP       J8A2             D7       CONN36_G97614001_CP-CONN,G9761A
SATA6G_P11_RX_C_DN       C2L34            2        CAP_A_0402V-0.01UF,25V,10%,X7RA
SATA6G_P11_RX_C_DN       J8A2             A8       CONN36_G97614001_CP-CONN,G9761A
SATA6G_P11_RX_C_DP       C2L33            2        CAP_A_0402V-0.01UF,25V,10%,X7RA
SATA6G_P11_RX_C_DP       J8A2             A7       CONN36_G97614001_CP-CONN,G9761A
SATA6G_P11_TX_C_DN       C1L15            1        CAP_A_0402V-0.01UF,25V,10%,X7RA
SATA6G_P11_TX_C_DN       J8A2             C8       CONN36_G97614001_CP-CONN,G9761A
SATA6G_P11_TX_C_DP       C1L14            1        CAP_A_0402V-0.01UF,25V,10%,X7RA
SATA6G_P11_TX_C_DP       J8A2             C7       CONN36_G97614001_CP-CONN,G9761A
SATA6G_P1_RX_C_DN        C2L6             2        CAP_A_0402V-0.01UF,25V,10%,X7RA
SATA6G_P1_RX_C_DN        J8A1             1A5      CONN72_G97614002_A_CP-CONN,G97A
SATA6G_P1_RX_C_DP        C2L10            2        CAP_A_0402V-0.01UF,25V,10%,X7RA
SATA6G_P1_RX_C_DP        J8A1             1A4      CONN72_G97614002_A_CP-CONN,G97A
SATA6G_P1_TX_C_DN        C2L44            1        CAP_A_0402V-0.01UF,25V,10%,X7RA
SATA6G_P1_TX_C_DN        J8A1             1C5      CONN72_G97614002_A_CP-CONN,G97A
SATA6G_P1_TX_C_DP        C2L43            1        CAP_A_0402V-0.01UF,25V,10%,X7RA
SATA6G_P1_TX_C_DP        J8A1             1C4      CONN72_G97614002_A_CP-CONN,G97A
SATA6G_P2_RX_C_DN        C2L13            2        CAP_A_0402V-0.01UF,25V,10%,X7RA
SATA6G_P2_RX_C_DN        J8A1             1B8      CONN72_G97614002_A_CP-CONN,G97A
SATA6G_P2_RX_C_DP        C2L15            2        CAP_A_0402V-0.01UF,25V,10%,X7RA
SATA6G_P2_RX_C_DP        J8A1             1B7      CONN72_G97614002_A_CP-CONN,G97A
SATA6G_P2_TX_C_DN        C2L42            1        CAP_A_0402V-0.01UF,25V,10%,X7RA
SATA6G_P2_TX_C_DN        J8A1             1D8      CONN72_G97614002_A_CP-CONN,G97A
SATA6G_P2_TX_C_DP        C2L41            1        CAP_A_0402V-0.01UF,25V,10%,X7RA
SATA6G_P2_TX_C_DP        J8A1             1D7      CONN72_G97614002_A_CP-CONN,G97A
SATA6G_P3_RX_C_DN        C2L3             2        CAP_A_0402V-0.01UF,25V,10%,X7RA
SATA6G_P3_RX_C_DN        J8A1             1A8      CONN72_G97614002_A_CP-CONN,G97A
SATA6G_P3_RX_C_DP        C2L4             2        CAP_A_0402V-0.01UF,25V,10%,X7RA
SATA6G_P3_RX_C_DP        J8A1             1A7      CONN72_G97614002_A_CP-CONN,G97A
SATA6G_P3_TX_C_DN        C2L22            1        CAP_A_0402V-0.01UF,25V,10%,X7RA
SATA6G_P3_TX_C_DN        J8A1             1C8      CONN72_G97614002_A_CP-CONN,G97A
SATA6G_P3_TX_C_DP        C2L23            1        CAP_A_0402V-0.01UF,25V,10%,X7RA
SATA6G_P3_TX_C_DP        J8A1             1C7      CONN72_G97614002_A_CP-CONN,G97A
SATA6G_P4_RX_C_DN        C2L18            2        CAP_A_0402V-0.01UF,25V,10%,X7RA
SATA6G_P4_RX_C_DN        J8A1             2B5      CONN72_G97614002_A_CP-CONN,G97A
SATA6G_P4_RX_C_DP        C2L20            2        CAP_A_0402V-0.01UF,25V,10%,X7RA
SATA6G_P4_RX_C_DP        J8A1             2B4      CONN72_G97614002_A_CP-CONN,G97A
SATA6G_P4_TX_C_DN        C2L37            1        CAP_A_0402V-0.01UF,25V,10%,X7RA
SATA6G_P4_TX_C_DN        J8A1             2D5      CONN72_G97614002_A_CP-CONN,G97A
SATA6G_P4_TX_C_DP        C2L47            1        CAP_A_0402V-0.01UF,25V,10%,X7RA
SATA6G_P4_TX_C_DP        J8A1             2D4      CONN72_G97614002_A_CP-CONN,G97A
SATA6G_P5_RX_C_DN        C2L9             2        CAP_A_0402V-0.01UF,25V,10%,X7RA
SATA6G_P5_RX_C_DN        J8A1             2A5      CONN72_G97614002_A_CP-CONN,G97A
SATA6G_P5_RX_C_DP        C2L12            2        CAP_A_0402V-0.01UF,25V,10%,X7RA
SATA6G_P5_RX_C_DP        J8A1             2A4      CONN72_G97614002_A_CP-CONN,G97A
SATA6G_P5_TX_C_DN        C2L26            1        CAP_A_0402V-0.01UF,25V,10%,X7RA
SATA6G_P5_TX_C_DN        J8A1             2C5      CONN72_G97614002_A_CP-CONN,G97A
SATA6G_P5_TX_C_DP        C2L27            1        CAP_A_0402V-0.01UF,25V,10%,X7RA
SATA6G_P5_TX_C_DP        J8A1             2C4      CONN72_G97614002_A_CP-CONN,G97A
SATA6G_P6_RX_C_DN        C2L14            2        CAP_A_0402V-0.01UF,25V,10%,X7RA
SATA6G_P6_RX_C_DN        J8A1             2B8      CONN72_G97614002_A_CP-CONN,G97A
SATA6G_P6_RX_C_DP        C2L16            2        CAP_A_0402V-0.01UF,25V,10%,X7RA
SATA6G_P6_RX_C_DP        J8A1             2B7      CONN72_G97614002_A_CP-CONN,G97A
SATA6G_P6_TX_C_DN        C2L38            1        CAP_A_0402V-0.01UF,25V,10%,X7RA
SATA6G_P6_TX_C_DN        J8A1             2D8      CONN72_G97614002_A_CP-CONN,G97A
SATA6G_P6_TX_C_DP        C2L48            1        CAP_A_0402V-0.01UF,25V,10%,X7RA
SATA6G_P6_TX_C_DP        J8A1             2D7      CONN72_G97614002_A_CP-CONN,G97A
SATA6G_P7_RX_C_DN        C2L5             2        CAP_A_0402V-0.01UF,25V,10%,X7RA
SATA6G_P7_RX_C_DN        J8A1             2A8      CONN72_G97614002_A_CP-CONN,G97A
SATA6G_P7_RX_C_DP        C2L7             2        CAP_A_0402V-0.01UF,25V,10%,X7RA
SATA6G_P7_RX_C_DP        J8A1             2A7      CONN72_G97614002_A_CP-CONN,G97A
SATA6G_P7_TX_C_DN        C2L21            1        CAP_A_0402V-0.01UF,25V,10%,X7RA
SATA6G_P7_TX_C_DN        J8A1             2C8      CONN72_G97614002_A_CP-CONN,G97A
SATA6G_P7_TX_C_DP        C2L24            1        CAP_A_0402V-0.01UF,25V,10%,X7RA
SATA6G_P7_TX_C_DP        J8A1             2C7      CONN72_G97614002_A_CP-CONN,G97A
SATA6G_P8_RX_C_DN        C2L31            2        CAP_A_0402V-0.01UF,25V,10%,X7RA
SATA6G_P8_RX_C_DN        J8A2             B5       CONN36_G97614001_CP-CONN,G9761A
SATA6G_P8_RX_C_DP        C2L30            2        CAP_A_0402V-0.01UF,25V,10%,X7RA
SATA6G_P8_RX_C_DP        J8A2             B4       CONN36_G97614001_CP-CONN,G9761A
SATA6G_P8_TX_C_DN        C1L3             1        CAP_A_0402V-0.01UF,25V,10%,X7RA
SATA6G_P8_TX_C_DN        J8A2             D5       CONN36_G97614001_CP-CONN,G9761A
SATA6G_P8_TX_C_DP        C1L2             1        CAP_A_0402V-0.01UF,25V,10%,X7RA
SATA6G_P8_TX_C_DP        J8A2             D4       CONN36_G97614001_CP-CONN,G9761A
SATA6G_P9_RX_C_DN        C2L29            2        CAP_A_0402V-0.01UF,25V,10%,X7RA
SATA6G_P9_RX_C_DN        J8A2             A5       CONN36_G97614001_CP-CONN,G9761A
SATA6G_P9_RX_C_DP        C2L28            2        CAP_A_0402V-0.01UF,25V,10%,X7RA
SATA6G_P9_RX_C_DP        J8A2             A4       CONN36_G97614001_CP-CONN,G9761A
SATA6G_P9_TX_C_DN        C1L7             1        CAP_A_0402V-0.01UF,25V,10%,X7RA
SATA6G_P9_TX_C_DN        J8A2             C5       CONN36_G97614001_CP-CONN,G9761A
SATA6G_P9_TX_C_DP        C1L6             1        CAP_A_0402V-0.01UF,25V,10%,X7RA
SATA6G_P9_TX_C_DP        J8A2             C4       CONN36_G97614001_CP-CONN,G9761A
SATA6G_PCH_PCIE_UP_SATA_RXN<0> C2L17            1        CAP_A_0402V-0.01UF,25V,10%,X7RA
SATA6G_PCH_PCIE_UP_SATA_RXN<0> U7C1             AR61     LBG_CORE_QAT_EXT_D_BGA1-IC,H91A
SATA6G_PCH_PCIE_UP_SATA_RXN<1> C2L6             1        CAP_A_0402V-0.01UF,25V,10%,X7RA
SATA6G_PCH_PCIE_UP_SATA_RXN<1> U7C1             AL66     LBG_CORE_QAT_EXT_D_BGA1-IC,H91A
SATA6G_PCH_PCIE_UP_SATA_RXN<2> C2L13            1        CAP_A_0402V-0.01UF,25V,10%,X7RA
SATA6G_PCH_PCIE_UP_SATA_RXN<2> U7C1             AK65     LBG_CORE_QAT_EXT_D_BGA1-IC,H91A
SATA6G_PCH_PCIE_UP_SATA_RXN<3> C2L3             1        CAP_A_0402V-0.01UF,25V,10%,X7RA
SATA6G_PCH_PCIE_UP_SATA_RXN<3> U7C1             AP63     LBG_CORE_QAT_EXT_D_BGA1-IC,H91A
SATA6G_PCH_PCIE_UP_SATA_RXN<4> C2L18            1        CAP_A_0402V-0.01UF,25V,10%,X7RA
SATA6G_PCH_PCIE_UP_SATA_RXN<4> U7C1             AF65     LBG_CORE_QAT_EXT_D_BGA1-IC,H91A
SATA6G_PCH_PCIE_UP_SATA_RXN<5> C2L9             1        CAP_A_0402V-0.01UF,25V,10%,X7RA
SATA6G_PCH_PCIE_UP_SATA_RXN<5> U7C1             AH61     LBG_CORE_QAT_EXT_D_BGA1-IC,H91A
SATA6G_PCH_PCIE_UP_SATA_RXN<6> C2L14            1        CAP_A_0402V-0.01UF,25V,10%,X7RA
SATA6G_PCH_PCIE_UP_SATA_RXN<6> U7C1             AP59     LBG_CORE_QAT_EXT_D_BGA1-IC,H91A
SATA6G_PCH_PCIE_UP_SATA_RXN<7> C2L5             1        CAP_A_0402V-0.01UF,25V,10%,X7RA
SATA6G_PCH_PCIE_UP_SATA_RXN<7> U7C1             AA61     LBG_CORE_QAT_EXT_D_BGA1-IC,H91A
SATA6G_PCH_PCIE_UP_SATA_RXP<0> C2L19            1        CAP_A_0402V-0.01UF,25V,10%,X7RA
SATA6G_PCH_PCIE_UP_SATA_RXP<0> U7C1             AT63     LBG_CORE_QAT_EXT_D_BGA1-IC,H91A
SATA6G_PCH_PCIE_UP_SATA_RXP<1> C2L10            1        CAP_A_0402V-0.01UF,25V,10%,X7RA
SATA6G_PCH_PCIE_UP_SATA_RXP<1> U7C1             AN65     LBG_CORE_QAT_EXT_D_BGA1-IC,H91A
SATA6G_PCH_PCIE_UP_SATA_RXP<2> C2L15            1        CAP_A_0402V-0.01UF,25V,10%,X7RA
SATA6G_PCH_PCIE_UP_SATA_RXP<2> U7C1             AJ63     LBG_CORE_QAT_EXT_D_BGA1-IC,H91A
SATA6G_PCH_PCIE_UP_SATA_RXP<3> C2L4             1        CAP_A_0402V-0.01UF,25V,10%,X7RA
SATA6G_PCH_PCIE_UP_SATA_RXP<3> U7C1             AL63     LBG_CORE_QAT_EXT_D_BGA1-IC,H91A
SATA6G_PCH_PCIE_UP_SATA_RXP<4> C2L20            1        CAP_A_0402V-0.01UF,25V,10%,X7RA
SATA6G_PCH_PCIE_UP_SATA_RXP<4> U7C1             AH65     LBG_CORE_QAT_EXT_D_BGA1-IC,H91A
SATA6G_PCH_PCIE_UP_SATA_RXP<5> C2L12            1        CAP_A_0402V-0.01UF,25V,10%,X7RA
SATA6G_PCH_PCIE_UP_SATA_RXP<5> U7C1             AG63     LBG_CORE_QAT_EXT_D_BGA1-IC,H91A
SATA6G_PCH_PCIE_UP_SATA_RXP<6> C2L16            1        CAP_A_0402V-0.01UF,25V,10%,X7RA
SATA6G_PCH_PCIE_UP_SATA_RXP<6> U7C1             AN61     LBG_CORE_QAT_EXT_D_BGA1-IC,H91A
SATA6G_PCH_PCIE_UP_SATA_RXP<7> C2L7             1        CAP_A_0402V-0.01UF,25V,10%,X7RA
SATA6G_PCH_PCIE_UP_SATA_RXP<7> U7C1             AD61     LBG_CORE_QAT_EXT_D_BGA1-IC,H91A
SATA6G_PCH_PCIE_UP_SATA_TXN<0> C2L40            2        CAP_A_0402V-0.01UF,25V,10%,X7RA
SATA6G_PCH_PCIE_UP_SATA_TXN<0> U7C1             W69      LBG_CORE_QAT_EXT_D_BGA1-IC,H91A
SATA6G_PCH_PCIE_UP_SATA_TXN<1> C2L44            2        CAP_A_0402V-0.01UF,25V,10%,X7RA
SATA6G_PCH_PCIE_UP_SATA_TXN<1> U7C1             V70      LBG_CORE_QAT_EXT_D_BGA1-IC,H91A
SATA6G_PCH_PCIE_UP_SATA_TXN<2> C2L42            2        CAP_A_0402V-0.01UF,25V,10%,X7RA
SATA6G_PCH_PCIE_UP_SATA_TXN<2> U7C1             T69      LBG_CORE_QAT_EXT_D_BGA1-IC,H91A
SATA6G_PCH_PCIE_UP_SATA_TXN<3> C2L22            2        CAP_A_0402V-0.01UF,25V,10%,X7RA
SATA6G_PCH_PCIE_UP_SATA_TXN<3> U7C1             R70      LBG_CORE_QAT_EXT_D_BGA1-IC,H91A
SATA6G_PCH_PCIE_UP_SATA_TXN<4> C2L37            2        CAP_A_0402V-0.01UF,25V,10%,X7RA
SATA6G_PCH_PCIE_UP_SATA_TXN<4> U7C1             P69      LBG_CORE_QAT_EXT_D_BGA1-IC,H91A
SATA6G_PCH_PCIE_UP_SATA_TXN<5> C2L26            2        CAP_A_0402V-0.01UF,25V,10%,X7RA
SATA6G_PCH_PCIE_UP_SATA_TXN<5> U7C1             N70      LBG_CORE_QAT_EXT_D_BGA1-IC,H91A
SATA6G_PCH_PCIE_UP_SATA_TXN<6> C2L38            2        CAP_A_0402V-0.01UF,25V,10%,X7RA
SATA6G_PCH_PCIE_UP_SATA_TXN<6> U7C1             M69      LBG_CORE_QAT_EXT_D_BGA1-IC,H91A
SATA6G_PCH_PCIE_UP_SATA_TXN<7> C2L21            2        CAP_A_0402V-0.01UF,25V,10%,X7RA
SATA6G_PCH_PCIE_UP_SATA_TXN<7> U7C1             L70      LBG_CORE_QAT_EXT_D_BGA1-IC,H91A
SATA6G_PCH_PCIE_UP_SATA_TXP<0> C2L39            2        CAP_A_0402V-0.01UF,25V,10%,X7RA
SATA6G_PCH_PCIE_UP_SATA_TXP<0> U7C1             W71      LBG_CORE_QAT_EXT_D_BGA1-IC,H91A
SATA6G_PCH_PCIE_UP_SATA_TXP<1> C2L43            2        CAP_A_0402V-0.01UF,25V,10%,X7RA
SATA6G_PCH_PCIE_UP_SATA_TXP<1> U7C1             V72      LBG_CORE_QAT_EXT_D_BGA1-IC,H91A
SATA6G_PCH_PCIE_UP_SATA_TXP<2> C2L41            2        CAP_A_0402V-0.01UF,25V,10%,X7RA
SATA6G_PCH_PCIE_UP_SATA_TXP<2> U7C1             T71      LBG_CORE_QAT_EXT_D_BGA1-IC,H91A
SATA6G_PCH_PCIE_UP_SATA_TXP<3> C2L23            2        CAP_A_0402V-0.01UF,25V,10%,X7RA
SATA6G_PCH_PCIE_UP_SATA_TXP<3> U7C1             R72      LBG_CORE_QAT_EXT_D_BGA1-IC,H91A
SATA6G_PCH_PCIE_UP_SATA_TXP<4> C2L47            2        CAP_A_0402V-0.01UF,25V,10%,X7RA
SATA6G_PCH_PCIE_UP_SATA_TXP<4> U7C1             P71      LBG_CORE_QAT_EXT_D_BGA1-IC,H91A
SATA6G_PCH_PCIE_UP_SATA_TXP<5> C2L27            2        CAP_A_0402V-0.01UF,25V,10%,X7RA
SATA6G_PCH_PCIE_UP_SATA_TXP<5> U7C1             N72      LBG_CORE_QAT_EXT_D_BGA1-IC,H91A
SATA6G_PCH_PCIE_UP_SATA_TXP<6> C2L48            2        CAP_A_0402V-0.01UF,25V,10%,X7RA
SATA6G_PCH_PCIE_UP_SATA_TXP<6> U7C1             M71      LBG_CORE_QAT_EXT_D_BGA1-IC,H91A
SATA6G_PCH_PCIE_UP_SATA_TXP<7> C2L24            2        CAP_A_0402V-0.01UF,25V,10%,X7RA
SATA6G_PCH_PCIE_UP_SATA_TXP<7> U7C1             L72      LBG_CORE_QAT_EXT_D_BGA1-IC,H91A
SATA6G_RX_DN<0>          C2L31            1        CAP_A_0402V-0.01UF,25V,10%,X7RA
SATA6G_RX_DN<0>          U7C1             BA65     LBG_CORE_QAT_EXT_D_BGA1-IC,H91A
SATA6G_RX_DN<1>          C2L29            1        CAP_A_0402V-0.01UF,25V,10%,X7RA
SATA6G_RX_DN<1>          U7C1             AW65     LBG_CORE_QAT_EXT_D_BGA1-IC,H91A
SATA6G_RX_DN<2>          C2L36            1        CAP_A_0402V-0.01UF,25V,10%,X7RA
SATA6G_RX_DN<2>          U7C1             AV63     LBG_CORE_QAT_EXT_D_BGA1-IC,H91A
SATA6G_RX_DN<3>          C2L34            1        CAP_A_0402V-0.01UF,25V,10%,X7RA
SATA6G_RX_DN<3>          U7C1             AT66     LBG_CORE_QAT_EXT_D_BGA1-IC,H91A
SATA6G_RX_DP<0>          C2L30            1        CAP_A_0402V-0.01UF,25V,10%,X7RA
SATA6G_RX_DP<0>          U7C1             BD65     LBG_CORE_QAT_EXT_D_BGA1-IC,H91A
SATA6G_RX_DP<1>          C2L28            1        CAP_A_0402V-0.01UF,25V,10%,X7RA
SATA6G_RX_DP<1>          U7C1             AY66     LBG_CORE_QAT_EXT_D_BGA1-IC,H91A
SATA6G_RX_DP<2>          C2L35            1        CAP_A_0402V-0.01UF,25V,10%,X7RA
SATA6G_RX_DP<2>          U7C1             AU65     LBG_CORE_QAT_EXT_D_BGA1-IC,H91A
SATA6G_RX_DP<3>          C2L33            1        CAP_A_0402V-0.01UF,25V,10%,X7RA
SATA6G_RX_DP<3>          U7C1             AV66     LBG_CORE_QAT_EXT_D_BGA1-IC,H91A
SATA6G_S0_RX_DN          C8F15            1        CAP_A_0402V-0.01UF,25V,10%,EMPA
SATA6G_S0_RX_DN          U7C1             BB63     LBG_CORE_QAT_EXT_D_BGA1-IC,H91A
SATA6G_S0_RX_DP          C8F13            1        CAP_A_0402V-0.01UF,25V,10%,EMPA
SATA6G_S0_RX_DP          U7C1             BD61     LBG_CORE_QAT_EXT_D_BGA1-IC,H91A
SATA6G_S0_TX_DN          C8F11            1        CAP_A_0402V-0.01UF,25V,10%,EMPA
SATA6G_S0_TX_DN          U7C1             AJ70     LBG_CORE_QAT_EXT_D_BGA1-IC,H91A
SATA6G_S0_TX_DP          C8F6             1        CAP_A_0402V-0.01UF,25V,10%,EMPA
SATA6G_S0_TX_DP          U7C1             AJ72     LBG_CORE_QAT_EXT_D_BGA1-IC,H91A
SATA6G_S1_RX_C_DN        C2L50            1        CAP_A_0402V-0.01UF,25V,10%,X7RA
SATA6G_S1_RX_C_DN        J2M1             5        CONN7_E82125014_PIP_TH-CONN,E8A
SATA6G_S1_RX_C_DN        J8A3             5        CONN7_E82125014_PIP_TH-EMPTY,EA
SATA6G_S1_RX_C_DP        C2L49            1        CAP_A_0402V-0.01UF,25V,10%,X7RA
SATA6G_S1_RX_C_DP        J2M1             6        CONN7_E82125014_PIP_TH-CONN,E8A
SATA6G_S1_RX_C_DP        J8A3             6        CONN7_E82125014_PIP_TH-EMPTY,EA
SATA6G_S1_RX_DN          C2L50            2        CAP_A_0402V-0.01UF,25V,10%,X7RA
SATA6G_S1_RX_DN          U7C1             AY59     LBG_CORE_QAT_EXT_D_BGA1-IC,H91A
SATA6G_S1_RX_DP          C2L49            2        CAP_A_0402V-0.01UF,25V,10%,X7RA
SATA6G_S1_RX_DP          U7C1             BA61     LBG_CORE_QAT_EXT_D_BGA1-IC,H91A
SATA6G_S1_TX_C_DN        C2L51            1        CAP_A_0402V-0.01UF,25V,10%,X7RA
SATA6G_S1_TX_C_DN        J2M1             3        CONN7_E82125014_PIP_TH-CONN,E8A
SATA6G_S1_TX_C_DN        J8A3             3        CONN7_E82125014_PIP_TH-EMPTY,EA
SATA6G_S1_TX_C_DP        C2L52            1        CAP_A_0402V-0.01UF,25V,10%,X7RA
SATA6G_S1_TX_C_DP        J2M1             2        CONN7_E82125014_PIP_TH-CONN,E8A
SATA6G_S1_TX_C_DP        J8A3             2        CONN7_E82125014_PIP_TH-EMPTY,EA
SATA6G_S1_TX_DN          C2L51            2        CAP_A_0402V-0.01UF,25V,10%,X7RA
SATA6G_S1_TX_DN          U7C1             AH69     LBG_CORE_QAT_EXT_D_BGA1-IC,H91A
SATA6G_S1_TX_DP          C2L52            2        CAP_A_0402V-0.01UF,25V,10%,X7RA
SATA6G_S1_TX_DP          U7C1             AH71     LBG_CORE_QAT_EXT_D_BGA1-IC,H91A
SATA6G_TX_DN<0>          C1L3             2        CAP_A_0402V-0.01UF,25V,10%,X7RA
SATA6G_TX_DN<0>          U7C1             AF70     LBG_CORE_QAT_EXT_D_BGA1-IC,H91A
SATA6G_TX_DN<1>          C1L7             2        CAP_A_0402V-0.01UF,25V,10%,X7RA
SATA6G_TX_DN<1>          U7C1             AE69     LBG_CORE_QAT_EXT_D_BGA1-IC,H91A
SATA6G_TX_DN<2>          C1L13            2        CAP_A_0402V-0.01UF,25V,10%,X7RA
SATA6G_TX_DN<2>          U7C1             AD70     LBG_CORE_QAT_EXT_D_BGA1-IC,H91A
SATA6G_TX_DN<3>          C1L15            2        CAP_A_0402V-0.01UF,25V,10%,X7RA
SATA6G_TX_DN<3>          U7C1             AC69     LBG_CORE_QAT_EXT_D_BGA1-IC,H91A
SATA6G_TX_DP<0>          C1L2             2        CAP_A_0402V-0.01UF,25V,10%,X7RA
SATA6G_TX_DP<0>          U7C1             AF72     LBG_CORE_QAT_EXT_D_BGA1-IC,H91A
SATA6G_TX_DP<1>          C1L6             2        CAP_A_0402V-0.01UF,25V,10%,X7RA
SATA6G_TX_DP<1>          U7C1             AE71     LBG_CORE_QAT_EXT_D_BGA1-IC,H91A
SATA6G_TX_DP<2>          C1L12            2        CAP_A_0402V-0.01UF,25V,10%,X7RA
SATA6G_TX_DP<2>          U7C1             AD72     LBG_CORE_QAT_EXT_D_BGA1-IC,H91A
SATA6G_TX_DP<3>          C1L14            2        CAP_A_0402V-0.01UF,25V,10%,X7RA
SATA6G_TX_DP<3>          U7C1             AC71     LBG_CORE_QAT_EXT_D_BGA1-IC,H91A
SGPIO_BMC_CLK            R1U14            2        RES_0402-51,5.0%,1/16W,CHIP,G2A
SGPIO_BMC_CLK            U8D7             J1       LCMXO2_A_256BGA-IC,H63395-001
SGPIO_BMC_CLK_R          R1U14            1        RES_0402-51,5.0%,1/16W,CHIP,G2A
SGPIO_BMC_CLK_R          U9F4             J5       AST1250_BGA-IC,G85138-002
SGPIO_BMC_DIN            R2R6             2        RES_0402-51,5.0%,1/16W,CHIP,G2A
SGPIO_BMC_DIN            U9F4             J3       AST1250_BGA-IC,G85138-002
SGPIO_BMC_DIN_R          R2R6             1        RES_0402-51,5.0%,1/16W,CHIP,G2A
SGPIO_BMC_DIN_R          U8D7             F8       LCMXO2_A_256BGA-IC,H63395-001
SGPIO_BMC_DOUT           R1U13            2        RES_0402-51,5.0%,1/16W,CHIP,G2A
SGPIO_BMC_DOUT           U8D7             J2       LCMXO2_A_256BGA-IC,H63395-001
SGPIO_BMC_DOUT_R         R1U13            1        RES_0402-51,5.0%,1/16W,CHIP,G2A
SGPIO_BMC_DOUT_R         U9F4             K5       AST1250_BGA-IC,G85138-002
SGPIO_BMC_LD_N           R1U12            2        RES_0402-51,5.0%,1/16W,CHIP,G2A
SGPIO_BMC_LD_N           U8D7             K4       LCMXO2_A_256BGA-IC,H63395-001
SGPIO_BMC_LD_R_N         R1U12            1        RES_0402-51,5.0%,1/16W,CHIP,G2A
SGPIO_BMC_LD_R_N         U9F4             J4       AST1250_BGA-IC,G85138-002
SGPIO_PCH_SATA_CLOCK     R2N31            1        RES_0402-49.9,1%,1/16W,CHIP,G2A
SGPIO_PCH_SATA_CLOCK     U7C1             AL7      LBG_CORE_QAT_EXT_D_BGA1-IC,H91A
SGPIO_PCH_SATA_CLOCK_R   J8A1             1A2      CONN72_G97614002_A_CP-CONN,G97A
SGPIO_PCH_SATA_CLOCK_R   R2L11            2        RES_0402-2.0K,1%,1/16W,CHIP,G2A
SGPIO_PCH_SATA_CLOCK_R   R2N31            2        RES_0402-49.9,1%,1/16W,CHIP,G2A
SGPIO_PCH_SATA_DOUT0     R8D19            1        RES_0402-49.9,1%,1/16W,CHIP,G2A
SGPIO_PCH_SATA_DOUT0     U7C1             AP11     LBG_CORE_QAT_EXT_D_BGA1-IC,H91A
SGPIO_PCH_SATA_DOUT0_R   J8A1             1C1      CONN72_G97614002_A_CP-CONN,G97A
SGPIO_PCH_SATA_DOUT0_R   R2L15            2        RES_0402-2.0K,1%,1/16W,CHIP,G2A
SGPIO_PCH_SATA_DOUT0_R   R8D19            2        RES_0402-49.9,1%,1/16W,CHIP,G2A
SGPIO_PCH_SATA_LOAD      R8D20            1        RES_0402-49.9,1%,1/16W,CHIP,G2A
SGPIO_PCH_SATA_LOAD      U7C1             AR9      LBG_CORE_QAT_EXT_D_BGA1-IC,H91A
SGPIO_PCH_SATA_LOAD_R    J8A1             1B2      CONN72_G97614002_A_CP-CONN,G97A
SGPIO_PCH_SATA_LOAD_R    R2L12            2        RES_0402-2.0K,1%,1/16W,CHIP,G2A
SGPIO_PCH_SATA_LOAD_R    R8D20            2        RES_0402-49.9,1%,1/16W,CHIP,G2A
SGPIO_PCH_SSATA_CLOCK    R2N22            1        RES_0402-49.9,1%,1/16W,CHIP,G2A
SGPIO_PCH_SSATA_CLOCK    U7C1             AP18     LBG_CORE_QAT_EXT_D_BGA1-IC,H91A
SGPIO_PCH_SSATA_CLOCK_R  J8A2             A2       CONN36_G97614001_CP-CONN,G9761A
SGPIO_PCH_SSATA_CLOCK_R  R2L6             2        RES_0402-2.0K,1%,1/16W,CHIP,G2A
SGPIO_PCH_SSATA_CLOCK_R  R2N22            2        RES_0402-49.9,1%,1/16W,CHIP,G2A
SGPIO_PCH_SSATA_DOUT0    R8B29            1        RES_0402-49.9,1%,1/16W,CHIP,G2A
SGPIO_PCH_SSATA_DOUT0    U7C1             BW43     LBG_CORE_QAT_EXT_D_BGA1-IC,H91A
SGPIO_PCH_SSATA_DOUT0_R  J8A2             C1       CONN36_G97614001_CP-CONN,G9761A
SGPIO_PCH_SSATA_DOUT0_R  R2L4             2        RES_0402-2.0K,1%,1/16W,CHIP,G2A
SGPIO_PCH_SSATA_DOUT0_R  R8B29            2        RES_0402-49.9,1%,1/16W,CHIP,G2A
SGPIO_PCH_SSATA_LOAD     R2N19            1        RES_0402-49.9,1%,1/16W,CHIP,G2A
SGPIO_PCH_SSATA_LOAD     U7C1             AU17     LBG_CORE_QAT_EXT_D_BGA1-IC,H91A
SGPIO_PCH_SSATA_LOAD_R   J8A2             B2       CONN36_G97614001_CP-CONN,G9761A
SGPIO_PCH_SSATA_LOAD_R   R2L5             2        RES_0402-2.0K,1%,1/16W,CHIP,G2A
SGPIO_PCH_SSATA_LOAD_R   R2N19            2        RES_0402-49.9,1%,1/16W,CHIP,G2A
SMB_3V3SB_HSC_SCL_R      EU1D2            16       ADM1278_SM-IC,G99251-001
SMB_3V3SB_HSC_SCL_R      R1D24            2        RES_0402-0.0,5%,1/16W,CHIP,G21A
SMB_3V3SB_HSC_SDA_R      EU1D2            15       ADM1278_SM-IC,G99251-001
SMB_3V3SB_HSC_SDA_R      R1D25            2        RES_0402-0.0,5%,1/16W,CHIP,G21A
SMB_BMC_PMBUS_STBY_LVC3_SCL J1F1             C6       CONN76_H22707001_THMT1-CONN,H2A
SMB_BMC_PMBUS_STBY_LVC3_SCL J1F3             7        CONN8_H62179001_PIP-CONN,H6217A
SMB_BMC_PMBUS_STBY_LVC3_SCL R1D24            1        RES_0402-0.0,5%,1/16W,CHIP,G21A
SMB_BMC_PMBUS_STBY_LVC3_SCL R2T54            2        RES_0402-665,1.0%,1/16W,CHIP,GA
SMB_BMC_PMBUS_STBY_LVC3_SCL R2T56            2        RES_0402-20.0,1%,1/16W,CHIP,G2A
SMB_BMC_PMBUS_STBY_LVC3_SCL R2U1             2        RES_0402-20.0,1%,1/16W,CHIP,G2A
SMB_BMC_PMBUS_STBY_LVC3_SCL_R R2U1             1        RES_0402-20.0,1%,1/16W,CHIP,G2A
SMB_BMC_PMBUS_STBY_LVC3_SCL_R U9F4             G5       AST1250_BGA-IC,G85138-002
SMB_BMC_PMBUS_STBY_LVC3_SDA J1F1             B6       CONN76_H22707001_THMT1-CONN,H2A
SMB_BMC_PMBUS_STBY_LVC3_SDA J1F3             6        CONN8_H62179001_PIP-CONN,H6217A
SMB_BMC_PMBUS_STBY_LVC3_SDA R1D25            1        RES_0402-0.0,5%,1/16W,CHIP,G21A
SMB_BMC_PMBUS_STBY_LVC3_SDA R2T49            2        RES_0402-20.0,1%,1/16W,CHIP,G2A
SMB_BMC_PMBUS_STBY_LVC3_SDA R2T53            2        RES_0402-665,1.0%,1/16W,CHIP,GA
SMB_BMC_PMBUS_STBY_LVC3_SDA R2T55            2        RES_0402-20.0,1%,1/16W,CHIP,G2A
SMB_BMC_PMBUS_STBY_LVC3_SDA_R R2T49            1        RES_0402-20.0,1%,1/16W,CHIP,G2A
SMB_BMC_PMBUS_STBY_LVC3_SDA_R U9F4             F3       AST1250_BGA-IC,G85138-002
SMB_CPU1_PE_HP_GTL_R_SCL R6N8             2        RES_0402-10.0,1%,1/16W,CHIP,G2A
SMB_CPU1_PE_HP_GTL_R_SCL R9M19            2        RES_0402-240,1.0%,1/16W,CHIP,GA
SMB_CPU1_PE_HP_GTL_R_SCL U1B2             2        PCA9517_SM-IC,G77073-001-GND=GA
SMB_CPU1_PE_HP_GTL_R_SDA R6N9             2        RES_0402-10.0,1%,1/16W,CHIP,G2A
SMB_CPU1_PE_HP_GTL_R_SDA R9M18            2        RES_0402-240,1.0%,1/16W,CHIP,GA
SMB_CPU1_PE_HP_GTL_R_SDA U1B2             3        PCA9517_SM-IC,G77073-001-GND=GA
SMB_CPU1_PE_HP_GTL_SCL   R6N8             1        RES_0402-10.0,1%,1/16W,CHIP,G2A
SMB_CPU1_PE_HP_GTL_SCL   U2D1             AM19     SKX_EXT_B_BGA1-IC,TBD
SMB_CPU1_PE_HP_GTL_SDA   R6N9             1        RES_0402-10.0,1%,1/16W,CHIP,G2A
SMB_CPU1_PE_HP_GTL_SDA   U2D1             AL18     SKX_EXT_B_BGA1-IC,TBD
SMB_DDR_ABC_SCL_G        R4T3             2        RES_0402-10.0,1%,1/16W,CHIP,G2A
SMB_DDR_ABC_SCL_G        R4T5             2        RES_0402-240,1.0%,1/16W,CHIP,GA
SMB_DDR_ABC_SCL_G        U6F1             2        PCA9617_SSOP-IC,G81764-001-GNDA
SMB_DDR_ABC_SCL_G_R      R4T3             1        RES_0402-10.0,1%,1/16W,CHIP,G2A
SMB_DDR_ABC_SCL_G_R      U5D1             AJ18     SKX_EXT_B_BGA1-IC,TBD
SMB_DDR_ABC_SDA_G        R4T4             2        RES_0402-10.0,1%,1/16W,CHIP,G2A
SMB_DDR_ABC_SDA_G        R4T6             2        RES_0402-240,1.0%,1/16W,CHIP,GA
SMB_DDR_ABC_SDA_G        U6F1             3        PCA9617_SSOP-IC,G81764-001-GNDA
SMB_DDR_ABC_SDA_G_R      R4T4             1        RES_0402-10.0,1%,1/16W,CHIP,G2A
SMB_DDR_ABC_SDA_G_R      U5D1             AF17     SKX_EXT_B_BGA1-IC,TBD
SMB_DDR_ABC_VPP_SCL      J4G1             141      SCONN288_H44441004_PIP-SCONN,HA
SMB_DDR_ABC_VPP_SCL      J4G2             141      SCONN288_H44441004_PIP-SCONN,HA
SMB_DDR_ABC_VPP_SCL      J4G3             141      SCONN288_H44441004_PIP-SCONN,HA
SMB_DDR_ABC_VPP_SCL      J6T1             141      SCONN288_H44441003_PIP-SCONN,HA
SMB_DDR_ABC_VPP_SCL      J6U1             141      SCONN288_H44441003_PIP-SCONN,HA
SMB_DDR_ABC_VPP_SCL      J6U2             141      SCONN288_H44441003_PIP-SCONN,HA
SMB_DDR_ABC_VPP_SCL      R4T9             2        RES_0402-20.0,1%,1/16W,CHIP,G2A
SMB_DDR_ABC_VPP_SCL_R    R4T7             2        RES_0402-665,1.0%,1/16W,CHIP,GA
SMB_DDR_ABC_VPP_SCL_R    R4T9             1        RES_0402-20.0,1%,1/16W,CHIP,G2A
SMB_DDR_ABC_VPP_SCL_R    U6F1             7        PCA9617_SSOP-IC,G81764-001-GNDA
SMB_DDR_ABC_VPP_SDA      J4G1             285      SCONN288_H44441004_PIP-SCONN,HA
SMB_DDR_ABC_VPP_SDA      J4G2             285      SCONN288_H44441004_PIP-SCONN,HA
SMB_DDR_ABC_VPP_SDA      J4G3             285      SCONN288_H44441004_PIP-SCONN,HA
SMB_DDR_ABC_VPP_SDA      J6T1             285      SCONN288_H44441003_PIP-SCONN,HA
SMB_DDR_ABC_VPP_SDA      J6U1             285      SCONN288_H44441003_PIP-SCONN,HA
SMB_DDR_ABC_VPP_SDA      J6U2             285      SCONN288_H44441003_PIP-SCONN,HA
SMB_DDR_ABC_VPP_SDA      R4T10            2        RES_0402-20.0,1%,1/16W,CHIP,G2A
SMB_DDR_ABC_VPP_SDA_R    R4T8             2        RES_0402-665,1.0%,1/16W,CHIP,GA
SMB_DDR_ABC_VPP_SDA_R    R4T10            1        RES_0402-20.0,1%,1/16W,CHIP,G2A
SMB_DDR_ABC_VPP_SDA_R    U6F1             6        PCA9617_SSOP-IC,G81764-001-GNDA
SMB_DDR_DEF_SCL_G        R3P60            2        RES_0402-240,1.0%,1/16W,CHIP,GA
SMB_DDR_DEF_SCL_G        R3R7             2        RES_0402-10.0,1%,1/16W,CHIP,G2A
SMB_DDR_DEF_SCL_G        U7E1             2        PCA9617_SSOP-IC,G81764-001-GNDA
SMB_DDR_DEF_SCL_G_R      R3R7             1        RES_0402-10.0,1%,1/16W,CHIP,G2A
SMB_DDR_DEF_SCL_G_R      U5D1             AE18     SKX_EXT_B_BGA1-IC,TBD
SMB_DDR_DEF_SDA_G        R3R13            2        RES_0402-240,1.0%,1/16W,CHIP,GA
SMB_DDR_DEF_SDA_G        R3R14            2        RES_0402-10.0,1%,1/16W,CHIP,G2A
SMB_DDR_DEF_SDA_G        U7E1             3        PCA9617_SSOP-IC,G81764-001-GNDA
SMB_DDR_DEF_SDA_G_R      R3R14            1        RES_0402-10.0,1%,1/16W,CHIP,G2A
SMB_DDR_DEF_SDA_G_R      U5D1             AD17     SKX_EXT_B_BGA1-IC,TBD
SMB_DDR_DEF_VPP_SCL      J4A1             141      SCONN288_H44441004_PIP-SCONN,HA
SMB_DDR_DEF_VPP_SCL      J4A2             141      SCONN288_H44441004_PIP-SCONN,HA
SMB_DDR_DEF_VPP_SCL      J4B1             141      SCONN288_H44441004_PIP-SCONN,HA
SMB_DDR_DEF_VPP_SCL      J6L1             141      SCONN288_H44441003_PIP-SCONN,HA
SMB_DDR_DEF_VPP_SCL      J6L2             141      SCONN288_H44441003_PIP-SCONN,HA
SMB_DDR_DEF_VPP_SCL      J6M1             141      SCONN288_H44441003_PIP-SCONN,HA
SMB_DDR_DEF_VPP_SCL      R3R8             2        RES_0402-20.0,1%,1/16W,CHIP,G2A
SMB_DDR_DEF_VPP_SCL_R    R3R5             2        RES_0402-665,1.0%,1/16W,CHIP,GA
SMB_DDR_DEF_VPP_SCL_R    R3R8             1        RES_0402-20.0,1%,1/16W,CHIP,G2A
SMB_DDR_DEF_VPP_SCL_R    U7E1             7        PCA9617_SSOP-IC,G81764-001-GNDA
SMB_DDR_DEF_VPP_SDA      J4A1             285      SCONN288_H44441004_PIP-SCONN,HA
SMB_DDR_DEF_VPP_SDA      J4A2             285      SCONN288_H44441004_PIP-SCONN,HA
SMB_DDR_DEF_VPP_SDA      J4B1             285      SCONN288_H44441004_PIP-SCONN,HA
SMB_DDR_DEF_VPP_SDA      J6L1             285      SCONN288_H44441003_PIP-SCONN,HA
SMB_DDR_DEF_VPP_SDA      J6L2             285      SCONN288_H44441003_PIP-SCONN,HA
SMB_DDR_DEF_VPP_SDA      J6M1             285      SCONN288_H44441003_PIP-SCONN,HA
SMB_DDR_DEF_VPP_SDA      R3R9             2        RES_0402-20.0,1%,1/16W,CHIP,G2A
SMB_DDR_DEF_VPP_SDA_R    R3R9             1        RES_0402-20.0,1%,1/16W,CHIP,G2A
SMB_DDR_DEF_VPP_SDA_R    R3R12            2        RES_0402-665,1.0%,1/16W,CHIP,GA
SMB_DDR_DEF_VPP_SDA_R    U7E1             6        PCA9617_SSOP-IC,G81764-001-GNDA
SMB_DDR_GHJ_SCL_G        R6T2             2        RES_0402-240,1.0%,1/16W,CHIP,GA
SMB_DDR_GHJ_SCL_G        R6T3             2        RES_0402-10.0,1%,1/16W,CHIP,G2A
SMB_DDR_GHJ_SCL_G        U4G1             2        PCA9617_SSOP-IC,G81764-001-GNDA
SMB_DDR_GHJ_SCL_G_R      R6T3             1        RES_0402-10.0,1%,1/16W,CHIP,G2A
SMB_DDR_GHJ_SCL_G_R      U2D1             AJ18     SKX_EXT_B_BGA1-IC,TBD
SMB_DDR_GHJ_SDA_G        R6T1             2        RES_0402-240,1.0%,1/16W,CHIP,GA
SMB_DDR_GHJ_SDA_G        R6T4             2        RES_0402-10.0,1%,1/16W,CHIP,G2A
SMB_DDR_GHJ_SDA_G        U4G1             3        PCA9617_SSOP-IC,G81764-001-GNDA
SMB_DDR_GHJ_SDA_G_R      R6T4             1        RES_0402-10.0,1%,1/16W,CHIP,G2A
SMB_DDR_GHJ_SDA_G_R      U2D1             AF17     SKX_EXT_B_BGA1-IC,TBD
SMB_DDR_GHJ_VPP_SCL      J1G1             141      SCONN288_H44441004_PIP-SCONN,HA
SMB_DDR_GHJ_VPP_SCL      J1G2             141      SCONN288_H44441004_PIP-SCONN,HA
SMB_DDR_GHJ_VPP_SCL      J1G3             141      SCONN288_H44441004_PIP-SCONN,HA
SMB_DDR_GHJ_VPP_SCL      J9T1             141      SCONN288_H44441003_PIP-SCONN,HA
SMB_DDR_GHJ_VPP_SCL      J9U1             141      SCONN288_H44441003_PIP-SCONN,HA
SMB_DDR_GHJ_VPP_SCL      J9U2             141      SCONN288_H44441003_PIP-SCONN,HA
SMB_DDR_GHJ_VPP_SCL      R6U13            2        RES_0402-20.0,1%,1/16W,CHIP,G2A
SMB_DDR_GHJ_VPP_SCL_R    R6U13            1        RES_0402-20.0,1%,1/16W,CHIP,G2A
SMB_DDR_GHJ_VPP_SCL_R    R6U17            2        RES_0402-665,1.0%,1/16W,CHIP,GA
SMB_DDR_GHJ_VPP_SCL_R    U4G1             7        PCA9617_SSOP-IC,G81764-001-GNDA
SMB_DDR_GHJ_VPP_SDA      J1G1             285      SCONN288_H44441004_PIP-SCONN,HA
SMB_DDR_GHJ_VPP_SDA      J1G2             285      SCONN288_H44441004_PIP-SCONN,HA
SMB_DDR_GHJ_VPP_SDA      J1G3             285      SCONN288_H44441004_PIP-SCONN,HA
SMB_DDR_GHJ_VPP_SDA      J9T1             285      SCONN288_H44441003_PIP-SCONN,HA
SMB_DDR_GHJ_VPP_SDA      J9U1             285      SCONN288_H44441003_PIP-SCONN,HA
SMB_DDR_GHJ_VPP_SDA      J9U2             285      SCONN288_H44441003_PIP-SCONN,HA
SMB_DDR_GHJ_VPP_SDA      R6U14            2        RES_0402-20.0,1%,1/16W,CHIP,G2A
SMB_DDR_GHJ_VPP_SDA_R    R6U14            1        RES_0402-20.0,1%,1/16W,CHIP,G2A
SMB_DDR_GHJ_VPP_SDA_R    R6U18            2        RES_0402-665,1.0%,1/16W,CHIP,GA
SMB_DDR_GHJ_VPP_SDA_R    U4G1             6        PCA9617_SSOP-IC,G81764-001-GNDA
SMB_DDR_KLM_SCL_G        R7M2             2        RES_0402-240,1.0%,1/16W,CHIP,GA
SMB_DDR_KLM_SCL_G        R7M3             2        RES_0402-10.0,1%,1/16W,CHIP,G2A
SMB_DDR_KLM_SCL_G        U3B1             2        PCA9617_SSOP-IC,G81764-001-GNDA
SMB_DDR_KLM_SCL_G_R      R7M3             1        RES_0402-10.0,1%,1/16W,CHIP,G2A
SMB_DDR_KLM_SCL_G_R      U2D1             AE18     SKX_EXT_B_BGA1-IC,TBD
SMB_DDR_KLM_SDA_G        R7M7             2        RES_0402-240,1.0%,1/16W,CHIP,GA
SMB_DDR_KLM_SDA_G        R7M8             2        RES_0402-10.0,1%,1/16W,CHIP,G2A
SMB_DDR_KLM_SDA_G        U3B1             3        PCA9617_SSOP-IC,G81764-001-GNDA
SMB_DDR_KLM_SDA_G_R      R7M8             1        RES_0402-10.0,1%,1/16W,CHIP,G2A
SMB_DDR_KLM_SDA_G_R      U2D1             AD17     SKX_EXT_B_BGA1-IC,TBD
SMB_DDR_KLM_VPP_SCL      J1A1             141      SCONN288_H44441004_PIP-SCONN,HA
SMB_DDR_KLM_VPP_SCL      J1A2             141      SCONN288_H44441004_PIP-SCONN,HA
SMB_DDR_KLM_VPP_SCL      J1B1             141      SCONN288_H44441004_PIP-SCONN,HA
SMB_DDR_KLM_VPP_SCL      J9L1             141      SCONN288_H44441003_PIP-SCONN,HA
SMB_DDR_KLM_VPP_SCL      J9L2             141      SCONN288_H44441003_PIP-SCONN,HA
SMB_DDR_KLM_VPP_SCL      J9M1             141      SCONN288_H44441003_PIP-SCONN,HA
SMB_DDR_KLM_VPP_SCL      R7M4             2        RES_0402-20.0,1%,1/16W,CHIP,G2A
SMB_DDR_KLM_VPP_SCL_R    R7M1             2        RES_0402-665,1.0%,1/16W,CHIP,GA
SMB_DDR_KLM_VPP_SCL_R    R7M4             1        RES_0402-20.0,1%,1/16W,CHIP,G2A
SMB_DDR_KLM_VPP_SCL_R    U3B1             7        PCA9617_SSOP-IC,G81764-001-GNDA
SMB_DDR_KLM_VPP_SDA      J1A1             285      SCONN288_H44441004_PIP-SCONN,HA
SMB_DDR_KLM_VPP_SDA      J1A2             285      SCONN288_H44441004_PIP-SCONN,HA
SMB_DDR_KLM_VPP_SDA      J1B1             285      SCONN288_H44441004_PIP-SCONN,HA
SMB_DDR_KLM_VPP_SDA      J9L1             285      SCONN288_H44441003_PIP-SCONN,HA
SMB_DDR_KLM_VPP_SDA      J9L2             285      SCONN288_H44441003_PIP-SCONN,HA
SMB_DDR_KLM_VPP_SDA      J9M1             285      SCONN288_H44441003_PIP-SCONN,HA
SMB_DDR_KLM_VPP_SDA      R7M5             2        RES_0402-20.0,1%,1/16W,CHIP,G2A
SMB_DDR_KLM_VPP_SDA_R    R7M5             1        RES_0402-20.0,1%,1/16W,CHIP,G2A
SMB_DDR_KLM_VPP_SDA_R    R7M6             2        RES_0402-665,1.0%,1/16W,CHIP,GA
SMB_DDR_KLM_VPP_SDA_R    U3B1             6        PCA9617_SSOP-IC,G81764-001-GNDA
SMB_HFI0_CPU0_LVC2_SCL   J8B1             2        SCONN24_H46321001_SM-SCONN,H46A
SMB_HFI0_CPU0_LVC2_SCL   R8B6             2        RES_0402-1.8K,1%,1/16W,CHIP,G2A
SMB_HFI0_CPU0_LVC2_SCL   U5D1             BN22     SKX_EXT_B_BGA1-IC,TBD
SMB_HFI0_CPU0_LVC2_SDA   J8B1             4        SCONN24_H46321001_SM-SCONN,H46A
SMB_HFI0_CPU0_LVC2_SDA   R8B7             2        RES_0402-1.8K,1%,1/16W,CHIP,G2A
SMB_HFI0_CPU0_LVC2_SDA   U5D1             BP23     SKX_EXT_B_BGA1-IC,TBD
SMB_HFI1_CPU0_LVC2_SCL   J8B1             10       SCONN24_H46321001_SM-SCONN,H46A
SMB_HFI1_CPU0_LVC2_SCL   R8B11            2        RES_0402-1.8K,1%,1/16W,CHIP,G2A
SMB_HFI1_CPU0_LVC2_SCL   U5D1             BJ22     SKX_EXT_B_BGA1-IC,TBD
SMB_HFI1_CPU0_LVC2_SDA   J8B1             12       SCONN24_H46321001_SM-SCONN,H46A
SMB_HFI1_CPU0_LVC2_SDA   R8B13            2        RES_0402-1.8K,1%,1/16W,CHIP,G2A
SMB_HFI1_CPU0_LVC2_SDA   U5D1             BH23     SKX_EXT_B_BGA1-IC,TBD
SMB_HOST_STBY_LVC3_SCL   EU8F2            38       ICS9FGP204_MLFP-IC,E95226-001
SMB_HOST_STBY_LVC3_SCL   J8C1             3        CONN3_C95678002_PIP-CONN,C9567A
SMB_HOST_STBY_LVC3_SCL   J9A3             53       SCONN60_C21100002_SMLF-CONN,C2A
SMB_HOST_STBY_LVC3_SCL   R2U34            2        RES_0402-20.0,1%,1/16W,CHIP,G2A
SMB_HOST_STBY_LVC3_SCL   R4D37            1        RES_0402-33.2,1%,1/16W,CHIP,G2A
SMB_HOST_STBY_LVC3_SCL   R8C14            2        RES_0402-20.0,1%,1/16W,CHIP,G2A
SMB_HOST_STBY_LVC3_SCL   R8C15            2        RES_0402-2.0K,1%,1/16W,CHIP,G2A
SMB_HOST_STBY_LVC3_SCL_R R2U34            1        RES_0402-20.0,1%,1/16W,CHIP,G2A
SMB_HOST_STBY_LVC3_SCL_R U9F4             B1       AST1250_BGA-IC,G85138-002
SMB_HOST_STBY_LVC3_SCL_R1 R8C14            1        RES_0402-20.0,1%,1/16W,CHIP,G2A
SMB_HOST_STBY_LVC3_SCL_R1 U7C1             BW28     LBG_CORE_QAT_EXT_D_BGA1-IC,H91A
SMB_HOST_STBY_LVC3_SCL_R2 EU4D2            13       NB3W1200L_LCC-IC,H13585-001
SMB_HOST_STBY_LVC3_SCL_R2 R4D37            2        RES_0402-33.2,1%,1/16W,CHIP,G2A
SMB_HOST_STBY_LVC3_SDA   EU8F2            39       ICS9FGP204_MLFP-IC,E95226-001
SMB_HOST_STBY_LVC3_SDA   J8C1             1        CONN3_C95678002_PIP-CONN,C9567A
SMB_HOST_STBY_LVC3_SDA   J9A3             51       SCONN60_C21100002_SMLF-CONN,C2A
SMB_HOST_STBY_LVC3_SDA   R2U33            2        RES_0402-20.0,1%,1/16W,CHIP,G2A
SMB_HOST_STBY_LVC3_SDA   R4D36            1        RES_0402-33.2,1%,1/16W,CHIP,G2A
SMB_HOST_STBY_LVC3_SDA   R8C16            2        RES_0402-2.0K,1%,1/16W,CHIP,G2A
SMB_HOST_STBY_LVC3_SDA   R8C20            2        RES_0402-20.0,1%,1/16W,CHIP,G2A
SMB_HOST_STBY_LVC3_SDA_R R2U33            1        RES_0402-20.0,1%,1/16W,CHIP,G2A
SMB_HOST_STBY_LVC3_SDA_R U9F4             F5       AST1250_BGA-IC,G85138-002
SMB_HOST_STBY_LVC3_SDA_R1 R8C20            1        RES_0402-20.0,1%,1/16W,CHIP,G2A
SMB_HOST_STBY_LVC3_SDA_R1 U7C1             BV27     LBG_CORE_QAT_EXT_D_BGA1-IC,H91A
SMB_HOST_STBY_LVC3_SDA_R2 EU4D2            12       NB3W1200L_LCC-IC,H13585-001
SMB_HOST_STBY_LVC3_SDA_R2 R4D36            2        RES_0402-33.2,1%,1/16W,CHIP,G2A
SMB_LAN_STBY_LVC3_SCL    J1C1             E5       CONN76_H22707001_THMT1-CONN,H2A
SMB_LAN_STBY_LVC3_SCL    R1C11            1        RES_0402-0.0,5%,1/16W,EMPTY,G2A
SMB_LAN_STBY_LVC3_SCL    R2N21            2        RES_0402-0.0,5%,1/16W,CHIP,G21A
SMB_LAN_STBY_LVC3_SCL    R2U3             2        RES_0402-665,1.0%,1/16W,CHIP,GA
SMB_LAN_STBY_LVC3_SCL    R2U6             2        RES_0402-20.0,1%,1/16W,CHIP,G2A
SMB_LAN_STBY_LVC3_SCL    R2U8             1        RES_0402-20.0,1%,1/16W,EMPTY,GA
SMB_LAN_STBY_LVC3_SCL    R4A9             1        RES_0402-0.0,5%,1/16W,CHIP,G21A
SMB_LAN_STBY_LVC3_SCL    R9F22            2        RES_0402-20.0,1%,1/16W,CHIP,G2A
SMB_LAN_STBY_LVC3_SCL    R9M20            1        RES_0402-0.0,5%,1/16W,CHIP,G21A
SMB_LAN_STBY_LVC3_SCL_R  R9F22            1        RES_0402-20.0,1%,1/16W,CHIP,G2A
SMB_LAN_STBY_LVC3_SCL_R  U9F4             K21      AST1250_BGA-IC,G85138-002
SMB_LAN_STBY_LVC3_SCL_R1 R2U6             1        RES_0402-20.0,1%,1/16W,CHIP,G2A
SMB_LAN_STBY_LVC3_SCL_R1 U7C1             BF1      LBG_CORE_QAT_EXT_D_BGA1-IC,H91A
SMB_LAN_STBY_LVC3_SCL_R2 R2N21            1        RES_0402-0.0,5%,1/16W,CHIP,G21A
SMB_LAN_STBY_LVC3_SCL_R2 U7C1             AU9      LBG_CORE_QAT_EXT_D_BGA1-IC,H91A
SMB_LAN_STBY_LVC3_SDA    J1C1             D5       CONN76_H22707001_THMT1-CONN,H2A
SMB_LAN_STBY_LVC3_SDA    R1C10            1        RES_0402-0.0,5%,1/16W,EMPTY,G2A
SMB_LAN_STBY_LVC3_SDA    R2N20            2        RES_0402-0.0,5%,1/16W,CHIP,G21A
SMB_LAN_STBY_LVC3_SDA    R2U9             2        RES_0402-20.0,1%,1/16W,CHIP,G2A
SMB_LAN_STBY_LVC3_SDA    R2U11            2        RES_0402-665,1.0%,1/16W,CHIP,GA
SMB_LAN_STBY_LVC3_SDA    R2U12            1        RES_0402-20.0,1%,1/16W,EMPTY,GA
SMB_LAN_STBY_LVC3_SDA    R4A8             1        RES_0402-0.0,5%,1/16W,CHIP,G21A
SMB_LAN_STBY_LVC3_SDA    R9F23            2        RES_0402-20.0,1%,1/16W,CHIP,G2A
SMB_LAN_STBY_LVC3_SDA    R9M21            1        RES_0402-0.0,5%,1/16W,CHIP,G21A
SMB_LAN_STBY_LVC3_SDA_R  R9F23            1        RES_0402-20.0,1%,1/16W,CHIP,G2A
SMB_LAN_STBY_LVC3_SDA_R  U9F4             K22      AST1250_BGA-IC,G85138-002
SMB_LAN_STBY_LVC3_SDA_R1 R2U9             1        RES_0402-20.0,1%,1/16W,CHIP,G2A
SMB_LAN_STBY_LVC3_SDA_R1 U7C1             BE4      LBG_CORE_QAT_EXT_D_BGA1-IC,H91A
SMB_LAN_STBY_LVC3_SDA_R2 R2N20            1        RES_0402-0.0,5%,1/16W,CHIP,G21A
SMB_LAN_STBY_LVC3_SDA_R2 U7C1             AU20     LBG_CORE_QAT_EXT_D_BGA1-IC,H91A
SMB_OCP_FRU_STBY_LVC3_SCL J8B1             22       SCONN24_H46321001_SM-SCONN,H46A
SMB_OCP_FRU_STBY_LVC3_SCL J8E4             1        SCONN64_H87568002_A_SMT-CONN,HA
SMB_OCP_FRU_STBY_LVC3_SCL J9B3             30       SCONN120_A28699018_SM-SCONN,A2A
SMB_OCP_FRU_STBY_LVC3_SCL R2U7             2        RES_0402-20.0,1%,1/16W,CHIP,G2A
SMB_OCP_FRU_STBY_LVC3_SCL R2U8             2        RES_0402-20.0,1%,1/16W,EMPTY,GA
SMB_OCP_FRU_STBY_LVC3_SCL_R R2U5             2        RES_0402-2.26K,1.0%,1/16W,CHIPA
SMB_OCP_FRU_STBY_LVC3_SCL_R R2U7             1        RES_0402-20.0,1%,1/16W,CHIP,G2A
SMB_OCP_FRU_STBY_LVC3_SCL_R U9F4             C5       AST1250_BGA-IC,G85138-002
SMB_OCP_FRU_STBY_LVC3_SDA J8B1             24       SCONN24_H46321001_SM-SCONN,H46A
SMB_OCP_FRU_STBY_LVC3_SDA J8E4             2        SCONN64_H87568002_A_SMT-CONN,HA
SMB_OCP_FRU_STBY_LVC3_SDA J9B3             32       SCONN120_A28699018_SM-SCONN,A2A
SMB_OCP_FRU_STBY_LVC3_SDA R2U10            2        RES_0402-20.0,1%,1/16W,CHIP,G2A
SMB_OCP_FRU_STBY_LVC3_SDA R2U12            2        RES_0402-20.0,1%,1/16W,EMPTY,GA
SMB_OCP_FRU_STBY_LVC3_SDA_R R2U10            1        RES_0402-20.0,1%,1/16W,CHIP,G2A
SMB_OCP_FRU_STBY_LVC3_SDA_R R2U13            2        RES_0402-2.26K,1.0%,1/16W,CHIPA
SMB_OCP_FRU_STBY_LVC3_SDA_R U9F4             B4       AST1250_BGA-IC,G85138-002
SMB_OCP_LAN_STBY_LVC3_SCL J9B3             35       SCONN120_A28699018_SM-SCONN,A2A
SMB_OCP_LAN_STBY_LVC3_SCL R8G4             2        RES_0402-20.0,1%,1/16W,CHIP,G2A
SMB_OCP_LAN_STBY_LVC3_SCL R9G13            1        RES_0402-20.0,1%,1/16W,CHIP,G2A
SMB_OCP_LAN_STBY_LVC3_SCL_R R8G3             2        RES_0402-2.26K,1.0%,1/16W,EMPTA
SMB_OCP_LAN_STBY_LVC3_SCL_R R8G4             1        RES_0402-20.0,1%,1/16W,CHIP,G2A
SMB_OCP_LAN_STBY_LVC3_SCL_R U9F4             D3       AST1250_BGA-IC,G85138-002
SMB_OCP_LAN_STBY_LVC3_SDA J9B3             37       SCONN120_A28699018_SM-SCONN,A2A
SMB_OCP_LAN_STBY_LVC3_SDA R8G5             2        RES_0402-20.0,1%,1/16W,CHIP,G2A
SMB_OCP_LAN_STBY_LVC3_SDA R9G12            1        RES_0402-20.0,1%,1/16W,CHIP,G2A
SMB_OCP_LAN_STBY_LVC3_SDA_R R8G5             1        RES_0402-20.0,1%,1/16W,CHIP,G2A
SMB_OCP_LAN_STBY_LVC3_SDA_R R8G6             2        RES_0402-2.26K,1.0%,1/16W,EMPTA
SMB_OCP_LAN_STBY_LVC3_SDA_R U9F4             C2       AST1250_BGA-IC,G85138-002
SMB_PCH_MEZZ_LOM0_SCL    J8E4             20       SCONN64_H87568002_A_SMT-CONN,HA
SMB_PCH_MEZZ_LOM0_SCL    R1R18            2        RES_0402-2.21K,1%,1/16W,CHIP,GA
SMB_PCH_MEZZ_LOM0_SCL    U7C1             BM4      LBG_CORE_QAT_EXT_D_BGA1-IC,H91A
SMB_PCH_MEZZ_LOM0_SDA    J8E4             21       SCONN64_H87568002_A_SMT-CONN,HA
SMB_PCH_MEZZ_LOM0_SDA    R1R19            2        RES_0402-2.21K,1%,1/16W,CHIP,GA
SMB_PCH_MEZZ_LOM0_SDA    U7C1             BN3      LBG_CORE_QAT_EXT_D_BGA1-IC,H91A
SMB_PCH_MEZZ_LOM1_SCL    J8E4             26       SCONN64_H87568002_A_SMT-CONN,HA
SMB_PCH_MEZZ_LOM1_SCL    R1R20            2        RES_0402-2.21K,1%,1/16W,CHIP,GA
SMB_PCH_MEZZ_LOM1_SCL    U7C1             BW5      LBG_CORE_QAT_EXT_D_BGA1-IC,H91A
SMB_PCH_MEZZ_LOM1_SDA    J8E4             27       SCONN64_H87568002_A_SMT-CONN,HA
SMB_PCH_MEZZ_LOM1_SDA    R1R21            2        RES_0402-2.21K,1%,1/16W,CHIP,GA
SMB_PCH_MEZZ_LOM1_SDA    U7C1             BV8      LBG_CORE_QAT_EXT_D_BGA1-IC,H91A
SMB_PCH_MEZZ_LOM2_SCL    J8E4             61       SCONN64_H87568002_A_SMT-CONN,HA
SMB_PCH_MEZZ_LOM2_SCL    R1R16            2        RES_0402-2.21K,1%,1/16W,CHIP,GA
SMB_PCH_MEZZ_LOM2_SCL    U7C1             BT5      LBG_CORE_QAT_EXT_D_BGA1-IC,H91A
SMB_PCH_MEZZ_LOM2_SDA    J8E4             62       SCONN64_H87568002_A_SMT-CONN,HA
SMB_PCH_MEZZ_LOM2_SDA    R1R17            2        RES_0402-2.21K,1%,1/16W,CHIP,GA
SMB_PCH_MEZZ_LOM2_SDA    U7C1             BW11     LBG_CORE_QAT_EXT_D_BGA1-IC,H91A
SMB_PCH_MEZZ_LOM3_SCL    J8E4             29       SCONN64_H87568002_A_SMT-CONN,HA
SMB_PCH_MEZZ_LOM3_SCL    R1R23            2        RES_0402-2.21K,1%,1/16W,CHIP,GA
SMB_PCH_MEZZ_LOM3_SCL    U7C1             BW6      LBG_CORE_QAT_EXT_D_BGA1-IC,H91A
SMB_PCH_MEZZ_LOM3_SDA    J8E4             30       SCONN64_H87568002_A_SMT-CONN,HA
SMB_PCH_MEZZ_LOM3_SDA    R1R22            2        RES_0402-2.21K,1%,1/16W,CHIP,GA
SMB_PCH_MEZZ_LOM3_SDA    U7C1             BW9      LBG_CORE_QAT_EXT_D_BGA1-IC,H91A
SMB_PEHPCPU1_STBY_LVC3_R_SCL R9M14            1        RES_0402-20.0,1%,1/16W,CHIP,G2A
SMB_PEHPCPU1_STBY_LVC3_R_SCL R9M15            1        RES_0402-20.0,1%,1/16W,CHIP,G2A
SMB_PEHPCPU1_STBY_LVC3_R_SCL R9M17            2        RES_0402-2.0K,1%,1/16W,CHIP,G2A
SMB_PEHPCPU1_STBY_LVC3_R_SCL U1B2             7        PCA9517_SM-IC,G77073-001-GND=GA
SMB_PEHPCPU1_STBY_LVC3_R_SDA R9M12            1        RES_0402-20.0,1%,1/16W,CHIP,G2A
SMB_PEHPCPU1_STBY_LVC3_R_SDA R9M13            1        RES_0402-20.0,1%,1/16W,CHIP,G2A
SMB_PEHPCPU1_STBY_LVC3_R_SDA R9M16            2        RES_0402-2.0K,1%,1/16W,CHIP,G2A
SMB_PEHPCPU1_STBY_LVC3_R_SDA U1B2             6        PCA9517_SM-IC,G77073-001-GND=GA
SMB_PEHPCPU1_STBY_LVC3_SCL J1C1             C6       CONN76_H22707001_THMT1-CONN,H2A
SMB_PEHPCPU1_STBY_LVC3_SCL R9M14            2        RES_0402-20.0,1%,1/16W,CHIP,G2A
SMB_PEHPCPU1_STBY_LVC3_SDA J1C1             B6       CONN76_H22707001_THMT1-CONN,H2A
SMB_PEHPCPU1_STBY_LVC3_SDA R9M13            2        RES_0402-20.0,1%,1/16W,CHIP,G2A
SMB_PIROM_CPU0_SCL       R4A9             2        RES_0402-0.0,5%,1/16W,CHIP,G21A
SMB_PIROM_CPU0_SCL       U5D1             CT59     SKX_EXT_B_BGA1-IC,TBD
SMB_PIROM_CPU0_SDA       R4A8             2        RES_0402-0.0,5%,1/16W,CHIP,G21A
SMB_PIROM_CPU0_SDA       U5D1             CW58     SKX_EXT_B_BGA1-IC,TBD
SMB_PIROM_CPU1_SCL       R9M20            2        RES_0402-0.0,5%,1/16W,CHIP,G21A
SMB_PIROM_CPU1_SCL       U2D1             CT59     SKX_EXT_B_BGA1-IC,TBD
SMB_PIROM_CPU1_SDA       R9M21            2        RES_0402-0.0,5%,1/16W,CHIP,G21A
SMB_PIROM_CPU1_SDA       U2D1             CW58     SKX_EXT_B_BGA1-IC,TBD
SMB_PMBUS_BMC_STBY_LVC3_SCL_R1 R2T56            1        RES_0402-20.0,1%,1/16W,CHIP,G2A
SMB_PMBUS_BMC_STBY_LVC3_SCL_R1 U7C1             CA28     LBG_CORE_QAT_EXT_D_BGA1-IC,H91A
SMB_PMBUS_BMC_STBY_LVC3_SDA_R1 R2T55            1        RES_0402-20.0,1%,1/16W,CHIP,G2A
SMB_PMBUS_BMC_STBY_LVC3_SDA_R1 U7C1             BV35     LBG_CORE_QAT_EXT_D_BGA1-IC,H91A
SMB_SENSOR_BMC_STBY_LVC3_SCL R9G14            1        RES_0402-20.0,1%,1/16W,CHIP,G2A
SMB_SENSOR_BMC_STBY_LVC3_SCL U9F4             E2       AST1250_BGA-IC,G85138-002
SMB_SENSOR_BMC_STBY_LVC3_SDA R9G15            1        RES_0402-20.0,1%,1/16W,CHIP,G2A
SMB_SENSOR_BMC_STBY_LVC3_SDA U9F4             D1       AST1250_BGA-IC,G85138-002
SMB_SENSOR_PCH_STBY_LVC3_SCL EU9G1            3        ADC128D818_SM-IC,H63642-001
SMB_SENSOR_PCH_STBY_LVC3_SCL R1U25            1        RES_0402-20.0,1%,1/16W,CHIP,G2A
SMB_SENSOR_PCH_STBY_LVC3_SCL R8D3             2        RES_0402-20.0,1%,1/16W,CHIP,G2A
SMB_SENSOR_PCH_STBY_LVC3_SDA EU9G1            2        ADC128D818_SM-IC,H63642-001
SMB_SENSOR_PCH_STBY_LVC3_SDA R1U31            1        RES_0402-20.0,1%,1/16W,CHIP,G2A
SMB_SENSOR_PCH_STBY_LVC3_SDA R8D6             2        RES_0402-20.0,1%,1/16W,CHIP,G2A
SMB_SENSOR_STBY_LVC3_SCL J8E1             10       SCONN11_H67026001_SM-CONN,H670A
SMB_SENSOR_STBY_LVC3_SCL R1M8             2        RES_0402-20.0,1%,1/16W,CHIP,G2A
SMB_SENSOR_STBY_LVC3_SCL R1U25            2        RES_0402-20.0,1%,1/16W,CHIP,G2A
SMB_SENSOR_STBY_LVC3_SCL R2U38            2        RES_0402-665,1.0%,1/16W,CHIP,GA
SMB_SENSOR_STBY_LVC3_SCL R8D24            1        RES_0402-20.0,1%,1/16W,CHIP,G2A
SMB_SENSOR_STBY_LVC3_SCL R9G14            2        RES_0402-20.0,1%,1/16W,CHIP,G2A
SMB_SENSOR_STBY_LVC3_SCL R9R7             2        RES_0402-20.0,1%,1/16W,CHIP,G2A
SMB_SENSOR_STBY_LVC3_SCL U8D7             A9       LCMXO2_A_256BGA-IC,H63395-001
SMB_SENSOR_STBY_LVC3_SCL_R1 R8D3             1        RES_0402-20.0,1%,1/16W,CHIP,G2A
SMB_SENSOR_STBY_LVC3_SCL_R1 U7C1             AY1      LBG_CORE_QAT_EXT_D_BGA1-IC,H91A
SMB_SENSOR_STBY_LVC3_SCL_R2 R8D24            2        RES_0402-20.0,1%,1/16W,CHIP,G2A
SMB_SENSOR_STBY_LVC3_SCL_R2 U8D4             6        AT24C64_SOICLF-IC,C47049-001-GA
SMB_SENSOR_STBY_LVC3_SDA J8E1             6        SCONN11_H67026001_SM-CONN,H670A
SMB_SENSOR_STBY_LVC3_SDA R1M9             2        RES_0402-20.0,1%,1/16W,CHIP,G2A
SMB_SENSOR_STBY_LVC3_SDA R1U31            2        RES_0402-20.0,1%,1/16W,CHIP,G2A
SMB_SENSOR_STBY_LVC3_SDA R2U39            2        RES_0402-665,1.0%,1/16W,CHIP,GA
SMB_SENSOR_STBY_LVC3_SDA R8D23            2        RES_0402-20.0,1%,1/16W,CHIP,G2A
SMB_SENSOR_STBY_LVC3_SDA R9G15            2        RES_0402-20.0,1%,1/16W,CHIP,G2A
SMB_SENSOR_STBY_LVC3_SDA R9R8             2        RES_0402-20.0,1%,1/16W,CHIP,G2A
SMB_SENSOR_STBY_LVC3_SDA U8D7             C9       LCMXO2_A_256BGA-IC,H63395-001
SMB_SENSOR_STBY_LVC3_SDA_R1 R8D6             1        RES_0402-20.0,1%,1/16W,CHIP,G2A
SMB_SENSOR_STBY_LVC3_SDA_R1 U7C1             BC2      LBG_CORE_QAT_EXT_D_BGA1-IC,H91A
SMB_SENSOR_STBY_LVC3_SDA_R2 R8D23            1        RES_0402-20.0,1%,1/16W,CHIP,G2A
SMB_SENSOR_STBY_LVC3_SDA_R2 U8D4             5        AT24C64_SOICLF-IC,C47049-001-GA
SMB_SENSOR_TMP421_1_SCL  R1M8             1        RES_0402-20.0,1%,1/16W,CHIP,G2A
SMB_SENSOR_TMP421_1_SCL  U9B4             7        TMP421_TSSOP-IC,G62962-001
SMB_SENSOR_TMP421_1_SDA  R1M9             1        RES_0402-20.0,1%,1/16W,CHIP,G2A
SMB_SENSOR_TMP421_1_SDA  U9B4             6        TMP421_TSSOP-IC,G62962-001
SMB_SENSOR_TMP421_2_SCL  R9R7             1        RES_0402-20.0,1%,1/16W,CHIP,G2A
SMB_SENSOR_TMP421_2_SCL  U1E1             7        TMP421_TSSOP-IC,G62962-001
SMB_SENSOR_TMP421_2_SDA  R9R8             1        RES_0402-20.0,1%,1/16W,CHIP,G2A
SMB_SENSOR_TMP421_2_SDA  U1E1             6        TMP421_TSSOP-IC,G62962-001
SMB_SLOTX24_BMC_STBY_LVC3_SCL R1T7             2        RES_0402-20.0,1%,1/16W,CHIP,G2A
SMB_SLOTX24_BMC_STBY_LVC3_SCL R2U32            1        RES_0402-20.0,1%,1/16W,CHIP,G2A
SMB_SLOTX24_BMC_STBY_LVC3_SCL R9M15            2        RES_0402-20.0,1%,1/16W,CHIP,G2A
SMB_SLOTX24_BMC_STBY_LVC3_SDA R1T8             2        RES_0402-20.0,1%,1/16W,CHIP,G2A
SMB_SLOTX24_BMC_STBY_LVC3_SDA R2U31            1        RES_0402-20.0,1%,1/16W,CHIP,G2A
SMB_SLOTX24_BMC_STBY_LVC3_SDA R9M12            2        RES_0402-20.0,1%,1/16W,CHIP,G2A
SMB_SLOTX24_PCH_STBY_LVC3_SCL EU9F3            17       PI7C9X1172_QFN-IC,H66899-001
SMB_SLOTX24_PCH_STBY_LVC3_SCL R2U36            1        RES_0402-20.0,1%,1/16W,EMPTY,GA
SMB_SLOTX24_PCH_STBY_LVC3_SCL R8B26            2        RES_0402-3.3K,5%,1/16W,CHIP,G2A
SMB_SLOTX24_PCH_STBY_LVC3_SCL R8B28            2        RES_0402-20.0,1%,1/16W,CHIP,G2A
SMB_SLOTX24_PCH_STBY_LVC3_SCL U8D7             H5       LCMXO2_A_256BGA-IC,H63395-001
SMB_SLOTX24_PCH_STBY_LVC3_SDA EU9F3            3        PI7C9X1172_QFN-IC,H66899-001
SMB_SLOTX24_PCH_STBY_LVC3_SDA R2U35            1        RES_0402-20.0,1%,1/16W,EMPTY,GA
SMB_SLOTX24_PCH_STBY_LVC3_SDA R8B24            2        RES_0402-3.3K,5%,1/16W,CHIP,G2A
SMB_SLOTX24_PCH_STBY_LVC3_SDA R8B27            2        RES_0402-20.0,1%,1/16W,CHIP,G2A
SMB_SLOTX24_PCH_STBY_LVC3_SDA U8D7             J4       LCMXO2_A_256BGA-IC,H63395-001
SMB_SLOTX24_STBY_LVC3_SCL_R R1T2             2        RES_0402-665,1.0%,1/16W,CHIP,GA
SMB_SLOTX24_STBY_LVC3_SCL_R R1T7             1        RES_0402-20.0,1%,1/16W,CHIP,G2A
SMB_SLOTX24_STBY_LVC3_SCL_R U9F4             J19      AST1250_BGA-IC,G85138-002
SMB_SLOTX24_STBY_LVC3_SCL_R1 R8B28            1        RES_0402-20.0,1%,1/16W,CHIP,G2A
SMB_SLOTX24_STBY_LVC3_SCL_R1 U7C1             BY44     LBG_CORE_QAT_EXT_D_BGA1-IC,H91A
SMB_SLOTX24_STBY_LVC3_SCL_R2 J8G1             17       SCONN200_H68296001_SM-CONN,H68A
SMB_SLOTX24_STBY_LVC3_SCL_R2 R2U32            2        RES_0402-20.0,1%,1/16W,CHIP,G2A
SMB_SLOTX24_STBY_LVC3_SCL_R2 R2U36            2        RES_0402-20.0,1%,1/16W,EMPTY,GA
SMB_SLOTX24_STBY_LVC3_SDA_R R1T3             2        RES_0402-665,1.0%,1/16W,CHIP,GA
SMB_SLOTX24_STBY_LVC3_SDA_R R1T8             1        RES_0402-20.0,1%,1/16W,CHIP,G2A
SMB_SLOTX24_STBY_LVC3_SDA_R U9F4             J18      AST1250_BGA-IC,G85138-002
SMB_SLOTX24_STBY_LVC3_SDA_R1 R8B27            1        RES_0402-20.0,1%,1/16W,CHIP,G2A
SMB_SLOTX24_STBY_LVC3_SDA_R1 U7C1             BL44     LBG_CORE_QAT_EXT_D_BGA1-IC,H91A
SMB_SLOTX24_STBY_LVC3_SDA_R2 J8G1             15       SCONN200_H68296001_SM-CONN,H68A
SMB_SLOTX24_STBY_LVC3_SDA_R2 R2U31            2        RES_0402-20.0,1%,1/16W,CHIP,G2A
SMB_SLOTX24_STBY_LVC3_SDA_R2 R2U35            2        RES_0402-20.0,1%,1/16W,EMPTY,GA
SMB_SMLINK0_STBY_LVC3_SCL J9B2             3        CONN3_C95678002_PIP-CONN,C9567A
SMB_SMLINK0_STBY_LVC3_SCL R1U9             2        RES_0402-20.0,1%,1/16W,CHIP,G2A
SMB_SMLINK0_STBY_LVC3_SCL R1U19            1        RES_0402-20.0,1%,1/16W,CHIP,G2A
SMB_SMLINK0_STBY_LVC3_SCL R2N5             2        RES_0402-665,1.0%,1/16W,CHIP,GA
SMB_SMLINK0_STBY_LVC3_SCL R8C12            2        RES_0402-20.0,1%,1/16W,CHIP,G2A
SMB_SMLINK0_STBY_LVC3_SCL_R R1U9             1        RES_0402-20.0,1%,1/16W,CHIP,G2A
SMB_SMLINK0_STBY_LVC3_SCL_R U9F4             E3       AST1250_BGA-IC,G85138-002
SMB_SMLINK0_STBY_LVC3_SCL_R1 R8C12            1        RES_0402-20.0,1%,1/16W,CHIP,G2A
SMB_SMLINK0_STBY_LVC3_SCL_R1 U7C1             BV29     LBG_CORE_QAT_EXT_D_BGA1-IC,H91A
SMB_SMLINK0_STBY_LVC3_SDA J9B2             1        CONN3_C95678002_PIP-CONN,C9567A
SMB_SMLINK0_STBY_LVC3_SDA R1U10            2        RES_0402-20.0,1%,1/16W,CHIP,G2A
SMB_SMLINK0_STBY_LVC3_SDA R1U20            1        RES_0402-20.0,1%,1/16W,CHIP,G2A
SMB_SMLINK0_STBY_LVC3_SDA R2N8             2        RES_0402-665,1.0%,1/16W,CHIP,GA
SMB_SMLINK0_STBY_LVC3_SDA R8C11            2        RES_0402-20.0,1%,1/16W,CHIP,G2A
SMB_SMLINK0_STBY_LVC3_SDA_R R1U10            1        RES_0402-20.0,1%,1/16W,CHIP,G2A
SMB_SMLINK0_STBY_LVC3_SDA_R U9F4             D2       AST1250_BGA-IC,G85138-002
SMB_SMLINK0_STBY_LVC3_SDA_R1 R8C11            1        RES_0402-20.0,1%,1/16W,CHIP,G2A
SMB_SMLINK0_STBY_LVC3_SDA_R1 U7C1             BW30     LBG_CORE_QAT_EXT_D_BGA1-IC,H91A
SMB_SPRINGVILLE_STBY_LVC3_SCL EU9E1            34       SPRINGVILLE_SM1-IC,G47144-004
SMB_SPRINGVILLE_STBY_LVC3_SCL R1U19            2        RES_0402-20.0,1%,1/16W,CHIP,G2A
SMB_SPRINGVILLE_STBY_LVC3_SCL R9G13            2        RES_0402-20.0,1%,1/16W,CHIP,G2A
SMB_SPRINGVILLE_STBY_LVC3_SDA EU9E1            36       SPRINGVILLE_SM1-IC,G47144-004
SMB_SPRINGVILLE_STBY_LVC3_SDA R1U20            2        RES_0402-20.0,1%,1/16W,CHIP,G2A
SMB_SPRINGVILLE_STBY_LVC3_SDA R9G12            2        RES_0402-20.0,1%,1/16W,CHIP,G2A
SMB_VR_SCL_PVCCIO_CPU0   EU3P1            7        PXE1110B_QFN-IC,H89187-001
SMB_VR_SCL_PVCCIO_CPU0   R3P24            2        RES_0402-20.0,1%,1/16W,CHIP,G2A
SMB_VR_SCL_PVCCIO_CPU1   EU4D5            7        PXE1110B_QFN-IC,H89187-001
SMB_VR_SCL_PVCCIO_CPU1   R4D43            2        RES_0402-20.0,1%,1/16W,CHIP,G2A
SMB_VR_SCL_PVNN_PCH      EU8A1            7        PXE1110B_QFN-IC,H89187-001
SMB_VR_SCL_PVNN_PCH      R8A9             2        RES_0402-20.0,1%,1/16W,CHIP,G2A
SMB_VR_SCL_R             EU4D4            9        PXE1610B_QFN-IC,H79206-001
SMB_VR_SCL_R             R4D53            1        RES_0402-0.0,5%,1/16W,CHIP,G21A
SMB_VR_SCL_R1            EU1C2            9        PXE1610B_QFN-IC,H79206-001
SMB_VR_SCL_R1            R1C25            1        RES_0402-0.0,5%,1/16W,CHIP,G21A
SMB_VR_SCL_VDDQ_ABC      EU7G1            7        PXM1310B_QFN-IC,H89186-001
SMB_VR_SCL_VDDQ_ABC      R7F25            1        RES_0402-20.0,1%,1/16W,CHIP,G2A
SMB_VR_SCL_VDDQ_DEF      EU7A5            7        PXM1310B_QFN-IC,H89186-001
SMB_VR_SCL_VDDQ_DEF      R7B3             1        RES_0402-20.0,1%,1/16W,CHIP,G2A
SMB_VR_SCL_VDDQ_GHJ      EU1G2            7        PXM1310B_QFN-IC,H89186-001
SMB_VR_SCL_VDDQ_GHJ      R1G19            1        RES_0402-0.0,5%,1/16W,CHIP,G21A
SMB_VR_SCL_VDDQ_KLM      EU1B1            7        PXM1310B_QFN-IC,H89186-001
SMB_VR_SCL_VDDQ_KLM      R1B6             1        RES_0402-20.0,1%,1/16W,CHIP,G2A
SMB_VR_SDA_PVCCIO_CPU0   EU3P1            6        PXE1110B_QFN-IC,H89187-001
SMB_VR_SDA_PVCCIO_CPU0   R3P23            2        RES_0402-20.0,1%,1/16W,CHIP,G2A
SMB_VR_SDA_PVCCIO_CPU1   EU4D5            6        PXE1110B_QFN-IC,H89187-001
SMB_VR_SDA_PVCCIO_CPU1   R4D44            2        RES_0402-20.0,1%,1/16W,CHIP,G2A
SMB_VR_SDA_PVNN_PCH      EU8A1            6        PXE1110B_QFN-IC,H89187-001
SMB_VR_SDA_PVNN_PCH      R8A8             2        RES_0402-20.0,1%,1/16W,CHIP,G2A
SMB_VR_SDA_R             EU4D4            8        PXE1610B_QFN-IC,H79206-001
SMB_VR_SDA_R             R4D50            1        RES_0402-0.0,5%,1/16W,CHIP,G21A
SMB_VR_SDA_R1            EU1C2            8        PXE1610B_QFN-IC,H79206-001
SMB_VR_SDA_R1            R1C23            1        RES_0402-0.0,5%,1/16W,CHIP,G21A
SMB_VR_SDA_VDDQ_ABC      EU7G1            6        PXM1310B_QFN-IC,H89186-001
SMB_VR_SDA_VDDQ_ABC      R7F26            1        RES_0402-20.0,1%,1/16W,CHIP,G2A
SMB_VR_SDA_VDDQ_DEF      EU7A5            6        PXM1310B_QFN-IC,H89186-001
SMB_VR_SDA_VDDQ_DEF      R7B2             1        RES_0402-20.0,1%,1/16W,CHIP,G2A
SMB_VR_SDA_VDDQ_GHJ      EU1G2            6        PXM1310B_QFN-IC,H89186-001
SMB_VR_SDA_VDDQ_GHJ      R1G21            1        RES_0402-0.0,5%,1/16W,CHIP,G21A
SMB_VR_SDA_VDDQ_KLM      EU1B1            6        PXM1310B_QFN-IC,H89186-001
SMB_VR_SDA_VDDQ_KLM      R1B7             1        RES_0402-20.0,1%,1/16W,CHIP,G2A
SMB_VR_STBY_LVC3_SCL     J4B2             A18      SCONN120_H61426002_SM-CONN,H61A
SMB_VR_STBY_LVC3_SCL     J6B1             A18      SCONN120_H61426002_SM-CONN,H61A
SMB_VR_STBY_LVC3_SCL     J8D4             3        CONN3_C95678002_PIP-CONN,C9567A
SMB_VR_STBY_LVC3_SCL     R1B6             2        RES_0402-20.0,1%,1/16W,CHIP,G2A
SMB_VR_STBY_LVC3_SCL     R1C25            2        RES_0402-0.0,5%,1/16W,CHIP,G21A
SMB_VR_STBY_LVC3_SCL     R1G19            2        RES_0402-0.0,5%,1/16W,CHIP,G21A
SMB_VR_STBY_LVC3_SCL     R1U11            2        RES_0402-0.0,5%,1/16W,CHIP,G21A
SMB_VR_STBY_LVC3_SCL     R3P24            1        RES_0402-20.0,1%,1/16W,CHIP,G2A
SMB_VR_STBY_LVC3_SCL     R4D43            1        RES_0402-20.0,1%,1/16W,CHIP,G2A
SMB_VR_STBY_LVC3_SCL     R4D53            2        RES_0402-0.0,5%,1/16W,CHIP,G21A
SMB_VR_STBY_LVC3_SCL     R6P37            2        RES_0402-2.0K,1%,1/16W,EMPTY,GA
SMB_VR_STBY_LVC3_SCL     R7B3             2        RES_0402-20.0,1%,1/16W,CHIP,G2A
SMB_VR_STBY_LVC3_SCL     R7F25            2        RES_0402-20.0,1%,1/16W,CHIP,G2A
SMB_VR_STBY_LVC3_SCL     R8A9             1        RES_0402-20.0,1%,1/16W,CHIP,G2A
SMB_VR_STBY_LVC3_SCL     R8D4             2        RES_0402-20.0,1%,1/16W,CHIP,G2A
SMB_VR_STBY_LVC3_SCL     R8D15            2        RES_0402-1.37K,1%,1/16W,CHIP,GA
SMB_VR_STBY_LVC3_SCL_R   R1U11            1        RES_0402-0.0,5%,1/16W,CHIP,G21A
SMB_VR_STBY_LVC3_SCL_R   U9F4             C1       AST1250_BGA-IC,G85138-002
SMB_VR_STBY_LVC3_SCL_R1  R8D4             1        RES_0402-20.0,1%,1/16W,CHIP,G2A
SMB_VR_STBY_LVC3_SCL_R1  U7C1             BA4      LBG_CORE_QAT_EXT_D_BGA1-IC,H91A
SMB_VR_STBY_LVC3_SDA     J4B2             B18      SCONN120_H61426002_SM-CONN,H61A
SMB_VR_STBY_LVC3_SDA     J6B1             B18      SCONN120_H61426002_SM-CONN,H61A
SMB_VR_STBY_LVC3_SDA     J8D4             1        CONN3_C95678002_PIP-CONN,C9567A
SMB_VR_STBY_LVC3_SDA     R1B7             2        RES_0402-20.0,1%,1/16W,CHIP,G2A
SMB_VR_STBY_LVC3_SDA     R1C23            2        RES_0402-0.0,5%,1/16W,CHIP,G21A
SMB_VR_STBY_LVC3_SDA     R1G21            2        RES_0402-0.0,5%,1/16W,CHIP,G21A
SMB_VR_STBY_LVC3_SDA     R1U8             2        RES_0402-0.0,5%,1/16W,CHIP,G21A
SMB_VR_STBY_LVC3_SDA     R3P23            1        RES_0402-20.0,1%,1/16W,CHIP,G2A
SMB_VR_STBY_LVC3_SDA     R4D44            1        RES_0402-20.0,1%,1/16W,CHIP,G2A
SMB_VR_STBY_LVC3_SDA     R4D50            2        RES_0402-0.0,5%,1/16W,CHIP,G21A
SMB_VR_STBY_LVC3_SDA     R6P32            2        RES_0402-2.0K,1%,1/16W,EMPTY,GA
SMB_VR_STBY_LVC3_SDA     R7B2             2        RES_0402-20.0,1%,1/16W,CHIP,G2A
SMB_VR_STBY_LVC3_SDA     R7F26            2        RES_0402-20.0,1%,1/16W,CHIP,G2A
SMB_VR_STBY_LVC3_SDA     R8A8             1        RES_0402-20.0,1%,1/16W,CHIP,G2A
SMB_VR_STBY_LVC3_SDA     R8D7             2        RES_0402-20.0,1%,1/16W,CHIP,G2A
SMB_VR_STBY_LVC3_SDA     R8D17            2        RES_0402-1.37K,1%,1/16W,CHIP,GA
SMB_VR_STBY_LVC3_SDA_R   R1U8             1        RES_0402-0.0,5%,1/16W,CHIP,G21A
SMB_VR_STBY_LVC3_SDA_R   U9F4             F4       AST1250_BGA-IC,G85138-002
SMB_VR_STBY_LVC3_SDA_R1  R8D7             1        RES_0402-20.0,1%,1/16W,CHIP,G2A
SMB_VR_STBY_LVC3_SDA_R1  U7C1             BD1      LBG_CORE_QAT_EXT_D_BGA1-IC,H91A
SP1_BMC_HOST_UART_RX     R9F54            1        RES_0402-0.0,5%,1/16W,CHIP,G21A
SP1_BMC_HOST_UART_RX     U8D7             K3       LCMXO2_A_256BGA-IC,H63395-001
SP1_BMC_HOST_UART_RX     U9F1             3        FSA3357_SM-IC,C63273-001
SP1_BMC_HOST_UART_RX     U9F4             U5       AST1250_BGA-IC,G85138-002
SP1_BMC_HOST_UART_TX     R9F56            2        RES_0402-0.0,5%,1/16W,CHIP,G21A
SP1_BMC_HOST_UART_TX     U8D7             K2       LCMXO2_A_256BGA-IC,H63395-001
SP1_BMC_HOST_UART_TX     U9F2             3        FSA3357_SM-IC,C63273-001
SP1_BMC_HOST_UART_TX     U9F4             W1       AST1250_BGA-IC,G85138-002
SP1_HOST_BRIDGE_UART_RX  EU9F3            5        PI7C9X1172_QFN-IC,H66899-001
SP1_HOST_BRIDGE_UART_RX  R9F54            2        RES_0402-0.0,5%,1/16W,CHIP,G21A
SP1_HOST_BRIDGE_UART_TX  EU9F3            6        PI7C9X1172_QFN-IC,H66899-001
SP1_HOST_BRIDGE_UART_TX  R9F56            1        RES_0402-0.0,5%,1/16W,CHIP,G21A
SP2_BMC_CM_UART_RX       R9F24            2        RES_0402-0.0,5%,1/16W,EMPTY,G2A
SP2_BMC_CM_UART_RX       R9F68            2        RES_0402-0.0,5%,1/16W,CHIP,G21A
SP2_BMC_CM_UART_RX       U7C1             BV44     LBG_CORE_QAT_EXT_D_BGA1-IC,H91A
SP2_BMC_CM_UART_RX       U9F4             V5       AST1250_BGA-IC,G85138-002
SP2_BMC_CM_UART_RX_R     R9F68            1        RES_0402-0.0,5%,1/16W,CHIP,G21A
SP2_BMC_CM_UART_RX_R     R9F69            1        RES_0402-0.0,5%,1/16W,EMPTY,G2A
SP2_BMC_CM_UART_RX_R     U9F1             1        FSA3357_SM-IC,C63273-001
SP2_BMC_CM_UART_RX_R1    R9F67            1        RES_0402-0.0,5%,1/16W,EMPTY,G2A
SP2_BMC_CM_UART_RX_R1    R9F69            2        RES_0402-0.0,5%,1/16W,EMPTY,G2A
SP2_BMC_CM_UART_TX       R9F26            1        RES_0402-0.0,5%,1/16W,EMPTY,G2A
SP2_BMC_CM_UART_TX       R9F66            1        RES_0402-0.0,5%,1/16W,CHIP,G21A
SP2_BMC_CM_UART_TX       U7C1             BR46     LBG_CORE_QAT_EXT_D_BGA1-IC,H91A
SP2_BMC_CM_UART_TX       U9F4             AA1      AST1250_BGA-IC,G85138-002
SP2_BMC_CM_UART_TX_R     R9F65            2        RES_0402-0.0,5%,1/16W,EMPTY,G2A
SP2_BMC_CM_UART_TX_R     R9F66            2        RES_0402-0.0,5%,1/16W,CHIP,G21A
SP2_BMC_CM_UART_TX_R     U9F2             1        FSA3357_SM-IC,C63273-001
SP2_BMC_CM_UART_TX_R1    R9F64            1        RES_0402-0.0,5%,1/16W,EMPTY,G2A
SP2_BMC_CM_UART_TX_R1    R9F65            1        RES_0402-0.0,5%,1/16W,EMPTY,G2A
SPA_5V_SIN_SW            J9A2             10       CONN14_H54902001_PIP-CONN,H549A
SPA_5V_SIN_SW            R9A6             2        RES_0402-20.0K,1%,1/16W,EMPTY,A
SPA_5V_SIN_SW            U9A1             2        TTL1G07_A_SOP-74LVC1G07,IC,C88B
SPA_MID_DBG_RX           R9A8             2        RES_0402-0.0,5%,1/16W,CHIP,G21A
SPA_MID_DBG_RX           R9F24            1        RES_0402-0.0,5%,1/16W,EMPTY,G2A
SPA_MID_DBG_RX           R9F25            1        RES_0402-100.0,1%,1/16W,CHIP,GA
SPA_MID_DBG_RX           R9F63            1        RES_0402-0.0,5%,1/16W,CHIP,G21A
SPA_MID_DBG_RX_R         J1F1             H3       CONN76_H22707001_THMT1-CONN,H2A
SPA_MID_DBG_RX_R         R9F63            2        RES_0402-0.0,5%,1/16W,CHIP,G21A
SPA_MID_DBG_RX_R         R9F64            2        RES_0402-0.0,5%,1/16W,EMPTY,G2A
SPA_MID_DBG_TX           J9A2             9        CONN14_H54902001_PIP-CONN,H549A
SPA_MID_DBG_TX           R9F26            2        RES_0402-0.0,5%,1/16W,EMPTY,G2A
SPA_MID_DBG_TX           R9F27            2        RES_0402-0.0,5%,1/16W,CHIP,G21A
SPA_MID_DBG_TX           R9F70            1        RES_0402-0.0,5%,1/16W,CHIP,G21A
SPA_MID_DBG_TX_R         J1F1             G3       CONN76_H22707001_THMT1-CONN,H2A
SPA_MID_DBG_TX_R         R9F67            2        RES_0402-0.0,5%,1/16W,EMPTY,G2A
SPA_MID_DBG_TX_R         R9F70            2        RES_0402-0.0,5%,1/16W,CHIP,G21A
SPA_SIN_SW_R             R9A7             2        RES_0402-2.21K,1%,1/16W,CHIP,GA
SPA_SIN_SW_R             R9A8             1        RES_0402-0.0,5%,1/16W,CHIP,G21A
SPA_SIN_SW_R             U9A1             4        TTL1G07_A_SOP-74LVC1G07,IC,C88B
SPI_BIOS_SOCKET_IO2      R3U1             1        RES_0402-33.2,1%,1/16W,CHIP,G2A
SPI_BIOS_SOCKET_IO2      R7F37            1        RES_0402-33.2,1%,1/16W,CHIP,G2A
SPI_BIOS_SOCKET_IO2      U2T1             4        PI3B3257A_TSSOPLF-IC,E16801-001
SPI_BIOS_SOCKET_IO3      R3T1             1        RES_0402-33.2,1%,1/16W,CHIP,G2A
SPI_BIOS_SOCKET_IO3      R7F3             1        RES_0402-33.2,1%,1/16W,CHIP,G2A
SPI_BIOS_SOCKET_IO3      U2T1             7        PI3B3257A_TSSOPLF-IC,E16801-001
SPI_BMC_BT_CLK           R9F21            2        RES_0402-33.2,1%,1/16W,CHIP,G2A
SPI_BMC_BT_CLK           U8F2             16       W25Q128_SKT16-IC,H12709-001
SPI_BMC_BT_CLK_R         R9F21            1        RES_0402-33.2,1%,1/16W,CHIP,G2A
SPI_BMC_BT_CLK_R         U9F4             T22      AST1250_BGA-IC,G85138-002
SPI_BMC_BT_CS_N          R1T26            1        RES_0402-22.1,1.0%,1/16W,CHIP,A
SPI_BMC_BT_CS_N          R8F13            2        RES_0402-4.75K,1%,1/16W,CHIP,GA
SPI_BMC_BT_CS_N          U8F2             7        W25Q128_SKT16-IC,H12709-001
SPI_BMC_BT_CS_R_N        R1T26            2        RES_0402-22.1,1.0%,1/16W,CHIP,A
SPI_BMC_BT_CS_R_N        U9F4             R19      AST1250_BGA-IC,G85138-002
SPI_BMC_BT_DI            R8F12            1        RES_0402-33.2,1%,1/16W,CHIP,G2A
SPI_BMC_BT_DI            U9F4             T20      AST1250_BGA-IC,G85138-002
SPI_BMC_BT_DI_R          R8F12            2        RES_0402-33.2,1%,1/16W,CHIP,G2A
SPI_BMC_BT_DI_R          U8F2             8        W25Q128_SKT16-IC,H12709-001
SPI_BMC_BT_DO            R9F41            2        RES_0402-33.2,1%,1/16W,CHIP,G2A
SPI_BMC_BT_DO            U8F2             15       W25Q128_SKT16-IC,H12709-001
SPI_BMC_BT_DO_R          R9F41            1        RES_0402-33.2,1%,1/16W,CHIP,G2A
SPI_BMC_BT_DO_R          U9F4             T21      AST1250_BGA-IC,G85138-002
SPI_BMC_CLK              U8F1             3        PI3B3257A_TSSOPLF-IC,E16801-001
SPI_BMC_CLK              U9F4             G19      AST1250_BGA-IC,G85138-002
SPI_BMC_CS0_N            U8F1             10       PI3B3257A_TSSOPLF-IC,E16801-001
SPI_BMC_CS0_N            U9F4             B22      AST1250_BGA-IC,G85138-002
SPI_BMC_DI               U8F1             13       PI3B3257A_TSSOPLF-IC,E16801-001
SPI_BMC_DI               U9F4             E20      AST1250_BGA-IC,G85138-002
SPI_BMC_DO               U8F1             6        PI3B3257A_TSSOPLF-IC,E16801-001
SPI_BMC_DO               U9F4             C18      AST1250_BGA-IC,G85138-002
SPI_CLK_R0               R8F8             2        RES_0402-33.2,1%,1/16W,CHIP,G2A
SPI_CLK_R0               U7F1             16       W25Q256_XSOI-IC,H25002-001
SPI_CLK_R1               R8F7             2        RES_0402-33.2,1%,1/16W,CHIP,G2A
SPI_CLK_R1               U3T1             16       W25Q256_XSOI-IC,H25002-001
SPI_CS0_PRIMARY_N        R2T13            1        RES_0402-200.0,1%,1/16W,CHIP,GA
SPI_CS0_PRIMARY_N        U2T3             4        TTL1G32_A_SOT-74LVC1G32,IC,E60B
SPI_CS0_PRIMARY_R_N      R2T13            2        RES_0402-200.0,1%,1/16W,CHIP,GA
SPI_CS0_PRIMARY_R_N      R7F5             2        RES_0402-4.75K,1%,1/16W,CHIP,GA
SPI_CS0_PRIMARY_R_N      U7F1             7        W25Q256_XSOI-IC,H25002-001
SPI_CS0_SECONDARY_N      R2T9             1        RES_0402-75,1.0%,1/16W,CHIP,G2A
SPI_CS0_SECONDARY_N      U2T2             4        TTL1G32_A_SOT-74LVC1G32,IC,E60B
SPI_CS0_SECONDARY_R_N    R2T9             2        RES_0402-75,1.0%,1/16W,CHIP,G2A
SPI_CS0_SECONDARY_R_N    R3T5             2        RES_0402-4.75K,1%,1/16W,CHIP,GA
SPI_CS0_SECONDARY_R_N    U3T1             7        W25Q256_XSOI-IC,H25002-001
SPI_MISO_R0              R7F4             2        RES_0402-33.2,1%,1/16W,CHIP,G2A
SPI_MISO_R0              U7F1             8        W25Q256_XSOI-IC,H25002-001
SPI_MISO_R1              R3T2             2        RES_0402-33.2,1%,1/16W,CHIP,G2A
SPI_MISO_R1              U3T1             8        W25Q256_XSOI-IC,H25002-001
SPI_NIC_CS_N             R9E5             2        RES_0402-33.2,1%,1/16W,CHIP,G2A
SPI_NIC_CS_N             U9E1             1        M25PE16_SM-IC,H77797-001
SPI_NIC_CS_R_N           EU9E1            15       SPRINGVILLE_SM1-IC,G47144-004
SPI_NIC_CS_R_N           R9E5             1        RES_0402-33.2,1%,1/16W,CHIP,G2A
SPI_NIC_MISO             EU9E1            14       SPRINGVILLE_SM1-IC,G47144-004
SPI_NIC_MISO             R9E6             2        RES_0402-33.2,1%,1/16W,CHIP,G2A
SPI_NIC_MISO_R           R9E6             1        RES_0402-33.2,1%,1/16W,CHIP,G2A
SPI_NIC_MISO_R           U9E1             2        M25PE16_SM-IC,H77797-001
SPI_NIC_MOSI             R1R6             1        RES_0402-3.32K,1%,1/16W,EMPTY,A
SPI_NIC_MOSI             R1R7             2        RES_0402-20.0K,1%,1/16W,CHIP,GA
SPI_NIC_MOSI             R9E9             2        RES_0402-33.2,1%,1/16W,CHIP,G2A
SPI_NIC_MOSI             U9E1             5        M25PE16_SM-IC,H77797-001
SPI_NIC_MOSI_R           EU9E1            12       SPRINGVILLE_SM1-IC,G47144-004
SPI_NIC_MOSI_R           R9E9             1        RES_0402-33.2,1%,1/16W,CHIP,G2A
SPI_NIC_SCLK             R9E8             2        RES_0402-33.2,1%,1/16W,CHIP,G2A
SPI_NIC_SCLK             U9E1             6        M25PE16_SM-IC,H77797-001
SPI_NIC_SCLK_R           EU9E1            13       SPRINGVILLE_SM1-IC,G47144-004
SPI_NIC_SCLK_R           R9E8             1        RES_0402-33.2,1%,1/16W,CHIP,G2A
SPI_PCH_CLK              R8E9             1        RES_0402-33.2,1%,1/16W,CHIP,G2A
SPI_PCH_CLK              U7C1             K2       LBG_CORE_QAT_EXT_D_BGA1-IC,H91A
SPI_PCH_CLK              U8F1             2        PI3B3257A_TSSOPLF-IC,E16801-001
SPI_PCH_CS0_N            R7C16            2        RES_0402-33.2,1%,1/16W,CHIP,G2A
SPI_PCH_CS0_N            U8F1             11       PI3B3257A_TSSOPLF-IC,E16801-001
SPI_PCH_CS0_R_N          R7C16            1        RES_0402-33.2,1%,1/16W,CHIP,G2A
SPI_PCH_CS0_R_N          U7C1             J3       LBG_CORE_QAT_EXT_D_BGA1-IC,H91A
SPI_PCH_IO2              R2P2             1        RES_0402-1.00K,1%,1/16W,CHIP,GA
SPI_PCH_IO2              R2R11            1        RES_0402-1.00K,1%,1/16W,EMPTY,A
SPI_PCH_IO2              R2R12            1        RES_0402-0.0,5%,1/16W,CHIP,G21A
SPI_PCH_IO2              U7C1             F5       LBG_CORE_QAT_EXT_D_BGA1-IC,H91A
SPI_PCH_IO2_R1           R2R12            2        RES_0402-0.0,5%,1/16W,CHIP,G21A
SPI_PCH_IO2_R1           U2T1             2        PI3B3257A_TSSOPLF-IC,E16801-001
SPI_PCH_IO3              R2T1             1        RES_0402-1.00K,1%,1/16W,CHIP,GA
SPI_PCH_IO3              R2T2             1        RES_0402-0.0,5%,1/16W,CHIP,G21A
SPI_PCH_IO3              R3N17            2        RES_0402-1.00K,1%,1/16W,EMPTY,A
SPI_PCH_IO3              U7C1             L1       LBG_CORE_QAT_EXT_D_BGA1-IC,H91A
SPI_PCH_IO3_R1           R2T2             2        RES_0402-0.0,5%,1/16W,CHIP,G21A
SPI_PCH_IO3_R1           U2T1             5        PI3B3257A_TSSOPLF-IC,E16801-001
SPI_PCH_MISO             R8E13            1        RES_0402-33.2,1%,1/16W,CHIP,G2A
SPI_PCH_MISO             R8F6             1        RES_0402-0.0,5%,1/16W,CHIP,G21A
SPI_PCH_MISO             U7C1             L3       LBG_CORE_QAT_EXT_D_BGA1-IC,H91A
SPI_PCH_MISO_R           R8F6             2        RES_0402-0.0,5%,1/16W,CHIP,G21A
SPI_PCH_MISO_R           U8F1             14       PI3B3257A_TSSOPLF-IC,E16801-001
SPI_PCH_MOSI             R7C15            2        RES_0402-0.0,5%,1/16W,CHIP,G21A
SPI_PCH_MOSI             R8E2             2        RES_0402-1.00K,1%,1/16W,CHIP,GA
SPI_PCH_MOSI             R8E4             1        RES_0402-1.00K,1%,1/16W,EMPTY,A
SPI_PCH_MOSI             R8E6             2        RES_0402-1.00K,1%,1/16W,EMPTY,A
SPI_PCH_MOSI             R8E10            1        RES_0402-33.2,1%,1/16W,CHIP,G2A
SPI_PCH_MOSI             U8F1             5        PI3B3257A_TSSOPLF-IC,E16801-001
SPI_PCH_MOSI_R           R7C15            1        RES_0402-0.0,5%,1/16W,CHIP,G21A
SPI_PCH_MOSI_R           U7C1             H4       LBG_CORE_QAT_EXT_D_BGA1-IC,H91A
SPI_PCH_TPM_CLK_R        J8E1             1        SCONN11_H67026001_SM-CONN,H670A
SPI_PCH_TPM_CLK_R        R8E9             2        RES_0402-33.2,1%,1/16W,CHIP,G2A
SPI_PCH_TPM_CS_N         R8D35            1        RES_0402-0.0,5%,1/16W,CHIP,G21A
SPI_PCH_TPM_CS_N         U7C1             K4       LBG_CORE_QAT_EXT_D_BGA1-IC,H91A
SPI_PCH_TPM_CS_R_N       J8E1             5        SCONN11_H67026001_SM-CONN,H670A
SPI_PCH_TPM_CS_R_N       R8D35            2        RES_0402-0.0,5%,1/16W,CHIP,G21A
SPI_PCH_TPM_MISO_R       J8E1             4        SCONN11_H67026001_SM-CONN,H670A
SPI_PCH_TPM_MISO_R       R8E13            2        RES_0402-33.2,1%,1/16W,CHIP,G2A
SPI_PCH_TPM_MOSI_R       J8E1             3        SCONN11_H67026001_SM-CONN,H670A
SPI_PCH_TPM_MOSI_R       R8E10            2        RES_0402-33.2,1%,1/16W,CHIP,G2A
SPI_SWITCH_CLK           R8F7             1        RES_0402-33.2,1%,1/16W,CHIP,G2A
SPI_SWITCH_CLK           R8F8             1        RES_0402-33.2,1%,1/16W,CHIP,G2A
SPI_SWITCH_CLK           U8F1             4        PI3B3257A_TSSOPLF-IC,E16801-001
SPI_SWITCH_CS0_N         R2T8             2        RES_0402-10.0K,1%,1/16W,CHIP,GA
SPI_SWITCH_CS0_N         U2T2             2        TTL1G32_A_SOT-74LVC1G32,IC,E60B
SPI_SWITCH_CS0_N         U2T3             2        TTL1G32_A_SOT-74LVC1G32,IC,E60B
SPI_SWITCH_CS0_N         U8F1             9        PI3B3257A_TSSOPLF-IC,E16801-001
SPI_SWITCH_MISO          R3T2             1        RES_0402-33.2,1%,1/16W,CHIP,G2A
SPI_SWITCH_MISO          R7F4             1        RES_0402-33.2,1%,1/16W,CHIP,G2A
SPI_SWITCH_MISO          U8F1             12       PI3B3257A_TSSOPLF-IC,E16801-001
SPI_SWITCH_MOSI          R3T10            1        RES_0402-33.2,1%,1/16W,CHIP,G2A
SPI_SWITCH_MOSI          R7F29            1        RES_0402-33.2,1%,1/16W,CHIP,G2A
SPI_SWITCH_MOSI          U8F1             7        PI3B3257A_TSSOPLF-IC,E16801-001
SPI_SWITCH_MOSI_R0       R7F29            2        RES_0402-33.2,1%,1/16W,CHIP,G2A
SPI_SWITCH_MOSI_R0       U7F1             15       W25Q256_XSOI-IC,H25002-001
SPI_SWITCH_MOSI_R1       R3T10            2        RES_0402-33.2,1%,1/16W,CHIP,G2A
SPI_SWITCH_MOSI_R1       U3T1             15       W25Q256_XSOI-IC,H25002-001
SVID_ALERT0_CPU0_N       R6N10            1        RES_0402-221,1.0%,1/16W,CHIP,GA
SVID_ALERT0_CPU0_N       U5D1             DE44     SKX_EXT_B_BGA1-IC,TBD
SVID_ALERT0_CPU0_R_N     J6B1             A19      SCONN120_H61426002_SM-CONN,H61A
SVID_ALERT0_CPU0_R_N     R3P1             2        RES_0402-0.0,5%,1/16W,CHIP,G21A
SVID_ALERT0_CPU0_R_N     R4D67            2        RES_0402-0.0,5%,1/16W,CHIP,G21A
SVID_ALERT0_CPU0_R_N     R6N1             1        RES_0402-49.9,1%,1/16W,CHIP,G2A
SVID_ALERT0_CPU0_R_N     R6N10            2        RES_0402-221,1.0%,1/16W,CHIP,GA
SVID_ALERT0_CPU1_N       R3B1             1        RES_0402-221,1.0%,1/16W,CHIP,GA
SVID_ALERT0_CPU1_N       U2D1             DE44     SKX_EXT_B_BGA1-IC,TBD
SVID_ALERT0_CPU1_R_N     J4B2             A19      SCONN120_H61426002_SM-CONN,H61A
SVID_ALERT0_CPU1_R_N     R1D3             2        RES_0402-0.0,5%,1/16W,CHIP,G21A
SVID_ALERT0_CPU1_R_N     R3B1             2        RES_0402-221,1.0%,1/16W,CHIP,GA
SVID_ALERT0_CPU1_R_N     R3B2             1        RES_0402-49.9,1%,1/16W,CHIP,G2A
SVID_ALERT0_CPU1_R_N     R4D56            2        RES_0402-0.0,5%,1/16W,CHIP,G21A
SVID_ALERT1_CPU0_N       R6B3             1        RES_0402-221,1.0%,1/16W,CHIP,GA
SVID_ALERT1_CPU0_N       U5D1             DL44     SKX_EXT_B_BGA1-IC,TBD
SVID_ALERT1_CPU0_R_N     J6B1             B19      SCONN120_H61426002_SM-CONN,H61A
SVID_ALERT1_CPU0_R_N     R6B1             2        RES_0402-49.9,1%,1/16W,CHIP,G2A
SVID_ALERT1_CPU0_R_N     R6B3             2        RES_0402-221,1.0%,1/16W,CHIP,GA
SVID_ALERT1_CPU0_R_N     R7A11            2        RES_0402-0.0,5%,1/16W,CHIP,G21A
SVID_ALERT1_CPU0_R_N     R7G4             2        RES_0402-0.0,5%,1/16W,CHIP,G21A
SVID_ALERT1_CPU1_N       R1C1             1        RES_0402-221,1.0%,1/16W,CHIP,GA
SVID_ALERT1_CPU1_N       U2D1             DL44     SKX_EXT_B_BGA1-IC,TBD
SVID_ALERT1_CPU1_R_N     J4B2             B19      SCONN120_H61426002_SM-CONN,H61A
SVID_ALERT1_CPU1_R_N     R1B11            2        RES_0402-0.0,5%,1/16W,CHIP,G21A
SVID_ALERT1_CPU1_R_N     R1C1             2        RES_0402-221,1.0%,1/16W,CHIP,GA
SVID_ALERT1_CPU1_R_N     R1G9             2        RES_0402-0.0,5%,1/16W,CHIP,G21A
SVID_ALERT1_CPU1_R_N     R9N1             2        RES_0402-49.9,1%,1/16W,CHIP,G2A
SVID_ALERT_PVCCIO_CPU0   EU3P1            17       PXE1110B_QFN-IC,H89187-001
SVID_ALERT_PVCCIO_CPU0   R3P1             1        RES_0402-0.0,5%,1/16W,CHIP,G21A
SVID_ALERT_PVCCIO_CPU1   EU4D5            17       PXE1110B_QFN-IC,H89187-001
SVID_ALERT_PVCCIO_CPU1   R4D56            1        RES_0402-0.0,5%,1/16W,CHIP,G21A
SVID_ALERT_PVDDQ_ABC     EU7G1            17       PXM1310B_QFN-IC,H89186-001
SVID_ALERT_PVDDQ_ABC     R7G4             1        RES_0402-0.0,5%,1/16W,CHIP,G21A
SVID_ALERT_PVDDQ_DEF     EU7A5            17       PXM1310B_QFN-IC,H89186-001
SVID_ALERT_PVDDQ_DEF     R7A11            1        RES_0402-0.0,5%,1/16W,CHIP,G21A
SVID_ALERT_PVDDQ_GHJ     EU1G2            17       PXM1310B_QFN-IC,H89186-001
SVID_ALERT_PVDDQ_GHJ     R1G9             1        RES_0402-0.0,5%,1/16W,CHIP,G21A
SVID_ALERT_PVDDQ_KLM     EU1B1            17       PXM1310B_QFN-IC,H89186-001
SVID_ALERT_PVDDQ_KLM     R1B11            1        RES_0402-0.0,5%,1/16W,CHIP,G21A
SVID_CLK0_CPU0           R6N12            1        RES_0402-0.0,5%,1/16W,CHIP,G21A
SVID_CLK0_CPU0           U5D1             DC44     SKX_EXT_B_BGA1-IC,TBD
SVID_CLK0_CPU0_R         J6B1             A20      SCONN120_H61426002_SM-CONN,H61A
SVID_CLK0_CPU0_R         R3P15            1        RES_0402-150.0,1%,1/16W,CHIP,GA
SVID_CLK0_CPU0_R         R3P17            2        RES_0402-49.9,1%,1/16W,EMPTY,GA
SVID_CLK0_CPU0_R         R4E6             1        RES_0402-150.0,1%,1/16W,CHIP,GA
SVID_CLK0_CPU0_R         R4E9             2        RES_0402-49.9,1%,1/16W,CHIP,G2A
SVID_CLK0_CPU0_R         R6N12            2        RES_0402-0.0,5%,1/16W,CHIP,G21A
SVID_CLK0_CPU1           R3B5             1        RES_0402-0.0,5%,1/16W,CHIP,G21A
SVID_CLK0_CPU1           U2D1             DC44     SKX_EXT_B_BGA1-IC,TBD
SVID_CLK0_CPU1_R         J4B2             A20      SCONN120_H61426002_SM-CONN,H61A
SVID_CLK0_CPU1_R         R1D9             1        RES_0402-150.0,1%,1/16W,CHIP,GA
SVID_CLK0_CPU1_R         R3B5             2        RES_0402-0.0,5%,1/16W,CHIP,G21A
SVID_CLK0_CPU1_R         R4D51            1        RES_0402-150.0,1%,1/16W,CHIP,GA
SVID_CLK0_CPU1_R         R6P33            2        RES_0402-110,1%,1/16W,EMPTY,G2A
SVID_CLK0_CPU1_R         R9P2             2        RES_0402-49.9,1%,1/16W,CHIP,G2A
SVID_CLK1_CPU0           R6B5             1        RES_0402-0.0,5%,1/16W,CHIP,G21A
SVID_CLK1_CPU0           U5D1             DG44     SKX_EXT_B_BGA1-IC,TBD
SVID_CLK1_CPU0_R         J6B1             E20      SCONN120_H61426002_SM-CONN,H61A
SVID_CLK1_CPU0_R         R3L13            2        RES_0402-49.9,1%,1/16W,CHIP,G2A
SVID_CLK1_CPU0_R         R3T11            2        RES_0402-49.9,1%,1/16W,EMPTY,GA
SVID_CLK1_CPU0_R         R6B5             2        RES_0402-0.0,5%,1/16W,CHIP,G21A
SVID_CLK1_CPU0_R         R7A17            1        RES_0402-150.0,1%,1/16W,CHIP,GA
SVID_CLK1_CPU0_R         R7G24            1        RES_0402-150.0,1%,1/16W,CHIP,GA
SVID_CLK1_CPU1           R1C3             1        RES_0402-0.0,5%,1/16W,CHIP,G21A
SVID_CLK1_CPU1           U2D1             DG44     SKX_EXT_B_BGA1-IC,TBD
SVID_CLK1_CPU1_R         J4B2             E20      SCONN120_H61426002_SM-CONN,H61A
SVID_CLK1_CPU1_R         R1B8             1        RES_0402-150.0,1%,1/16W,CHIP,GA
SVID_CLK1_CPU1_R         R1C3             2        RES_0402-0.0,5%,1/16W,CHIP,G21A
SVID_CLK1_CPU1_R         R1G7             1        RES_0402-150.0,1%,1/16W,CHIP,GA
SVID_CLK1_CPU1_R         R9M6             2        RES_0402-49.9,1%,1/16W,CHIP,G2A
SVID_CLK1_CPU1_R         R9U4             2        RES_0402-49.9,1%,1/16W,EMPTY,GA
SVID_CLK_PVCCIO_CPU0     EU3P1            15       PXE1110B_QFN-IC,H89187-001
SVID_CLK_PVCCIO_CPU0     R3P15            2        RES_0402-150.0,1%,1/16W,CHIP,GA
SVID_CLK_PVCCIO_CPU1     EU4D5            15       PXE1110B_QFN-IC,H89187-001
SVID_CLK_PVCCIO_CPU1     R4D51            2        RES_0402-150.0,1%,1/16W,CHIP,GA
SVID_CLK_PVDDQ_ABC       EU7G1            15       PXM1310B_QFN-IC,H89186-001
SVID_CLK_PVDDQ_ABC       R7G24            2        RES_0402-150.0,1%,1/16W,CHIP,GA
SVID_CLK_PVDDQ_DEF       EU7A5            15       PXM1310B_QFN-IC,H89186-001
SVID_CLK_PVDDQ_DEF       R7A17            2        RES_0402-150.0,1%,1/16W,CHIP,GA
SVID_CLK_PVDDQ_GHJ       EU1G2            15       PXM1310B_QFN-IC,H89186-001
SVID_CLK_PVDDQ_GHJ       R1G7             2        RES_0402-150.0,1%,1/16W,CHIP,GA
SVID_CLK_PVDDQ_KLM       EU1B1            15       PXM1310B_QFN-IC,H89186-001
SVID_CLK_PVDDQ_KLM       R1B8             2        RES_0402-150.0,1%,1/16W,CHIP,GA
SVID_DIO0_CPU0           R6N11            1        RES_0402-0.0,5%,1/16W,CHIP,G21A
SVID_DIO0_CPU0           U5D1             DB45     SKX_EXT_B_BGA1-IC,TBD
SVID_DIO0_CPU0_R         J6B1             B20      SCONN120_H61426002_SM-CONN,H61A
SVID_DIO0_CPU0_R         R3P11            1        RES_0402-0.0,5%,1/16W,CHIP,G21A
SVID_DIO0_CPU0_R         R3P13            2        RES_0402-100.0,1%,1/16W,EMPTY,A
SVID_DIO0_CPU0_R         R4D66            2        RES_0402-0.0,5%,1/16W,CHIP,G21A
SVID_DIO0_CPU0_R         R4E10            2        RES_0402-100.0,1%,1/16W,CHIP,GA
SVID_DIO0_CPU0_R         R6N2             1        RES_0402-100.0,1%,1/16W,CHIP,GA
SVID_DIO0_CPU0_R         R6N11            2        RES_0402-0.0,5%,1/16W,CHIP,G21A
SVID_DIO0_CPU1           R3B3             1        RES_0402-0.0,5%,1/16W,CHIP,G21A
SVID_DIO0_CPU1           U2D1             DB45     SKX_EXT_B_BGA1-IC,TBD
SVID_DIO0_CPU1_R         J4B2             B20      SCONN120_H61426002_SM-CONN,H61A
SVID_DIO0_CPU1_R         R1D2             2        RES_0402-0.0,5%,1/16W,CHIP,G21A
SVID_DIO0_CPU1_R         R3B3             2        RES_0402-0.0,5%,1/16W,CHIP,G21A
SVID_DIO0_CPU1_R         R3B4             1        RES_0402-100.0,1%,1/16W,CHIP,GA
SVID_DIO0_CPU1_R         R4D54            1        RES_0402-0.0,5%,1/16W,CHIP,G21A
SVID_DIO0_CPU1_R         R6P35            2        RES_0402-100.0,1%,1/16W,EMPTY,A
SVID_DIO0_CPU1_R         R9P1             2        RES_0402-100.0,1%,1/16W,CHIP,GA
SVID_DIO1_CPU0           R6B4             1        RES_0402-0.0,5%,1/16W,CHIP,G21A
SVID_DIO1_CPU0           U5D1             DJ44     SKX_EXT_B_BGA1-IC,TBD
SVID_DIO1_CPU0_R         J6B1             F20      SCONN120_H61426002_SM-CONN,H61A
SVID_DIO1_CPU0_R         R3L11            2        RES_0402-100.0,1%,1/16W,EMPTY,A
SVID_DIO1_CPU0_R         R3U2             2        RES_0402-100.0,1%,1/16W,CHIP,GA
SVID_DIO1_CPU0_R         R6B2             2        RES_0402-100.0,1%,1/16W,CHIP,GA
SVID_DIO1_CPU0_R         R6B4             2        RES_0402-0.0,5%,1/16W,CHIP,G21A
SVID_DIO1_CPU0_R         R7A12            2        RES_0402-0.0,5%,1/16W,CHIP,G21A
SVID_DIO1_CPU0_R         R7G2             2        RES_0402-0.0,5%,1/16W,CHIP,G21A
SVID_DIO1_CPU1           R1C2             1        RES_0402-0.0,5%,1/16W,CHIP,G21A
SVID_DIO1_CPU1           U2D1             DJ44     SKX_EXT_B_BGA1-IC,TBD
SVID_DIO1_CPU1_R         J4B2             F20      SCONN120_H61426002_SM-CONN,H61A
SVID_DIO1_CPU1_R         R1B10            2        RES_0402-0.0,5%,1/16W,CHIP,G21A
SVID_DIO1_CPU1_R         R1C2             2        RES_0402-0.0,5%,1/16W,CHIP,G21A
SVID_DIO1_CPU1_R         R1G10            2        RES_0402-0.0,5%,1/16W,CHIP,G21A
SVID_DIO1_CPU1_R         R9M7             2        RES_0402-100.0,1%,1/16W,EMPTY,A
SVID_DIO1_CPU1_R         R9N2             2        RES_0402-100.0,1%,1/16W,CHIP,GA
SVID_DIO1_CPU1_R         R9U3             2        RES_0402-100.0,1%,1/16W,CHIP,GA
SVID_VALERT_VCCIN_CPU0   EU4D4            19       PXE1610B_QFN-IC,H79206-001
SVID_VALERT_VCCIN_CPU0   R4D67            1        RES_0402-0.0,5%,1/16W,CHIP,G21A
SVID_VALERT_VCCIN_CPU1   EU1C2            19       PXE1610B_QFN-IC,H79206-001
SVID_VALERT_VCCIN_CPU1   R1D3             1        RES_0402-0.0,5%,1/16W,CHIP,G21A
SVID_VCLK_PVCCIN_CPU0    EU4D4            17       PXE1610B_QFN-IC,H79206-001
SVID_VCLK_PVCCIN_CPU0    R4E6             2        RES_0402-150.0,1%,1/16W,CHIP,GA
SVID_VCLK_PVCCIN_CPU1    EU1C2            17       PXE1610B_QFN-IC,H79206-001
SVID_VCLK_PVCCIN_CPU1    R1D9             2        RES_0402-150.0,1%,1/16W,CHIP,GA
SVID_VDIO_PVCCIN_CPU0    EU4D4            18       PXE1610B_QFN-IC,H79206-001
SVID_VDIO_PVCCIN_CPU0    R4D66            1        RES_0402-0.0,5%,1/16W,CHIP,G21A
SVID_VDIO_PVCCIN_CPU1    EU1C2            18       PXE1610B_QFN-IC,H79206-001
SVID_VDIO_PVCCIN_CPU1    R1D2             1        RES_0402-0.0,5%,1/16W,CHIP,G21A
SVID_VDIO_PVCCIO_CPU0    EU3P1            16       PXE1110B_QFN-IC,H89187-001
SVID_VDIO_PVCCIO_CPU0    R3P11            2        RES_0402-0.0,5%,1/16W,CHIP,G21A
SVID_VDIO_PVCCIO_CPU1    EU4D5            16       PXE1110B_QFN-IC,H89187-001
SVID_VDIO_PVCCIO_CPU1    R4D54            2        RES_0402-0.0,5%,1/16W,CHIP,G21A
SVID_VDIO_PVDDQ_ABC      EU7G1            16       PXM1310B_QFN-IC,H89186-001
SVID_VDIO_PVDDQ_ABC      R7G2             1        RES_0402-0.0,5%,1/16W,CHIP,G21A
SVID_VDIO_PVDDQ_DEF      EU7A5            16       PXM1310B_QFN-IC,H89186-001
SVID_VDIO_PVDDQ_DEF      R7A12            1        RES_0402-0.0,5%,1/16W,CHIP,G21A
SVID_VDIO_PVDDQ_GHJ      EU1G2            16       PXM1310B_QFN-IC,H89186-001
SVID_VDIO_PVDDQ_GHJ      R1G10            1        RES_0402-0.0,5%,1/16W,CHIP,G21A
SVID_VDIO_PVDDQ_KLM      EU1B1            16       PXM1310B_QFN-IC,H89186-001
SVID_VDIO_PVDDQ_KLM      R1B10            1        RES_0402-0.0,5%,1/16W,CHIP,G21A
TP_10GBE_KR0_MON_DN      U7C1             BL26     LBG_CORE_QAT_EXT_D_BGA1-IC,H91A
TP_10GBE_KR0_MON_DP      U7C1             BN26     LBG_CORE_QAT_EXT_D_BGA1-IC,H91A
TP_10GBE_KR1_MON_DN      U7C1             BL33     LBG_CORE_QAT_EXT_D_BGA1-IC,H91A
TP_10GBE_KR1_MON_DP      U7C1             BN33     LBG_CORE_QAT_EXT_D_BGA1-IC,H91A
TP_33P_33M_SMBADR        EU8F2            22       ICS9FGP204_MLFP-IC,E95226-001
TP_ADC128_VREF           EU9G1            1        ADC128D818_SM-IC,H63642-001
TP_BIOS_RECOVER_BOOT     J7G3             8        CONN12_C73564003_PIP-CONN,C735A
TP_BIOS_USB_RECOVERY     J7G3             2        CONN12_C73564003_PIP-CONN,C735A
TP_BMC_DISABLE           J9G1             1        CONN12_C73564003_PIP-CONN,C735A
TP_CD_HFI1_CPU1_I2CDAT   U2D1             BH23     SKX_EXT_B_BGA1-IC,TBD
TP_CD_HFI1_CPU1_I2CLK    U2D1             BJ22     SKX_EXT_B_BGA1-IC,TBD
TP_CD_HFI1_CPU1_INT_N    U2D1             BM21     SKX_EXT_B_BGA1-IC,TBD
TP_CD_HFI1_CPU1_LED_N    U2D1             BM23     SKX_EXT_B_BGA1-IC,TBD
TP_CD_HFI1_CPU1_MODPRST_N U2D1             BT19     SKX_EXT_B_BGA1-IC,TBD
TP_CD_HFI1_CPU1_RESET_N  U2D1             BK23     SKX_EXT_B_BGA1-IC,TBD
TP_CH_A_DIMM_A0_RFU_0    J4G1             205      SCONN288_H44441004_PIP-SCONN,HA
TP_CH_A_DIMM_A0_RFU_1    J4G1             227      SCONN288_H44441004_PIP-SCONN,HA
TP_CH_A_DIMM_A0_RFU_2    J4G1             144      SCONN288_H44441004_PIP-SCONN,HA
TP_CH_A_DIMM_A1_RFU_0    J6T1             205      SCONN288_H44441003_PIP-SCONN,HA
TP_CH_A_DIMM_A1_RFU_1    J6T1             227      SCONN288_H44441003_PIP-SCONN,HA
TP_CH_A_DIMM_A1_RFU_2    J6T1             144      SCONN288_H44441003_PIP-SCONN,HA
TP_CH_B_DIMM_B0_RFU_0    J4G2             205      SCONN288_H44441004_PIP-SCONN,HA
TP_CH_B_DIMM_B0_RFU_1    J4G2             227      SCONN288_H44441004_PIP-SCONN,HA
TP_CH_B_DIMM_B0_RFU_2    J4G2             144      SCONN288_H44441004_PIP-SCONN,HA
TP_CH_B_DIMM_B1_RFU_0    J6U1             205      SCONN288_H44441003_PIP-SCONN,HA
TP_CH_B_DIMM_B1_RFU_1    J6U1             227      SCONN288_H44441003_PIP-SCONN,HA
TP_CH_B_DIMM_B1_RFU_2    J6U1             144      SCONN288_H44441003_PIP-SCONN,HA
TP_CH_C_DIMM_C0_RFU_0    J4G3             205      SCONN288_H44441004_PIP-SCONN,HA
TP_CH_C_DIMM_C0_RFU_1    J4G3             227      SCONN288_H44441004_PIP-SCONN,HA
TP_CH_C_DIMM_C0_RFU_2    J4G3             144      SCONN288_H44441004_PIP-SCONN,HA
TP_CH_C_DIMM_C1_RFU_0    J6U2             205      SCONN288_H44441003_PIP-SCONN,HA
TP_CH_C_DIMM_C1_RFU_1    J6U2             227      SCONN288_H44441003_PIP-SCONN,HA
TP_CH_C_DIMM_C1_RFU_2    J6U2             144      SCONN288_H44441003_PIP-SCONN,HA
TP_CH_D_DIMM_D0_RFU_0    J4B1             205      SCONN288_H44441004_PIP-SCONN,HA
TP_CH_D_DIMM_D0_RFU_1    J4B1             227      SCONN288_H44441004_PIP-SCONN,HA
TP_CH_D_DIMM_D0_RFU_2    J4B1             144      SCONN288_H44441004_PIP-SCONN,HA
TP_CH_D_DIMM_D1_RFU_0    J6M1             205      SCONN288_H44441003_PIP-SCONN,HA
TP_CH_D_DIMM_D1_RFU_1    J6M1             227      SCONN288_H44441003_PIP-SCONN,HA
TP_CH_D_DIMM_D1_RFU_2    J6M1             144      SCONN288_H44441003_PIP-SCONN,HA
TP_CH_E_DIMM_E0_RFU_0    J4A2             205      SCONN288_H44441004_PIP-SCONN,HA
TP_CH_E_DIMM_E0_RFU_1    J4A2             227      SCONN288_H44441004_PIP-SCONN,HA
TP_CH_E_DIMM_E0_RFU_2    J4A2             144      SCONN288_H44441004_PIP-SCONN,HA
TP_CH_E_DIMM_E1_RFU_0    J6L2             205      SCONN288_H44441003_PIP-SCONN,HA
TP_CH_E_DIMM_E1_RFU_1    J6L2             227      SCONN288_H44441003_PIP-SCONN,HA
TP_CH_E_DIMM_E1_RFU_2    J6L2             144      SCONN288_H44441003_PIP-SCONN,HA
TP_CH_F_DIMM_F0_RFU_0    J4A1             205      SCONN288_H44441004_PIP-SCONN,HA
TP_CH_F_DIMM_F0_RFU_1    J4A1             227      SCONN288_H44441004_PIP-SCONN,HA
TP_CH_F_DIMM_F0_RFU_2    J4A1             144      SCONN288_H44441004_PIP-SCONN,HA
TP_CH_F_DIMM_F1_RFU_0    J6L1             205      SCONN288_H44441003_PIP-SCONN,HA
TP_CH_F_DIMM_F1_RFU_1    J6L1             227      SCONN288_H44441003_PIP-SCONN,HA
TP_CH_F_DIMM_F1_RFU_2    J6L1             144      SCONN288_H44441003_PIP-SCONN,HA
TP_CH_G_DIMM0_RFU_0      J9T1             205      SCONN288_H44441003_PIP-SCONN,HA
TP_CH_G_DIMM0_RFU_1      J9T1             227      SCONN288_H44441003_PIP-SCONN,HA
TP_CH_G_DIMM0_RFU_2      J9T1             144      SCONN288_H44441003_PIP-SCONN,HA
TP_CH_G_DIMM_G0_RFU_0    J1G1             205      SCONN288_H44441004_PIP-SCONN,HA
TP_CH_G_DIMM_G0_RFU_1    J1G1             227      SCONN288_H44441004_PIP-SCONN,HA
TP_CH_G_DIMM_G0_RFU_2    J1G1             144      SCONN288_H44441004_PIP-SCONN,HA
TP_CH_H_DIMM0_RFU_0      J9U1             205      SCONN288_H44441003_PIP-SCONN,HA
TP_CH_H_DIMM0_RFU_1      J9U1             227      SCONN288_H44441003_PIP-SCONN,HA
TP_CH_H_DIMM0_RFU_2      J9U1             144      SCONN288_H44441003_PIP-SCONN,HA
TP_CH_H_DIMM_H0_RFU_0    J1G2             205      SCONN288_H44441004_PIP-SCONN,HA
TP_CH_H_DIMM_H0_RFU_1    J1G2             227      SCONN288_H44441004_PIP-SCONN,HA
TP_CH_H_DIMM_H0_RFU_2    J1G2             144      SCONN288_H44441004_PIP-SCONN,HA
TP_CH_J_DIMM_J0_RFU_0    J1G3             205      SCONN288_H44441004_PIP-SCONN,HA
TP_CH_J_DIMM_J0_RFU_1    J1G3             227      SCONN288_H44441004_PIP-SCONN,HA
TP_CH_J_DIMM_J0_RFU_2    J1G3             144      SCONN288_H44441004_PIP-SCONN,HA
TP_CH_J_DIMM_J1_RFU_0    J9U2             205      SCONN288_H44441003_PIP-SCONN,HA
TP_CH_J_DIMM_J1_RFU_1    J9U2             227      SCONN288_H44441003_PIP-SCONN,HA
TP_CH_J_DIMM_J1_RFU_2    J9U2             144      SCONN288_H44441003_PIP-SCONN,HA
TP_CH_K_DIMM0_RFU_0      J9M1             205      SCONN288_H44441003_PIP-SCONN,HA
TP_CH_K_DIMM0_RFU_1      J9M1             227      SCONN288_H44441003_PIP-SCONN,HA
TP_CH_K_DIMM0_RFU_2      J9M1             144      SCONN288_H44441003_PIP-SCONN,HA
TP_CH_K_DIMM_K0_RFU_0    J1B1             205      SCONN288_H44441004_PIP-SCONN,HA
TP_CH_K_DIMM_K0_RFU_1    J1B1             227      SCONN288_H44441004_PIP-SCONN,HA
TP_CH_K_DIMM_K0_RFU_2    J1B1             144      SCONN288_H44441004_PIP-SCONN,HA
TP_CH_L_DIMM0_RFU_0      J9L2             205      SCONN288_H44441003_PIP-SCONN,HA
TP_CH_L_DIMM0_RFU_1      J9L2             227      SCONN288_H44441003_PIP-SCONN,HA
TP_CH_L_DIMM0_RFU_2      J9L2             144      SCONN288_H44441003_PIP-SCONN,HA
TP_CH_L_DIMM_L0_RFU_0    J1A2             205      SCONN288_H44441004_PIP-SCONN,HA
TP_CH_L_DIMM_L0_RFU_1    J1A2             227      SCONN288_H44441004_PIP-SCONN,HA
TP_CH_L_DIMM_L0_RFU_2    J1A2             144      SCONN288_H44441004_PIP-SCONN,HA
TP_CH_M_DIMM_M0_RFU_0    J1A1             205      SCONN288_H44441004_PIP-SCONN,HA
TP_CH_M_DIMM_M0_RFU_1    J1A1             227      SCONN288_H44441004_PIP-SCONN,HA
TP_CH_M_DIMM_M0_RFU_2    J1A1             144      SCONN288_H44441004_PIP-SCONN,HA
TP_CH_M_DIMM_M1_RFU_0    J9L1             205      SCONN288_H44441003_PIP-SCONN,HA
TP_CH_M_DIMM_M1_RFU_1    J9L1             227      SCONN288_H44441003_PIP-SCONN,HA
TP_CH_M_DIMM_M1_RFU_2    J9L1             144      SCONN288_H44441003_PIP-SCONN,HA
TP_CLK5_50M_CKMNG        EU8F2            24       ICS9FGP204_MLFP-IC,E95226-001
TP_CLK_100M_NSSCC0_DN    U7C1             A32      LBG_CORE_QAT_EXT_D_BGA1-IC,H91A
TP_CLK_100M_NSSCC0_DP    U7C1             C32      LBG_CORE_QAT_EXT_D_BGA1-IC,H91A
TP_CLK_100M_NSSCC1_DN    U7C1             B38      LBG_CORE_QAT_EXT_D_BGA1-IC,H91A
TP_CLK_100M_NSSCC1_DP    U7C1             D38      LBG_CORE_QAT_EXT_D_BGA1-IC,H91A
TP_CLK_100M_PLAT1_DN     U7C1             B40      LBG_CORE_QAT_EXT_D_BGA1-IC,H91A
TP_CLK_100M_PLAT1_DP     U7C1             D40      LBG_CORE_QAT_EXT_D_BGA1-IC,H91A
TP_CLK_100M_R_DN         EU8F2            8        ICS9FGP204_MLFP-IC,E95226-001
TP_CLK_100M_R_DP         EU8F2            7        ICS9FGP204_MLFP-IC,E95226-001
TP_CLK_100M_SRC12_DN     U7C1             K24      LBG_CORE_QAT_EXT_D_BGA1-IC,H91A
TP_CLK_100M_SRC12_DP     U7C1             H24      LBG_CORE_QAT_EXT_D_BGA1-IC,H91A
TP_CLK_100M_SRC13_DN     U7C1             C24      LBG_CORE_QAT_EXT_D_BGA1-IC,H91A
TP_CLK_100M_SRC13_DP     U7C1             A24      LBG_CORE_QAT_EXT_D_BGA1-IC,H91A
TP_CLK_125M              EU8F2            36       ICS9FGP204_MLFP-IC,E95226-001
TP_CLK_125M_BMCA         EU8F2            37       ICS9FGP204_MLFP-IC,E95226-001
TP_CLK_24M_PMSYNC2       U7C1             BV51     LBG_CORE_QAT_EXT_D_BGA1-IC,H91A
TP_CLK_96M_CKMNG_N       EU8F2            4        ICS9FGP204_MLFP-IC,E95226-001
TP_CLK_96M_CKMNG_P       EU8F2            3        ICS9FGP204_MLFP-IC,E95226-001
TP_CPLD1_PB11B_PCLKC2_0  U8D7             R8       LCMXO2_A_256BGA-IC,H63395-001
TP_CPLD1_PB16A_PCLKT2_1  U8D7             T9       LCMXO2_A_256BGA-IC,H63395-001
TP_CPLD1_PB16B_PCLKC2_1  U8D7             P9       LCMXO2_A_256BGA-IC,H63395-001
TP_CPLD1_PB25B_SI_SISPI  U8D7             P13      LCMXO2_A_256BGA-IC,H63395-001
TP_CPLD1_PB5A_CSSPIN     U8D7             R5       LCMXO2_A_256BGA-IC,H63395-001
TP_CPLD1_PB8A_MCLK_CCLK  U8D7             P6       LCMXO2_A_256BGA-IC,H63395-001
TP_CPLD1_PB8B_SO_SPISO   U8D7             T6       LCMXO2_A_256BGA-IC,H63395-001
TP_CPLD1_PB8D            U8D7             L7       LCMXO2_A_256BGA-IC,H63395-001
TP_CPLD1_PL11A           U8D7             L3       LCMXO2_A_256BGA-IC,H63395-001
TP_CPLD1_PL1A_L_GPLLT_FB U8D7             D3       LCMXO2_A_256BGA-IC,H63395-001
TP_CPLD1_PL1B_L_GPLLC_FB U8D7             D1       LCMXO2_A_256BGA-IC,H63395-001
TP_CPLD1_PL2B_L_GPLLC_IN U8D7             E3       LCMXO2_A_256BGA-IC,H63395-001
TP_CPLD1_PL7D_PCLKT4_0   U8D7             J3       LCMXO2_A_256BGA-IC,H63395-001
TP_CPLD1_PR10C           U8D7             J11      LCMXO2_A_256BGA-IC,H63395-001
TP_CPLD1_PR11B           U8D7             L14      LCMXO2_A_256BGA-IC,H63395-001
TP_CPLD1_PR12D           U8D7             L13      LCMXO2_A_256BGA-IC,H63395-001
TP_CPLD1_PR7A_PCLKT1_0   U8D7             H14      LCMXO2_A_256BGA-IC,H63395-001
TP_CPLD1_PR7B_PCLKC1_0   U8D7             H16      LCMXO2_A_256BGA-IC,H63395-001
TP_CPLD1_PR7C            U8D7             J16      LCMXO2_A_256BGA-IC,H63395-001
TP_CPLD1_PR7D            U8D7             J14      LCMXO2_A_256BGA-IC,H63395-001
TP_CPLD1_PR9A            U8D7             J15      LCMXO2_A_256BGA-IC,H63395-001
TP_CPLD1_PR9C            U8D7             H11      LCMXO2_A_256BGA-IC,H63395-001
TP_CPLD1_PR9D            U8D7             J13      LCMXO2_A_256BGA-IC,H63395-001
TP_CPLD1_PT11A           U8D7             A5       LCMXO2_A_256BGA-IC,H63395-001
TP_CPLD1_PT11B           U8D7             B6       LCMXO2_A_256BGA-IC,H63395-001
TP_CPLD1_PT13A           U8D7             B7       LCMXO2_A_256BGA-IC,H63395-001
TP_CPLD1_PT16B           U8D7             E8       LCMXO2_A_256BGA-IC,H63395-001
TP_CPLD1_PT17B_PCLKC0_1  U8D7             A8       LCMXO2_A_256BGA-IC,H63395-001
TP_CPLD1_PT17C           U8D7             D8       LCMXO2_A_256BGA-IC,H63395-001
TP_CPLD1_PT19D           U8D7             E11      LCMXO2_A_256BGA-IC,H63395-001
TP_CPLD1_PT20A           U8D7             D10      LCMXO2_A_256BGA-IC,H63395-001
TP_CPLD1_PT20B           U8D7             E10      LCMXO2_A_256BGA-IC,H63395-001
TP_CPLD1_PT20D_PROGRAMN  U8D7             B10      LCMXO2_A_256BGA-IC,H63395-001
TP_CPLD1_PT22C           U8D7             B13      LCMXO2_A_256BGA-IC,H63395-001
TP_CPLD1_PT22D           U8D7             A14      LCMXO2_A_256BGA-IC,H63395-001
TP_CPLD1_PT24B           U8D7             A15      LCMXO2_A_256BGA-IC,H63395-001
TP_CPLD1_PT24C_INITN     U8D7             A13      LCMXO2_A_256BGA-IC,H63395-001
TP_CPLD1_PT24D_DONE      U8D7             C13      LCMXO2_A_256BGA-IC,H63395-001
TP_CPU0_KTI2_AMONV       U5D1             CN22     SKX_EXT_B_BGA1-IC,TBD
TP_CPU0_KTI2_DFX_DN      U5D1             CW22     SKX_EXT_B_BGA1-IC,TBD
TP_CPU0_PE_HP_SCL        U5D1             AM19     SKX_EXT_B_BGA1-IC,TBD
TP_CPU0_PE_HP_SDA        U5D1             AL18     SKX_EXT_B_BGA1-IC,TBD
TP_CPU0_PROCDIS_G_N      U5D1             AB17     SKX_EXT_B_BGA1-IC,TBD
TP_CPU0_RSVD_0           U5D1             EF83     SKX_EXT_B_BGA1-IC,TBD
TP_CPU0_RSVD_1           U5D1             EF81     SKX_EXT_B_BGA1-IC,TBD
TP_CPU0_RSVD_2           U5D1             EF77     SKX_EXT_B_BGA1-IC,TBD
TP_CPU0_RSVD_3           U5D1             EF47     SKX_EXT_B_BGA1-IC,TBD
TP_CPU0_RSVD_4           U5D1             EE84     SKX_EXT_B_BGA1-IC,TBD
TP_CPU0_RSVD_5           U5D1             EE82     SKX_EXT_B_BGA1-IC,TBD
TP_CPU0_RSVD_6           U5D1             EE6      SKX_EXT_B_BGA1-IC,TBD
TP_CPU0_RSVD_7           U5D1             EE46     SKX_EXT_B_BGA1-IC,TBD
TP_CPU0_RSVD_8           U5D1             EE16     SKX_EXT_B_BGA1-IC,TBD
TP_CPU0_RSVD_9           U5D1             ED83     SKX_EXT_B_BGA1-IC,TBD
TP_CPU0_RSVD_10          U5D1             ED5      SKX_EXT_B_BGA1-IC,TBD
TP_CPU0_RSVD_11          U5D1             ED45     SKX_EXT_B_BGA1-IC,TBD
TP_CPU0_RSVD_12          U5D1             EC84     SKX_EXT_B_BGA1-IC,TBD
TP_CPU0_RSVD_13          U5D1             EC44     SKX_EXT_B_BGA1-IC,TBD
TP_CPU0_RSVD_14          U5D1             EC4      SKX_EXT_B_BGA1-IC,TBD
TP_CPU0_RSVD_15          U5D1             EC16     SKX_EXT_B_BGA1-IC,TBD
TP_CPU0_RSVD_16          U5D1             EB85     SKX_EXT_B_BGA1-IC,TBD
TP_CPU0_RSVD_17          U5D1             EB5      SKX_EXT_B_BGA1-IC,TBD
TP_CPU0_RSVD_18          U5D1             EB3      SKX_EXT_B_BGA1-IC,TBD
TP_CPU0_RSVD_19          U5D1             EA44     SKX_EXT_B_BGA1-IC,TBD
TP_CPU0_RSVD_20          U5D1             EA4      SKX_EXT_B_BGA1-IC,TBD
TP_CPU0_RSVD_21          U5D1             DY3      SKX_EXT_B_BGA1-IC,TBD
TP_CPU0_RSVD_22          U5D1             DW46     SKX_EXT_B_BGA1-IC,TBD
TP_CPU0_RSVD_23          U5D1             DW44     SKX_EXT_B_BGA1-IC,TBD
TP_CPU0_RSVD_24          U5D1             DV71     SKX_EXT_B_BGA1-IC,TBD
TP_CPU0_RSVD_25          U5D1             DV61     SKX_EXT_B_BGA1-IC,TBD
TP_CPU0_RSVD_26          U5D1             DU44     SKX_EXT_B_BGA1-IC,TBD
TP_CPU0_RSVD_27          U5D1             DT71     SKX_EXT_B_BGA1-IC,TBD
TP_CPU0_RSVD_28          U5D1             DR44     SKX_EXT_B_BGA1-IC,TBD
TP_CPU0_RSVD_29          U5D1             DP65     SKX_EXT_B_BGA1-IC,TBD
TP_CPU0_RSVD_30          U5D1             DP17     SKX_EXT_B_BGA1-IC,TBD
TP_CPU0_RSVD_31          U5D1             DN66     SKX_EXT_B_BGA1-IC,TBD
TP_CPU0_RSVD_32          U5D1             DN62     SKX_EXT_B_BGA1-IC,TBD
TP_CPU0_RSVD_33          U5D1             DM67     SKX_EXT_B_BGA1-IC,TBD
TP_CPU0_RSVD_34          U5D1             DL66     SKX_EXT_B_BGA1-IC,TBD
TP_CPU0_RSVD_35          U5D1             DL38     SKX_EXT_B_BGA1-IC,TBD
TP_CPU0_RSVD_36          U5D1             DK67     SKX_EXT_B_BGA1-IC,TBD
TP_CPU0_RSVD_37          U5D1             DK65     SKX_EXT_B_BGA1-IC,TBD
TP_CPU0_RSVD_38          U5D1             DK37     SKX_EXT_B_BGA1-IC,TBD
TP_CPU0_RSVD_39          U5D1             DK15     SKX_EXT_B_BGA1-IC,TBD
TP_CPU0_RSVD_40          U5D1             DJ66     SKX_EXT_B_BGA1-IC,TBD
TP_CPU0_RSVD_41          U5D1             DJ36     SKX_EXT_B_BGA1-IC,TBD
TP_CPU0_RSVD_42          U5D1             DH65     SKX_EXT_B_BGA1-IC,TBD
TP_CPU0_RSVD_43          U5D1             DG64     SKX_EXT_B_BGA1-IC,TBD
TP_CPU0_RSVD_44          U5D1             DG36     SKX_EXT_B_BGA1-IC,TBD
TP_CPU0_RSVD_45          U5D1             DD51     SKX_EXT_B_BGA1-IC,TBD
TP_CPU0_RSVD_46          U5D1             DC52     SKX_EXT_B_BGA1-IC,TBD
TP_CPU0_RSVD_47          U5D1             DC46     SKX_EXT_B_BGA1-IC,TBD
TP_CPU0_RSVD_48          U5D1             DA56     SKX_EXT_B_BGA1-IC,TBD
TP_CPU0_RSVD_49          U5D1             DA54     SKX_EXT_B_BGA1-IC,TBD
TP_CPU0_RSVD_50          U5D1             DA52     SKX_EXT_B_BGA1-IC,TBD
TP_CPU0_RSVD_51          U5D1             DA40     SKX_EXT_B_BGA1-IC,TBD
TP_CPU0_RSVD_53          U5D1             CY73     SKX_EXT_B_BGA1-IC,TBD
TP_CPU0_RSVD_54          U5D1             CY63     SKX_EXT_B_BGA1-IC,TBD
TP_CPU0_RSVD_55          U5D1             CY57     SKX_EXT_B_BGA1-IC,TBD
TP_CPU0_RSVD_56          U5D1             CY53     SKX_EXT_B_BGA1-IC,TBD
TP_CPU0_RSVD_57          U5D1             CY39     SKX_EXT_B_BGA1-IC,TBD
TP_CPU0_RSVD_59          U5D1             CY23     SKX_EXT_B_BGA1-IC,TBD
TP_CPU0_RSVD_60          U5D1             CW62     SKX_EXT_B_BGA1-IC,TBD
TP_CPU0_RSVD_61          U5D1             CW60     SKX_EXT_B_BGA1-IC,TBD
TP_CPU0_RSVD_64          U5D1             CV69     SKX_EXT_B_BGA1-IC,TBD
TP_CPU0_RSVD_66          U5D1             CU60     SKX_EXT_B_BGA1-IC,TBD
TP_CPU0_RSVD_67          U5D1             CU6      SKX_EXT_B_BGA1-IC,TBD
TP_CPU0_RSVD_69          U5D1             CT69     SKX_EXT_B_BGA1-IC,TBD
TP_CPU0_RSVD_70          U5D1             CT5      SKX_EXT_B_BGA1-IC,TBD
TP_CPU0_RSVD_72          U5D1             CR60     SKX_EXT_B_BGA1-IC,TBD
TP_CPU0_RSVD_73          U5D1             CP31     SKX_EXT_B_BGA1-IC,TBD
TP_CPU0_RSVD_82          U5D1             CK77     SKX_EXT_B_BGA1-IC,TBD
TP_CPU0_RSVD_85          U5D1             CK19     SKX_EXT_B_BGA1-IC,TBD
TP_CPU0_RSVD_90          U5D1             CH77     SKX_EXT_B_BGA1-IC,TBD
TP_CPU0_RSVD_91          U5D1             CH25     SKX_EXT_B_BGA1-IC,TBD
TP_CPU0_RSVD_94          U5D1             CG82     SKX_EXT_B_BGA1-IC,TBD
TP_CPU0_RSVD_95          U5D1             CG78     SKX_EXT_B_BGA1-IC,TBD
TP_CPU0_RSVD_97          U5D1             CG24     SKX_EXT_B_BGA1-IC,TBD
TP_CPU0_RSVD_99          U5D1             CG10     SKX_EXT_B_BGA1-IC,TBD
TP_CPU0_RSVD_100         U5D1             CF81     SKX_EXT_B_BGA1-IC,TBD
TP_CPU0_RSVD_101         U5D1             CF79     SKX_EXT_B_BGA1-IC,TBD
TP_CPU0_RSVD_105         U5D1             CE80     SKX_EXT_B_BGA1-IC,TBD
TP_CPU0_RSVD_106         U5D1             CE78     SKX_EXT_B_BGA1-IC,TBD
TP_CPU0_RSVD_108         U5D1             CD25     SKX_EXT_B_BGA1-IC,TBD
TP_CPU0_RSVD_111         U5D1             CC6      SKX_EXT_B_BGA1-IC,TBD
TP_CPU0_RSVD_113         U5D1             CB5      SKX_EXT_B_BGA1-IC,TBD
TP_CPU0_RSVD_114         U5D1             CB25     SKX_EXT_B_BGA1-IC,TBD
TP_CPU0_RSVD_117         U5D1             CA24     SKX_EXT_B_BGA1-IC,TBD
TP_CPU0_RSVD_119         U5D1             BY25     SKX_EXT_B_BGA1-IC,TBD
TP_CPU0_RSVD_121         U5D1             BW22     SKX_EXT_B_BGA1-IC,TBD
TP_CPU0_RSVD_123         U5D1             BW10     SKX_EXT_B_BGA1-IC,TBD
TP_CPU0_RSVD_124         U5D1             BV23     SKX_EXT_B_BGA1-IC,TBD
TP_CPU0_RSVD_144         U5D1             BG20     SKX_EXT_B_BGA1-IC,TBD
TP_CPU0_RSVD_145         U5D1             BG18     SKX_EXT_B_BGA1-IC,TBD
TP_CPU0_RSVD_146         U5D1             BF21     SKX_EXT_B_BGA1-IC,TBD
TP_CPU0_RSVD_147         U5D1             BE22     SKX_EXT_B_BGA1-IC,TBD
TP_CPU0_RSVD_148         U5D1             BE20     SKX_EXT_B_BGA1-IC,TBD
TP_CPU0_RSVD_149         U5D1             BE18     SKX_EXT_B_BGA1-IC,TBD
TP_CPU0_RSVD_150         U5D1             BD69     SKX_EXT_B_BGA1-IC,TBD
TP_CPU0_RSVD_151         U5D1             BD67     SKX_EXT_B_BGA1-IC,TBD
TP_CPU0_RSVD_152         U5D1             BD65     SKX_EXT_B_BGA1-IC,TBD
TP_CPU0_RSVD_154         U5D1             BD19     SKX_EXT_B_BGA1-IC,TBD
TP_CPU0_RSVD_155         U5D1             BD17     SKX_EXT_B_BGA1-IC,TBD
TP_CPU0_RSVD_156         U5D1             BC68     SKX_EXT_B_BGA1-IC,TBD
TP_CPU0_RSVD_157         U5D1             BC66     SKX_EXT_B_BGA1-IC,TBD
TP_CPU0_RSVD_158         U5D1             BC64     SKX_EXT_B_BGA1-IC,TBD
TP_CPU0_RSVD_159         U5D1             BC22     SKX_EXT_B_BGA1-IC,TBD
TP_CPU0_RSVD_160         U5D1             BC20     SKX_EXT_B_BGA1-IC,TBD
TP_CPU0_RSVD_161         U5D1             BC18     SKX_EXT_B_BGA1-IC,TBD
TP_CPU0_RSVD_162         U5D1             BC14     SKX_EXT_B_BGA1-IC,TBD
TP_CPU0_RSVD_163         U5D1             BB67     SKX_EXT_B_BGA1-IC,TBD
TP_CPU0_RSVD_164         U5D1             BB65     SKX_EXT_B_BGA1-IC,TBD
TP_CPU0_RSVD_166         U5D1             BB21     SKX_EXT_B_BGA1-IC,TBD
TP_CPU0_RSVD_167         U5D1             BB17     SKX_EXT_B_BGA1-IC,TBD
TP_CPU0_RSVD_168         U5D1             BB15     SKX_EXT_B_BGA1-IC,TBD
TP_CPU0_RSVD_169         U5D1             BB13     SKX_EXT_B_BGA1-IC,TBD
TP_CPU0_RSVD_170         U5D1             BA82     SKX_EXT_B_BGA1-IC,TBD
TP_CPU0_RSVD_171         U5D1             BA78     SKX_EXT_B_BGA1-IC,TBD
TP_CPU0_RSVD_172         U5D1             BA76     SKX_EXT_B_BGA1-IC,TBD
TP_CPU0_RSVD_173         U5D1             BA66     SKX_EXT_B_BGA1-IC,TBD
TP_CPU0_RSVD_174         U5D1             BA64     SKX_EXT_B_BGA1-IC,TBD
TP_CPU0_RSVD_175         U5D1             BA22     SKX_EXT_B_BGA1-IC,TBD
TP_CPU0_RSVD_176         U5D1             BA18     SKX_EXT_B_BGA1-IC,TBD
TP_CPU0_RSVD_177         U5D1             BA16     SKX_EXT_B_BGA1-IC,TBD
TP_CPU0_RSVD_178         U5D1             BA14     SKX_EXT_B_BGA1-IC,TBD
TP_CPU0_RSVD_179         U5D1             AY77     SKX_EXT_B_BGA1-IC,TBD
TP_CPU0_RSVD_180         U5D1             AY75     SKX_EXT_B_BGA1-IC,TBD
TP_CPU0_RSVD_181         U5D1             AY67     SKX_EXT_B_BGA1-IC,TBD
TP_CPU0_RSVD_182         U5D1             AY65     SKX_EXT_B_BGA1-IC,TBD
TP_CPU0_RSVD_183         U5D1             AW76     SKX_EXT_B_BGA1-IC,TBD
TP_CPU0_RSVD_184         U5D1             AW64     SKX_EXT_B_BGA1-IC,TBD
TP_CPU0_RSVD_186         U5D1             AV77     SKX_EXT_B_BGA1-IC,TBD
TP_CPU0_RSVD_189         U5D1             AT13     SKX_EXT_B_BGA1-IC,TBD
TP_CPU0_RSVD_190         U5D1             AR62     SKX_EXT_B_BGA1-IC,TBD
TP_CPU0_RSVD_194         U5D1             AP61     SKX_EXT_B_BGA1-IC,TBD
TP_CPU0_RSVD_198         U5D1             AN62     SKX_EXT_B_BGA1-IC,TBD
TP_CPU0_RSVD_199         U5D1             AN60     SKX_EXT_B_BGA1-IC,TBD
TP_CPU0_RSVD_204         U5D1             AM61     SKX_EXT_B_BGA1-IC,TBD
TP_CPU0_RSVD_205         U5D1             AM59     SKX_EXT_B_BGA1-IC,TBD
TP_CPU0_RSVD_208         U5D1             AM23     SKX_EXT_B_BGA1-IC,TBD
TP_CPU0_RSVD_210         U5D1             AL62     SKX_EXT_B_BGA1-IC,TBD
TP_CPU0_RSVD_211         U5D1             AL60     SKX_EXT_B_BGA1-IC,TBD
TP_CPU0_RSVD_212         U5D1             AL58     SKX_EXT_B_BGA1-IC,TBD
TP_CPU0_RSVD_214         U5D1             AL22     SKX_EXT_B_BGA1-IC,TBD
TP_CPU0_RSVD_216         U5D1             AK69     SKX_EXT_B_BGA1-IC,TBD
TP_CPU0_RSVD_217         U5D1             AK61     SKX_EXT_B_BGA1-IC,TBD
TP_CPU0_RSVD_218         U5D1             AK59     SKX_EXT_B_BGA1-IC,TBD
TP_CPU0_RSVD_219         U5D1             AK57     SKX_EXT_B_BGA1-IC,TBD
TP_CPU0_RSVD_222         U5D1             AJ70     SKX_EXT_B_BGA1-IC,TBD
TP_CPU0_RSVD_223         U5D1             AJ62     SKX_EXT_B_BGA1-IC,TBD
TP_CPU0_RSVD_224         U5D1             AJ60     SKX_EXT_B_BGA1-IC,TBD
TP_CPU0_RSVD_225         U5D1             AJ58     SKX_EXT_B_BGA1-IC,TBD
TP_CPU0_RSVD_226         U5D1             AJ56     SKX_EXT_B_BGA1-IC,TBD
TP_CPU0_RSVD_227         U5D1             AJ20     SKX_EXT_B_BGA1-IC,TBD
TP_CPU0_RSVD_228         U5D1             AH73     SKX_EXT_B_BGA1-IC,TBD
TP_CPU0_RSVD_229         U5D1             AH71     SKX_EXT_B_BGA1-IC,TBD
TP_CPU0_RSVD_230         U5D1             AH57     SKX_EXT_B_BGA1-IC,TBD
TP_CPU0_RSVD_231         U5D1             AH55     SKX_EXT_B_BGA1-IC,TBD
TP_CPU0_RSVD_232         U5D1             AH19     SKX_EXT_B_BGA1-IC,TBD
TP_CPU0_RSVD_233         U5D1             AH15     SKX_EXT_B_BGA1-IC,TBD
TP_CPU0_RSVD_234         U5D1             AG72     SKX_EXT_B_BGA1-IC,TBD
TP_CPU0_RSVD_235         U5D1             AG56     SKX_EXT_B_BGA1-IC,TBD
TP_CPU0_RSVD_236         U5D1             AG54     SKX_EXT_B_BGA1-IC,TBD
TP_CPU0_RSVD_237         U5D1             AG52     SKX_EXT_B_BGA1-IC,TBD
TP_CPU0_RSVD_238         U5D1             AG50     SKX_EXT_B_BGA1-IC,TBD
TP_CPU0_RSVD_239         U5D1             AG48     SKX_EXT_B_BGA1-IC,TBD
TP_CPU0_RSVD_240         U5D1             AG20     SKX_EXT_B_BGA1-IC,TBD
TP_CPU0_RSVD_241         U5D1             AF71     SKX_EXT_B_BGA1-IC,TBD
TP_CPU0_RSVD_242         U5D1             AF53     SKX_EXT_B_BGA1-IC,TBD
TP_CPU0_RSVD_243         U5D1             AF51     SKX_EXT_B_BGA1-IC,TBD
TP_CPU0_RSVD_244         U5D1             AF49     SKX_EXT_B_BGA1-IC,TBD
TP_CPU0_RSVD_245         U5D1             AF47     SKX_EXT_B_BGA1-IC,TBD
TP_CPU0_RSVD_246         U5D1             AF19     SKX_EXT_B_BGA1-IC,TBD
TP_CPU0_RSVD_247         U5D1             AE72     SKX_EXT_B_BGA1-IC,TBD
TP_CPU0_RSVD_248         U5D1             AE52     SKX_EXT_B_BGA1-IC,TBD
TP_CPU0_RSVD_249         U5D1             AE50     SKX_EXT_B_BGA1-IC,TBD
TP_CPU0_RSVD_250         U5D1             AE48     SKX_EXT_B_BGA1-IC,TBD
TP_CPU0_RSVD_251         U5D1             AE46     SKX_EXT_B_BGA1-IC,TBD
TP_CPU0_RSVD_252         U5D1             AD51     SKX_EXT_B_BGA1-IC,TBD
TP_CPU0_RSVD_253         U5D1             AD49     SKX_EXT_B_BGA1-IC,TBD
TP_CPU0_RSVD_254         U5D1             AD47     SKX_EXT_B_BGA1-IC,TBD
TP_CPU0_RSVD_255         U5D1             AY83     SKX_EXT_B_BGA1-IC,TBD
TP_CPU0_RSVD_256         U5D1             Y65      SKX_EXT_B_BGA1-IC,TBD
TP_CPU0_RSVD_258         U5D1             W66      SKX_EXT_B_BGA1-IC,TBD
TP_CPU0_RSVD_259         U5D1             V67      SKX_EXT_B_BGA1-IC,TBD
TP_CPU0_RSVD_260         U5D1             V65      SKX_EXT_B_BGA1-IC,TBD
TP_CPU0_RSVD_261         U5D1             U66      SKX_EXT_B_BGA1-IC,TBD
TP_CPU0_RSVD_262         U5D1             T67      SKX_EXT_B_BGA1-IC,TBD
TP_CPU0_RSVD_263         U5D1             R66      SKX_EXT_B_BGA1-IC,TBD
TP_CPU0_RSVD_264         U5D1             R62      SKX_EXT_B_BGA1-IC,TBD
TP_CPU0_RSVD_265         U5D1             P65      SKX_EXT_B_BGA1-IC,TBD
TP_CPU0_RSVD_266         U5D1             M63      SKX_EXT_B_BGA1-IC,TBD
TP_CPU0_RSVD_267         U5D1             K61      SKX_EXT_B_BGA1-IC,TBD
TP_CPU0_RSVD_268         U5D1             J62      SKX_EXT_B_BGA1-IC,TBD
TP_CPU0_RSVD_269         U5D1             J46      SKX_EXT_B_BGA1-IC,TBD
TP_CPU0_RSVD_270         U5D1             H85      SKX_EXT_B_BGA1-IC,TBD
TP_CPU0_RSVD_271         U5D1             H83      SKX_EXT_B_BGA1-IC,TBD
TP_CPU0_RSVD_272         U5D1             H1       SKX_EXT_B_BGA1-IC,TBD
TP_CPU0_RSVD_273         U5D1             G84      SKX_EXT_B_BGA1-IC,TBD
TP_CPU0_RSVD_274         U5D1             G64      SKX_EXT_B_BGA1-IC,TBD
TP_CPU0_RSVD_275         U5D1             G2       SKX_EXT_B_BGA1-IC,TBD
TP_CPU0_RSVD_276         U5D1             F83      SKX_EXT_B_BGA1-IC,TBD
TP_CPU0_RSVD_277         U5D1             F65      SKX_EXT_B_BGA1-IC,TBD
TP_CPU0_RSVD_278         U5D1             F23      SKX_EXT_B_BGA1-IC,TBD
TP_CPU0_RSVD_279         U5D1             F3       SKX_EXT_B_BGA1-IC,TBD
TP_CPU0_RSVD_280         U5D1             E84      SKX_EXT_B_BGA1-IC,TBD
TP_CPU0_RSVD_281         U5D1             E24      SKX_EXT_B_BGA1-IC,TBD
TP_CPU0_RSVD_282         U5D1             E4       SKX_EXT_B_BGA1-IC,TBD
TP_CPU0_RSVD_283         U5D1             E2       SKX_EXT_B_BGA1-IC,TBD
TP_CPU0_RSVD_284         U5D1             D83      SKX_EXT_B_BGA1-IC,TBD
TP_CPU0_RSVD_285         U5D1             D65      SKX_EXT_B_BGA1-IC,TBD
TP_CPU0_RSVD_286         U5D1             D17      SKX_EXT_B_BGA1-IC,TBD
TP_CPU0_RSVD_287         U5D1             D5       SKX_EXT_B_BGA1-IC,TBD
TP_CPU0_RSVD_288         U5D1             C82      SKX_EXT_B_BGA1-IC,TBD
TP_CPU0_RSVD_289         U5D1             C24      SKX_EXT_B_BGA1-IC,TBD
TP_CPU0_RSVD_290         U5D1             C18      SKX_EXT_B_BGA1-IC,TBD
TP_CPU0_RSVD_291         U5D1             C6       SKX_EXT_B_BGA1-IC,TBD
TP_CPU0_RSVD_292         U5D1             B81      SKX_EXT_B_BGA1-IC,TBD
TP_CPU0_RSVD_293         U5D1             B77      SKX_EXT_B_BGA1-IC,TBD
TP_CPU0_RSVD_298         U5D1             B7       SKX_EXT_B_BGA1-IC,TBD
TP_CPU0_RSVD_299         U5D1             B3       SKX_EXT_B_BGA1-IC,TBD
TP_CPU0_RSVD_300         U5D1             A24      SKX_EXT_B_BGA1-IC,TBD
TP_CPU0_RSVD_303         U5D1             A6       SKX_EXT_B_BGA1-IC,TBD
TP_CPU0_RSVD_304         U5D1             A4       SKX_EXT_B_BGA1-IC,TBD
TP_CPU0_RSVD_TEST_3      U5D1             AM13     SKX_EXT_B_BGA1-IC,TBD
TP_CPU0_RSVD_TEST_4      U5D1             AN12     SKX_EXT_B_BGA1-IC,TBD
TP_CPU0_RSVD_TEST_5      U5D1             AN14     SKX_EXT_B_BGA1-IC,TBD
TP_CPU0_RSVD_TEST_11     U5D1             AY13     SKX_EXT_B_BGA1-IC,TBD
TP_CPU0_SOCKET_ID_2      U5D1             AU20     SKX_EXT_B_BGA1-IC,TBD
TP_CPU0_TEST_6           U5D1             AR16     SKX_EXT_B_BGA1-IC,TBD
TP_CPU0_TEST_7           U5D1             AU18     SKX_EXT_B_BGA1-IC,TBD
TP_CPU0_TEST_8           U5D1             AW16     SKX_EXT_B_BGA1-IC,TBD
TP_CPU0_TEST_9           U5D1             AW20     SKX_EXT_B_BGA1-IC,TBD
TP_CPU0_TEST_10          U5D1             AW22     SKX_EXT_B_BGA1-IC,TBD
TP_CPU0_UPI2_RSVD_CA12   U5D1             DP21     SKX_EXT_B_BGA1-IC,TBD
TP_CPU0_UPI2_RSVD_CB11   U5D1             DN20     SKX_EXT_B_BGA1-IC,TBD
TP_CPU0_UPI2_RSVD_CC10   U5D1             DM21     SKX_EXT_B_BGA1-IC,TBD
TP_CPU0_UPI2_RSVD_CC12   U5D1             DT21     SKX_EXT_B_BGA1-IC,TBD
TP_CPU0_UPI2_RSVD_CD11   U5D1             DK19     SKX_EXT_B_BGA1-IC,TBD
TP_CPU0_UPI2_RSVD_CE12   U5D1             DL20     SKX_EXT_B_BGA1-IC,TBD
TP_CPU0_UPI2_RSVD_CF11   U5D1             DJ20     SKX_EXT_B_BGA1-IC,TBD
TP_CPU0_UPI2_RSVD_CF13   U5D1             DH19     SKX_EXT_B_BGA1-IC,TBD
TP_CPU0_UPI2_RSVD_CG12   U5D1             DJ18     SKX_EXT_B_BGA1-IC,TBD
TP_CPU0_UPI2_RSVD_CH11   U5D1             DG20     SKX_EXT_B_BGA1-IC,TBD
TP_CPU0_UPI2_RSVD_CH13   U5D1             DH17     SKX_EXT_B_BGA1-IC,TBD
TP_CPU0_UPI2_RSVD_CJ14   U5D1             DK17     SKX_EXT_B_BGA1-IC,TBD
TP_CPU0_UPI2_RSVD_CK13   U5D1             DF17     SKX_EXT_B_BGA1-IC,TBD
TP_CPU0_UPI2_RSVD_CM13   U5D1             DG18     SKX_EXT_B_BGA1-IC,TBD
TP_CPU0_UPI2_RSVD_CR14   U5D1             DE16     SKX_EXT_B_BGA1-IC,TBD
TP_CPU0_UPI2_RSVD_CU14   U5D1             DD17     SKX_EXT_B_BGA1-IC,TBD
TP_CPU0_UPI2_RSVD_CV13   U5D1             DD15     SKX_EXT_B_BGA1-IC,TBD
TP_CPU0_UPI2_RSVD_CW14   U5D1             DF15     SKX_EXT_B_BGA1-IC,TBD
TP_CPU0_UPI2_RSVD_CW16   U5D1             DB15     SKX_EXT_B_BGA1-IC,TBD
TP_CPU0_UPI2_RSVD_DA16   U5D1             DC16     SKX_EXT_B_BGA1-IC,TBD
TP_CPU0_UPI2_RSVD_DB15   U5D1             CW16     SKX_EXT_B_BGA1-IC,TBD
TP_CPU0_UPI2_RSVD_DC16   U5D1             DA16     SKX_EXT_B_BGA1-IC,TBD
TP_CPU0_UPI2_RSVD_DD15   U5D1             CV13     SKX_EXT_B_BGA1-IC,TBD
TP_CPU0_UPI2_RSVD_DD17   U5D1             CU14     SKX_EXT_B_BGA1-IC,TBD
TP_CPU0_UPI2_RSVD_DE16   U5D1             CR14     SKX_EXT_B_BGA1-IC,TBD
TP_CPU0_UPI2_RSVD_DF15   U5D1             CW14     SKX_EXT_B_BGA1-IC,TBD
TP_CPU0_UPI2_RSVD_DF17   U5D1             CK13     SKX_EXT_B_BGA1-IC,TBD
TP_CPU0_UPI2_RSVD_DG18   U5D1             CM13     SKX_EXT_B_BGA1-IC,TBD
TP_CPU0_UPI2_RSVD_DG20   U5D1             CH11     SKX_EXT_B_BGA1-IC,TBD
TP_CPU0_UPI2_RSVD_DH17   U5D1             CH13     SKX_EXT_B_BGA1-IC,TBD
TP_CPU0_UPI2_RSVD_DH19   U5D1             CF13     SKX_EXT_B_BGA1-IC,TBD
TP_CPU0_UPI2_RSVD_DJ18   U5D1             CG12     SKX_EXT_B_BGA1-IC,TBD
TP_CPU0_UPI2_RSVD_DJ20   U5D1             CF11     SKX_EXT_B_BGA1-IC,TBD
TP_CPU0_UPI2_RSVD_DK17   U5D1             CJ14     SKX_EXT_B_BGA1-IC,TBD
TP_CPU0_UPI2_RSVD_DK19   U5D1             CD11     SKX_EXT_B_BGA1-IC,TBD
TP_CPU0_UPI2_RSVD_DL20   U5D1             CE12     SKX_EXT_B_BGA1-IC,TBD
TP_CPU0_UPI2_RSVD_DM21   U5D1             CC10     SKX_EXT_B_BGA1-IC,TBD
TP_CPU0_UPI2_RSVD_DN20   U5D1             CB11     SKX_EXT_B_BGA1-IC,TBD
TP_CPU0_UPI2_RSVD_DP21   U5D1             CA12     SKX_EXT_B_BGA1-IC,TBD
TP_CPU0_UPI2_RSVD_DT21   U5D1             CC12     SKX_EXT_B_BGA1-IC,TBD
TP_CPU1_DMI_RX_DN0       U2D1             CK9      SKX_EXT_B_BGA1-IC,TBD
TP_CPU1_DMI_RX_DN1       U2D1             CM11     SKX_EXT_B_BGA1-IC,TBD
TP_CPU1_DMI_RX_DN2       U2D1             CR12     SKX_EXT_B_BGA1-IC,TBD
TP_CPU1_DMI_RX_DN3       U2D1             CT11     SKX_EXT_B_BGA1-IC,TBD
TP_CPU1_DMI_RX_DP0       U2D1             CL10     SKX_EXT_B_BGA1-IC,TBD
TP_CPU1_DMI_RX_DP1       U2D1             CN10     SKX_EXT_B_BGA1-IC,TBD
TP_CPU1_DMI_RX_DP2       U2D1             CP11     SKX_EXT_B_BGA1-IC,TBD
TP_CPU1_DMI_RX_DP3       U2D1             CV11     SKX_EXT_B_BGA1-IC,TBD
TP_CPU1_DMI_TX_DN0       U2D1             CG4      SKX_EXT_B_BGA1-IC,TBD
TP_CPU1_DMI_TX_DN1       U2D1             CJ4      SKX_EXT_B_BGA1-IC,TBD
TP_CPU1_DMI_TX_DN2       U2D1             CN4      SKX_EXT_B_BGA1-IC,TBD
TP_CPU1_DMI_TX_DN3       U2D1             CP5      SKX_EXT_B_BGA1-IC,TBD
TP_CPU1_DMI_TX_DP0       U2D1             CH5      SKX_EXT_B_BGA1-IC,TBD
TP_CPU1_DMI_TX_DP1       U2D1             CL4      SKX_EXT_B_BGA1-IC,TBD
TP_CPU1_DMI_TX_DP2       U2D1             CM3      SKX_EXT_B_BGA1-IC,TBD
TP_CPU1_DMI_TX_DP3       U2D1             CR4      SKX_EXT_B_BGA1-IC,TBD
TP_CPU1_KTI2_AMONV       U2D1             CN22     SKX_EXT_B_BGA1-IC,TBD
TP_CPU1_KTI2_DFX_DN      U2D1             CW22     SKX_EXT_B_BGA1-IC,TBD
TP_CPU1_NMI              U2D1             AP11     SKX_EXT_B_BGA1-IC,TBD
TP_CPU1_PROC_DIS_G_N     U2D1             AB17     SKX_EXT_B_BGA1-IC,TBD
TP_CPU1_RSVD_0           U2D1             EF83     SKX_EXT_B_BGA1-IC,TBD
TP_CPU1_RSVD_1           U2D1             EF81     SKX_EXT_B_BGA1-IC,TBD
TP_CPU1_RSVD_2           U2D1             EF77     SKX_EXT_B_BGA1-IC,TBD
TP_CPU1_RSVD_3           U2D1             EF47     SKX_EXT_B_BGA1-IC,TBD
TP_CPU1_RSVD_4           U2D1             EE84     SKX_EXT_B_BGA1-IC,TBD
TP_CPU1_RSVD_5           U2D1             EE82     SKX_EXT_B_BGA1-IC,TBD
TP_CPU1_RSVD_6           U2D1             EE6      SKX_EXT_B_BGA1-IC,TBD
TP_CPU1_RSVD_7           U2D1             EE46     SKX_EXT_B_BGA1-IC,TBD
TP_CPU1_RSVD_8           U2D1             EE16     SKX_EXT_B_BGA1-IC,TBD
TP_CPU1_RSVD_9           U2D1             ED83     SKX_EXT_B_BGA1-IC,TBD
TP_CPU1_RSVD_10          U2D1             ED5      SKX_EXT_B_BGA1-IC,TBD
TP_CPU1_RSVD_11          U2D1             ED45     SKX_EXT_B_BGA1-IC,TBD
TP_CPU1_RSVD_12          U2D1             EC84     SKX_EXT_B_BGA1-IC,TBD
TP_CPU1_RSVD_13          U2D1             EC44     SKX_EXT_B_BGA1-IC,TBD
TP_CPU1_RSVD_14          U2D1             EC4      SKX_EXT_B_BGA1-IC,TBD
TP_CPU1_RSVD_15          U2D1             EC16     SKX_EXT_B_BGA1-IC,TBD
TP_CPU1_RSVD_16          U2D1             EB85     SKX_EXT_B_BGA1-IC,TBD
TP_CPU1_RSVD_17          U2D1             EB5      SKX_EXT_B_BGA1-IC,TBD
TP_CPU1_RSVD_18          U2D1             EB3      SKX_EXT_B_BGA1-IC,TBD
TP_CPU1_RSVD_19          U2D1             EA44     SKX_EXT_B_BGA1-IC,TBD
TP_CPU1_RSVD_20          U2D1             EA4      SKX_EXT_B_BGA1-IC,TBD
TP_CPU1_RSVD_21          U2D1             DY3      SKX_EXT_B_BGA1-IC,TBD
TP_CPU1_RSVD_22          U2D1             DW46     SKX_EXT_B_BGA1-IC,TBD
TP_CPU1_RSVD_23          U2D1             DW44     SKX_EXT_B_BGA1-IC,TBD
TP_CPU1_RSVD_24          U2D1             DV71     SKX_EXT_B_BGA1-IC,TBD
TP_CPU1_RSVD_25          U2D1             DV61     SKX_EXT_B_BGA1-IC,TBD
TP_CPU1_RSVD_26          U2D1             DU44     SKX_EXT_B_BGA1-IC,TBD
TP_CPU1_RSVD_27          U2D1             DT71     SKX_EXT_B_BGA1-IC,TBD
TP_CPU1_RSVD_28          U2D1             DR44     SKX_EXT_B_BGA1-IC,TBD
TP_CPU1_RSVD_29          U2D1             DP65     SKX_EXT_B_BGA1-IC,TBD
TP_CPU1_RSVD_30          U2D1             DP17     SKX_EXT_B_BGA1-IC,TBD
TP_CPU1_RSVD_31          U2D1             DN66     SKX_EXT_B_BGA1-IC,TBD
TP_CPU1_RSVD_32          U2D1             DN62     SKX_EXT_B_BGA1-IC,TBD
TP_CPU1_RSVD_33          U2D1             DM67     SKX_EXT_B_BGA1-IC,TBD
TP_CPU1_RSVD_34          U2D1             DL66     SKX_EXT_B_BGA1-IC,TBD
TP_CPU1_RSVD_35          U2D1             DL38     SKX_EXT_B_BGA1-IC,TBD
TP_CPU1_RSVD_36          U2D1             DK67     SKX_EXT_B_BGA1-IC,TBD
TP_CPU1_RSVD_37          U2D1             DK65     SKX_EXT_B_BGA1-IC,TBD
TP_CPU1_RSVD_38          U2D1             DK37     SKX_EXT_B_BGA1-IC,TBD
TP_CPU1_RSVD_39          U2D1             DK15     SKX_EXT_B_BGA1-IC,TBD
TP_CPU1_RSVD_40          U2D1             DJ66     SKX_EXT_B_BGA1-IC,TBD
TP_CPU1_RSVD_41          U2D1             DJ36     SKX_EXT_B_BGA1-IC,TBD
TP_CPU1_RSVD_42          U2D1             DH65     SKX_EXT_B_BGA1-IC,TBD
TP_CPU1_RSVD_43          U2D1             DG64     SKX_EXT_B_BGA1-IC,TBD
TP_CPU1_RSVD_44          U2D1             DG36     SKX_EXT_B_BGA1-IC,TBD
TP_CPU1_RSVD_45          U2D1             DD51     SKX_EXT_B_BGA1-IC,TBD
TP_CPU1_RSVD_46          U2D1             DC52     SKX_EXT_B_BGA1-IC,TBD
TP_CPU1_RSVD_47          U2D1             DC46     SKX_EXT_B_BGA1-IC,TBD
TP_CPU1_RSVD_48          U2D1             DA56     SKX_EXT_B_BGA1-IC,TBD
TP_CPU1_RSVD_49          U2D1             DA54     SKX_EXT_B_BGA1-IC,TBD
TP_CPU1_RSVD_50          U2D1             DA52     SKX_EXT_B_BGA1-IC,TBD
TP_CPU1_RSVD_51          U2D1             DA40     SKX_EXT_B_BGA1-IC,TBD
TP_CPU1_RSVD_53          U2D1             CY73     SKX_EXT_B_BGA1-IC,TBD
TP_CPU1_RSVD_54          U2D1             CY63     SKX_EXT_B_BGA1-IC,TBD
TP_CPU1_RSVD_55          U2D1             CY57     SKX_EXT_B_BGA1-IC,TBD
TP_CPU1_RSVD_56          U2D1             CY53     SKX_EXT_B_BGA1-IC,TBD
TP_CPU1_RSVD_57          U2D1             CY39     SKX_EXT_B_BGA1-IC,TBD
TP_CPU1_RSVD_59          U2D1             CY23     SKX_EXT_B_BGA1-IC,TBD
TP_CPU1_RSVD_60          U2D1             CW62     SKX_EXT_B_BGA1-IC,TBD
TP_CPU1_RSVD_61          U2D1             CW60     SKX_EXT_B_BGA1-IC,TBD
TP_CPU1_RSVD_64          U2D1             CV69     SKX_EXT_B_BGA1-IC,TBD
TP_CPU1_RSVD_66          U2D1             CU60     SKX_EXT_B_BGA1-IC,TBD
TP_CPU1_RSVD_67          U2D1             CU6      SKX_EXT_B_BGA1-IC,TBD
TP_CPU1_RSVD_69          U2D1             CT69     SKX_EXT_B_BGA1-IC,TBD
TP_CPU1_RSVD_70          U2D1             CT5      SKX_EXT_B_BGA1-IC,TBD
TP_CPU1_RSVD_72          U2D1             CR60     SKX_EXT_B_BGA1-IC,TBD
TP_CPU1_RSVD_73          U2D1             CP31     SKX_EXT_B_BGA1-IC,TBD
TP_CPU1_RSVD_82          U2D1             CK77     SKX_EXT_B_BGA1-IC,TBD
TP_CPU1_RSVD_85          U2D1             CK19     SKX_EXT_B_BGA1-IC,TBD
TP_CPU1_RSVD_90          U2D1             CH77     SKX_EXT_B_BGA1-IC,TBD
TP_CPU1_RSVD_91          U2D1             CH25     SKX_EXT_B_BGA1-IC,TBD
TP_CPU1_RSVD_94          U2D1             CG82     SKX_EXT_B_BGA1-IC,TBD
TP_CPU1_RSVD_95          U2D1             CG78     SKX_EXT_B_BGA1-IC,TBD
TP_CPU1_RSVD_97          U2D1             CG24     SKX_EXT_B_BGA1-IC,TBD
TP_CPU1_RSVD_99          U2D1             CG10     SKX_EXT_B_BGA1-IC,TBD
TP_CPU1_RSVD_100         U2D1             CF81     SKX_EXT_B_BGA1-IC,TBD
TP_CPU1_RSVD_101         U2D1             CF79     SKX_EXT_B_BGA1-IC,TBD
TP_CPU1_RSVD_105         U2D1             CE80     SKX_EXT_B_BGA1-IC,TBD
TP_CPU1_RSVD_106         U2D1             CE78     SKX_EXT_B_BGA1-IC,TBD
TP_CPU1_RSVD_108         U2D1             CD25     SKX_EXT_B_BGA1-IC,TBD
TP_CPU1_RSVD_111         U2D1             CC6      SKX_EXT_B_BGA1-IC,TBD
TP_CPU1_RSVD_113         U2D1             CB5      SKX_EXT_B_BGA1-IC,TBD
TP_CPU1_RSVD_114         U2D1             CB25     SKX_EXT_B_BGA1-IC,TBD
TP_CPU1_RSVD_117         U2D1             CA24     SKX_EXT_B_BGA1-IC,TBD
TP_CPU1_RSVD_119         U2D1             BY25     SKX_EXT_B_BGA1-IC,TBD
TP_CPU1_RSVD_121         U2D1             BW22     SKX_EXT_B_BGA1-IC,TBD
TP_CPU1_RSVD_123         U2D1             BW10     SKX_EXT_B_BGA1-IC,TBD
TP_CPU1_RSVD_124         U2D1             BV23     SKX_EXT_B_BGA1-IC,TBD
TP_CPU1_RSVD_144         U2D1             BG20     SKX_EXT_B_BGA1-IC,TBD
TP_CPU1_RSVD_145         U2D1             BG18     SKX_EXT_B_BGA1-IC,TBD
TP_CPU1_RSVD_146         U2D1             BF21     SKX_EXT_B_BGA1-IC,TBD
TP_CPU1_RSVD_147         U2D1             BE22     SKX_EXT_B_BGA1-IC,TBD
TP_CPU1_RSVD_148         U2D1             BE20     SKX_EXT_B_BGA1-IC,TBD
TP_CPU1_RSVD_149         U2D1             BE18     SKX_EXT_B_BGA1-IC,TBD
TP_CPU1_RSVD_150         U2D1             BD69     SKX_EXT_B_BGA1-IC,TBD
TP_CPU1_RSVD_151         U2D1             BD67     SKX_EXT_B_BGA1-IC,TBD
TP_CPU1_RSVD_152         U2D1             BD65     SKX_EXT_B_BGA1-IC,TBD
TP_CPU1_RSVD_154         U2D1             BD19     SKX_EXT_B_BGA1-IC,TBD
TP_CPU1_RSVD_155         U2D1             BD17     SKX_EXT_B_BGA1-IC,TBD
TP_CPU1_RSVD_156         U2D1             BC68     SKX_EXT_B_BGA1-IC,TBD
TP_CPU1_RSVD_157         U2D1             BC66     SKX_EXT_B_BGA1-IC,TBD
TP_CPU1_RSVD_158         U2D1             BC64     SKX_EXT_B_BGA1-IC,TBD
TP_CPU1_RSVD_159         U2D1             BC22     SKX_EXT_B_BGA1-IC,TBD
TP_CPU1_RSVD_160         U2D1             BC20     SKX_EXT_B_BGA1-IC,TBD
TP_CPU1_RSVD_161         U2D1             BC18     SKX_EXT_B_BGA1-IC,TBD
TP_CPU1_RSVD_162         U2D1             BC14     SKX_EXT_B_BGA1-IC,TBD
TP_CPU1_RSVD_163         U2D1             BB67     SKX_EXT_B_BGA1-IC,TBD
TP_CPU1_RSVD_164         U2D1             BB65     SKX_EXT_B_BGA1-IC,TBD
TP_CPU1_RSVD_166         U2D1             BB21     SKX_EXT_B_BGA1-IC,TBD
TP_CPU1_RSVD_167         U2D1             BB17     SKX_EXT_B_BGA1-IC,TBD
TP_CPU1_RSVD_168         U2D1             BB15     SKX_EXT_B_BGA1-IC,TBD
TP_CPU1_RSVD_169         U2D1             BB13     SKX_EXT_B_BGA1-IC,TBD
TP_CPU1_RSVD_170         U2D1             BA82     SKX_EXT_B_BGA1-IC,TBD
TP_CPU1_RSVD_171         U2D1             BA78     SKX_EXT_B_BGA1-IC,TBD
TP_CPU1_RSVD_172         U2D1             BA76     SKX_EXT_B_BGA1-IC,TBD
TP_CPU1_RSVD_173         U2D1             BA66     SKX_EXT_B_BGA1-IC,TBD
TP_CPU1_RSVD_174         U2D1             BA64     SKX_EXT_B_BGA1-IC,TBD
TP_CPU1_RSVD_175         U2D1             BA22     SKX_EXT_B_BGA1-IC,TBD
TP_CPU1_RSVD_176         U2D1             BA18     SKX_EXT_B_BGA1-IC,TBD
TP_CPU1_RSVD_177         U2D1             BA16     SKX_EXT_B_BGA1-IC,TBD
TP_CPU1_RSVD_178         U2D1             BA14     SKX_EXT_B_BGA1-IC,TBD
TP_CPU1_RSVD_179         U2D1             AY77     SKX_EXT_B_BGA1-IC,TBD
TP_CPU1_RSVD_180         U2D1             AY75     SKX_EXT_B_BGA1-IC,TBD
TP_CPU1_RSVD_181         U2D1             AY67     SKX_EXT_B_BGA1-IC,TBD
TP_CPU1_RSVD_182         U2D1             AY65     SKX_EXT_B_BGA1-IC,TBD
TP_CPU1_RSVD_183         U2D1             AW76     SKX_EXT_B_BGA1-IC,TBD
TP_CPU1_RSVD_184         U2D1             AW64     SKX_EXT_B_BGA1-IC,TBD
TP_CPU1_RSVD_186         U2D1             AV77     SKX_EXT_B_BGA1-IC,TBD
TP_CPU1_RSVD_189         U2D1             AT13     SKX_EXT_B_BGA1-IC,TBD
TP_CPU1_RSVD_190         U2D1             AR62     SKX_EXT_B_BGA1-IC,TBD
TP_CPU1_RSVD_194         U2D1             AP61     SKX_EXT_B_BGA1-IC,TBD
TP_CPU1_RSVD_198         U2D1             AN62     SKX_EXT_B_BGA1-IC,TBD
TP_CPU1_RSVD_199         U2D1             AN60     SKX_EXT_B_BGA1-IC,TBD
TP_CPU1_RSVD_204         U2D1             AM61     SKX_EXT_B_BGA1-IC,TBD
TP_CPU1_RSVD_205         U2D1             AM59     SKX_EXT_B_BGA1-IC,TBD
TP_CPU1_RSVD_208         U2D1             AM23     SKX_EXT_B_BGA1-IC,TBD
TP_CPU1_RSVD_210         U2D1             AL62     SKX_EXT_B_BGA1-IC,TBD
TP_CPU1_RSVD_211         U2D1             AL60     SKX_EXT_B_BGA1-IC,TBD
TP_CPU1_RSVD_212         U2D1             AL58     SKX_EXT_B_BGA1-IC,TBD
TP_CPU1_RSVD_214         U2D1             AL22     SKX_EXT_B_BGA1-IC,TBD
TP_CPU1_RSVD_216         U2D1             AK69     SKX_EXT_B_BGA1-IC,TBD
TP_CPU1_RSVD_217         U2D1             AK61     SKX_EXT_B_BGA1-IC,TBD
TP_CPU1_RSVD_218         U2D1             AK59     SKX_EXT_B_BGA1-IC,TBD
TP_CPU1_RSVD_219         U2D1             AK57     SKX_EXT_B_BGA1-IC,TBD
TP_CPU1_RSVD_222         U2D1             AJ70     SKX_EXT_B_BGA1-IC,TBD
TP_CPU1_RSVD_223         U2D1             AJ62     SKX_EXT_B_BGA1-IC,TBD
TP_CPU1_RSVD_224         U2D1             AJ60     SKX_EXT_B_BGA1-IC,TBD
TP_CPU1_RSVD_225         U2D1             AJ58     SKX_EXT_B_BGA1-IC,TBD
TP_CPU1_RSVD_226         U2D1             AJ56     SKX_EXT_B_BGA1-IC,TBD
TP_CPU1_RSVD_227         U2D1             AJ20     SKX_EXT_B_BGA1-IC,TBD
TP_CPU1_RSVD_228         U2D1             AH73     SKX_EXT_B_BGA1-IC,TBD
TP_CPU1_RSVD_229         U2D1             AH71     SKX_EXT_B_BGA1-IC,TBD
TP_CPU1_RSVD_230         U2D1             AH57     SKX_EXT_B_BGA1-IC,TBD
TP_CPU1_RSVD_231         U2D1             AH55     SKX_EXT_B_BGA1-IC,TBD
TP_CPU1_RSVD_232         U2D1             AH19     SKX_EXT_B_BGA1-IC,TBD
TP_CPU1_RSVD_233         U2D1             AH15     SKX_EXT_B_BGA1-IC,TBD
TP_CPU1_RSVD_234         U2D1             AG72     SKX_EXT_B_BGA1-IC,TBD
TP_CPU1_RSVD_235         U2D1             AG56     SKX_EXT_B_BGA1-IC,TBD
TP_CPU1_RSVD_236         U2D1             AG54     SKX_EXT_B_BGA1-IC,TBD
TP_CPU1_RSVD_237         U2D1             AG52     SKX_EXT_B_BGA1-IC,TBD
TP_CPU1_RSVD_238         U2D1             AG50     SKX_EXT_B_BGA1-IC,TBD
TP_CPU1_RSVD_239         U2D1             AG48     SKX_EXT_B_BGA1-IC,TBD
TP_CPU1_RSVD_240         U2D1             AG20     SKX_EXT_B_BGA1-IC,TBD
TP_CPU1_RSVD_241         U2D1             AF71     SKX_EXT_B_BGA1-IC,TBD
TP_CPU1_RSVD_242         U2D1             AF53     SKX_EXT_B_BGA1-IC,TBD
TP_CPU1_RSVD_243         U2D1             AF51     SKX_EXT_B_BGA1-IC,TBD
TP_CPU1_RSVD_244         U2D1             AF49     SKX_EXT_B_BGA1-IC,TBD
TP_CPU1_RSVD_245         U2D1             AF47     SKX_EXT_B_BGA1-IC,TBD
TP_CPU1_RSVD_246         U2D1             AF19     SKX_EXT_B_BGA1-IC,TBD
TP_CPU1_RSVD_247         U2D1             AE72     SKX_EXT_B_BGA1-IC,TBD
TP_CPU1_RSVD_248         U2D1             AE52     SKX_EXT_B_BGA1-IC,TBD
TP_CPU1_RSVD_249         U2D1             AE50     SKX_EXT_B_BGA1-IC,TBD
TP_CPU1_RSVD_250         U2D1             AE48     SKX_EXT_B_BGA1-IC,TBD
TP_CPU1_RSVD_251         U2D1             AE46     SKX_EXT_B_BGA1-IC,TBD
TP_CPU1_RSVD_252         U2D1             AD51     SKX_EXT_B_BGA1-IC,TBD
TP_CPU1_RSVD_253         U2D1             AD49     SKX_EXT_B_BGA1-IC,TBD
TP_CPU1_RSVD_254         U2D1             AD47     SKX_EXT_B_BGA1-IC,TBD
TP_CPU1_RSVD_255         U2D1             AY83     SKX_EXT_B_BGA1-IC,TBD
TP_CPU1_RSVD_256         U2D1             Y65      SKX_EXT_B_BGA1-IC,TBD
TP_CPU1_RSVD_258         U2D1             W66      SKX_EXT_B_BGA1-IC,TBD
TP_CPU1_RSVD_259         U2D1             V67      SKX_EXT_B_BGA1-IC,TBD
TP_CPU1_RSVD_260         U2D1             V65      SKX_EXT_B_BGA1-IC,TBD
TP_CPU1_RSVD_261         U2D1             U66      SKX_EXT_B_BGA1-IC,TBD
TP_CPU1_RSVD_262         U2D1             T67      SKX_EXT_B_BGA1-IC,TBD
TP_CPU1_RSVD_263         U2D1             R66      SKX_EXT_B_BGA1-IC,TBD
TP_CPU1_RSVD_264         U2D1             R62      SKX_EXT_B_BGA1-IC,TBD
TP_CPU1_RSVD_265         U2D1             P65      SKX_EXT_B_BGA1-IC,TBD
TP_CPU1_RSVD_266         U2D1             M63      SKX_EXT_B_BGA1-IC,TBD
TP_CPU1_RSVD_267         U2D1             K61      SKX_EXT_B_BGA1-IC,TBD
TP_CPU1_RSVD_268         U2D1             J62      SKX_EXT_B_BGA1-IC,TBD
TP_CPU1_RSVD_269         U2D1             J46      SKX_EXT_B_BGA1-IC,TBD
TP_CPU1_RSVD_270         U2D1             H85      SKX_EXT_B_BGA1-IC,TBD
TP_CPU1_RSVD_271         U2D1             H83      SKX_EXT_B_BGA1-IC,TBD
TP_CPU1_RSVD_272         U2D1             H1       SKX_EXT_B_BGA1-IC,TBD
TP_CPU1_RSVD_273         U2D1             G84      SKX_EXT_B_BGA1-IC,TBD
TP_CPU1_RSVD_274         U2D1             G64      SKX_EXT_B_BGA1-IC,TBD
TP_CPU1_RSVD_275         U2D1             G2       SKX_EXT_B_BGA1-IC,TBD
TP_CPU1_RSVD_276         U2D1             F83      SKX_EXT_B_BGA1-IC,TBD
TP_CPU1_RSVD_277         U2D1             F65      SKX_EXT_B_BGA1-IC,TBD
TP_CPU1_RSVD_278         U2D1             F23      SKX_EXT_B_BGA1-IC,TBD
TP_CPU1_RSVD_279         U2D1             F3       SKX_EXT_B_BGA1-IC,TBD
TP_CPU1_RSVD_280         U2D1             E84      SKX_EXT_B_BGA1-IC,TBD
TP_CPU1_RSVD_281         U2D1             E24      SKX_EXT_B_BGA1-IC,TBD
TP_CPU1_RSVD_282         U2D1             E4       SKX_EXT_B_BGA1-IC,TBD
TP_CPU1_RSVD_283         U2D1             E2       SKX_EXT_B_BGA1-IC,TBD
TP_CPU1_RSVD_284         U2D1             D83      SKX_EXT_B_BGA1-IC,TBD
TP_CPU1_RSVD_285         U2D1             D65      SKX_EXT_B_BGA1-IC,TBD
TP_CPU1_RSVD_286         U2D1             D17      SKX_EXT_B_BGA1-IC,TBD
TP_CPU1_RSVD_287         U2D1             D5       SKX_EXT_B_BGA1-IC,TBD
TP_CPU1_RSVD_288         U2D1             C82      SKX_EXT_B_BGA1-IC,TBD
TP_CPU1_RSVD_289         U2D1             C24      SKX_EXT_B_BGA1-IC,TBD
TP_CPU1_RSVD_290         U2D1             C18      SKX_EXT_B_BGA1-IC,TBD
TP_CPU1_RSVD_291         U2D1             C6       SKX_EXT_B_BGA1-IC,TBD
TP_CPU1_RSVD_292         U2D1             B81      SKX_EXT_B_BGA1-IC,TBD
TP_CPU1_RSVD_293         U2D1             B77      SKX_EXT_B_BGA1-IC,TBD
TP_CPU1_RSVD_298         U2D1             B7       SKX_EXT_B_BGA1-IC,TBD
TP_CPU1_RSVD_299         U2D1             B3       SKX_EXT_B_BGA1-IC,TBD
TP_CPU1_RSVD_300         U2D1             A24      SKX_EXT_B_BGA1-IC,TBD
TP_CPU1_RSVD_303         U2D1             A6       SKX_EXT_B_BGA1-IC,TBD
TP_CPU1_RSVD_304         U2D1             A4       SKX_EXT_B_BGA1-IC,TBD
TP_CPU1_RSVD_TEST_3      U2D1             AM13     SKX_EXT_B_BGA1-IC,TBD
TP_CPU1_RSVD_TEST_4      U2D1             AN12     SKX_EXT_B_BGA1-IC,TBD
TP_CPU1_RSVD_TEST_5      U2D1             AN14     SKX_EXT_B_BGA1-IC,TBD
TP_CPU1_RSVD_TEST_11     U2D1             AY13     SKX_EXT_B_BGA1-IC,TBD
TP_CPU1_SOCKET_ID_2      U2D1             AU20     SKX_EXT_B_BGA1-IC,TBD
TP_CPU1_TEST_6           U2D1             AR16     SKX_EXT_B_BGA1-IC,TBD
TP_CPU1_TEST_7           U2D1             AU18     SKX_EXT_B_BGA1-IC,TBD
TP_CPU1_TEST_8           U2D1             AW16     SKX_EXT_B_BGA1-IC,TBD
TP_CPU1_TEST_9           U2D1             AW20     SKX_EXT_B_BGA1-IC,TBD
TP_CPU1_TEST_10          U2D1             AW22     SKX_EXT_B_BGA1-IC,TBD
TP_CPU1_UPI2_RSVD_CA12   U2D1             DP21     SKX_EXT_B_BGA1-IC,TBD
TP_CPU1_UPI2_RSVD_CB11   U2D1             DN20     SKX_EXT_B_BGA1-IC,TBD
TP_CPU1_UPI2_RSVD_CC10   U2D1             DM21     SKX_EXT_B_BGA1-IC,TBD
TP_CPU1_UPI2_RSVD_CC12   U2D1             DT21     SKX_EXT_B_BGA1-IC,TBD
TP_CPU1_UPI2_RSVD_CD11   U2D1             DK19     SKX_EXT_B_BGA1-IC,TBD
TP_CPU1_UPI2_RSVD_CE12   U2D1             DL20     SKX_EXT_B_BGA1-IC,TBD
TP_CPU1_UPI2_RSVD_CF11   U2D1             DJ20     SKX_EXT_B_BGA1-IC,TBD
TP_CPU1_UPI2_RSVD_CF13   U2D1             DH19     SKX_EXT_B_BGA1-IC,TBD
TP_CPU1_UPI2_RSVD_CG12   U2D1             DJ18     SKX_EXT_B_BGA1-IC,TBD
TP_CPU1_UPI2_RSVD_CH11   U2D1             DG20     SKX_EXT_B_BGA1-IC,TBD
TP_CPU1_UPI2_RSVD_CH13   U2D1             DH17     SKX_EXT_B_BGA1-IC,TBD
TP_CPU1_UPI2_RSVD_CJ14   U2D1             DK17     SKX_EXT_B_BGA1-IC,TBD
TP_CPU1_UPI2_RSVD_CK13   U2D1             DF17     SKX_EXT_B_BGA1-IC,TBD
TP_CPU1_UPI2_RSVD_CM13   U2D1             DG18     SKX_EXT_B_BGA1-IC,TBD
TP_CPU1_UPI2_RSVD_CR14   U2D1             DE16     SKX_EXT_B_BGA1-IC,TBD
TP_CPU1_UPI2_RSVD_CU14   U2D1             DD17     SKX_EXT_B_BGA1-IC,TBD
TP_CPU1_UPI2_RSVD_CV13   U2D1             DD15     SKX_EXT_B_BGA1-IC,TBD
TP_CPU1_UPI2_RSVD_CW14   U2D1             DF15     SKX_EXT_B_BGA1-IC,TBD
TP_CPU1_UPI2_RSVD_CW16   U2D1             DB15     SKX_EXT_B_BGA1-IC,TBD
TP_CPU1_UPI2_RSVD_DA16   U2D1             DC16     SKX_EXT_B_BGA1-IC,TBD
TP_CPU1_UPI2_RSVD_DB15   U2D1             CW16     SKX_EXT_B_BGA1-IC,TBD
TP_CPU1_UPI2_RSVD_DC16   U2D1             DA16     SKX_EXT_B_BGA1-IC,TBD
TP_CPU1_UPI2_RSVD_DD15   U2D1             CV13     SKX_EXT_B_BGA1-IC,TBD
TP_CPU1_UPI2_RSVD_DD17   U2D1             CU14     SKX_EXT_B_BGA1-IC,TBD
TP_CPU1_UPI2_RSVD_DE16   U2D1             CR14     SKX_EXT_B_BGA1-IC,TBD
TP_CPU1_UPI2_RSVD_DF15   U2D1             CW14     SKX_EXT_B_BGA1-IC,TBD
TP_CPU1_UPI2_RSVD_DF17   U2D1             CK13     SKX_EXT_B_BGA1-IC,TBD
TP_CPU1_UPI2_RSVD_DG18   U2D1             CM13     SKX_EXT_B_BGA1-IC,TBD
TP_CPU1_UPI2_RSVD_DG20   U2D1             CH11     SKX_EXT_B_BGA1-IC,TBD
TP_CPU1_UPI2_RSVD_DH17   U2D1             CH13     SKX_EXT_B_BGA1-IC,TBD
TP_CPU1_UPI2_RSVD_DH19   U2D1             CF13     SKX_EXT_B_BGA1-IC,TBD
TP_CPU1_UPI2_RSVD_DJ18   U2D1             CG12     SKX_EXT_B_BGA1-IC,TBD
TP_CPU1_UPI2_RSVD_DJ20   U2D1             CF11     SKX_EXT_B_BGA1-IC,TBD
TP_CPU1_UPI2_RSVD_DK17   U2D1             CJ14     SKX_EXT_B_BGA1-IC,TBD
TP_CPU1_UPI2_RSVD_DK19   U2D1             CD11     SKX_EXT_B_BGA1-IC,TBD
TP_CPU1_UPI2_RSVD_DL20   U2D1             CE12     SKX_EXT_B_BGA1-IC,TBD
TP_CPU1_UPI2_RSVD_DM21   U2D1             CC10     SKX_EXT_B_BGA1-IC,TBD
TP_CPU1_UPI2_RSVD_DN20   U2D1             CB11     SKX_EXT_B_BGA1-IC,TBD
TP_CPU1_UPI2_RSVD_DP21   U2D1             CA12     SKX_EXT_B_BGA1-IC,TBD
TP_CPU1_UPI2_RSVD_DT21   U2D1             CC12     SKX_EXT_B_BGA1-IC,TBD
TP_CPU_PCH_TRIGGER_IN    U7C1             M7       LBG_CORE_QAT_EXT_D_BGA1-IC,H91A
TP_CPU_PCH_TRIGGER_OUT   U7C1             R13      LBG_CORE_QAT_EXT_D_BGA1-IC,H91A
TP_DACB                  U9F4             R4       AST1250_BGA-IC,G85138-002
TP_DACG                  U9F4             R3       AST1250_BGA-IC,G85138-002
TP_DACR                  U9F4             R2       AST1250_BGA-IC,G85138-002
TP_DDCCLK_GPIOJ6         U9F4             T2       AST1250_BGA-IC,G85138-002
TP_DDCDAT_GPIOJ7         U9F4             T1       AST1250_BGA-IC,G85138-002
TP_EXT_MDIO_I2C_SEL      J8E4             3        SCONN64_H87568002_A_SMT-CONN,HA
TP_FAN_0                 J1F2             6        CONN6_C74770005_PIP-HDR,C74770A
TP_FAN_1                 J1B2             6        CONN6_C74770005_PIP-HDR,C74770A
TP_FET_Q56_3             Q1L4             3        FET_N_DUAL_SMLF-2N7002DW,FET,DA
TP_FET_Q56_4             Q1L4             4        FET_N_DUAL_SMLF-2N7002DW,FET,DA
TP_FET_Q56_4             Q1L4             5        FET_N_DUAL_SMLF-2N7002DW,FET,DA
TP_FM_CPU1_CD_HFI0_MODPRST_N U2D1             BR20     SKX_EXT_B_BGA1-IC,TBD
TP_FM_QAT_CBL_PRSNT0_R_N J8A1             1A1      CONN72_G97614002_A_CP-CONN,G97A
TP_FM_QAT_CBL_PRSNT1_N_R J8A1             2A1      CONN72_G97614002_A_CP-CONN,G97A
TP_FM_QAT_CBL_PRSNT2_N   J8A2             A1       CONN36_G97614001_CP-CONN,G9761A
TP_FM_WAKE_N             J1C1             B4       CONN76_H22707001_THMT1-CONN,H2A
TP_GPIO0_DSRB_N          EU9F3            13       PI7C9X1172_QFN-IC,H66899-001
TP_GPIO1_DTRB_N          EU9F3            23       PI7C9X1172_QFN-IC,H66899-001
TP_GPIO2_CDB_N           EU9F3            11       PI7C9X1172_QFN-IC,H66899-001
TP_GPIO3_RIB_N           EU9F3            14       PI7C9X1172_QFN-IC,H66899-001
TP_GPIO4_DSRA_N          EU9F3            26       PI7C9X1172_QFN-IC,H66899-001
TP_GPIO5_DTRA_N          EU9F3            22       PI7C9X1172_QFN-IC,H66899-001
TP_GPIO6_CDA_N           EU9F3            27       PI7C9X1172_QFN-IC,H66899-001
TP_GPIO7_RIA_N           EU9F3            28       PI7C9X1172_QFN-IC,H66899-001
TP_GPIOE7_RXD3           U9F4             B14      AST1250_BGA-IC,G85138-002
TP_GPIOM5_NRTS2_VPIB7    U9F4             Y2       AST1250_BGA-IC,G85138-002
TP_GPIOR5_ROMA25_VPOR7   U9F4             W22      AST1250_BGA-IC,G85138-002
TP_HFI_IO_CONN0_RSVD_17  J8B1             17       SCONN24_H46321001_SM-SCONN,H46A
TP_HSC_ALERT2_N          EU1D2            14       ADM1278_SM-IC,G99251-001
TP_HSC_MCLK              EU1D2            10       ADM1278_SM-IC,G99251-001
TP_HSC_MDAT              EU1D2            11       ADM1278_SM-IC,G99251-001
TP_HSC_SPISSN            EU1D2            9        ADM1278_SM-IC,G99251-001
TP_IE_DEBUG_MODE         J9G1             7        CONN12_C73564003_PIP-CONN,C735A
TP_IOA5                  J1C1             A5       CONN76_H22707001_THMT1-CONN,H2A
TP_IOE4                  J1C1             E4       CONN76_H22707001_THMT1-CONN,H2A
TP_IOF4                  J1C1             F4       CONN76_H22707001_THMT1-CONN,H2A
TP_IOG3                  J1C1             G3       CONN76_H22707001_THMT1-CONN,H2A
TP_IOH3                  J1C1             H3       CONN76_H22707001_THMT1-CONN,H2A
TP_IOH4                  J1C1             H4       CONN76_H22707001_THMT1-CONN,H2A
TP_IOI4                  J1C1             I4       CONN76_H22707001_THMT1-CONN,H2A
TP_IRQ_CPU1_CD_HFI0_N    U2D1             BP19     SKX_EXT_B_BGA1-IC,TBD
TP_JTAG_BMC_RTCK         U9F4             G4       AST1250_BGA-IC,G85138-002
TP_JTAG_MCP_IO8_RSVD     J9B4             8        SCONN10_C12536004_SMLF-CONN,C1A
TP_JUMPER_BLOCK_1_1      J8G2             1        CONN12_C73564003_PIP-CONN,C735A
TP_JUMPER_BLOCK_1_2      J8G2             2        CONN12_C73564003_PIP-CONN,C735A
TP_JUMPER_BLOCK_1_7      J8G2             7        CONN12_C73564003_PIP-CONN,C735A
TP_JUMPER_BLOCK_1_8      J8G2             8        CONN12_C73564003_PIP-CONN,C735A
TP_JUMPER_BLOCK_2_8      J9G1             8        CONN12_C73564003_PIP-CONN,C735A
TP_JUMPER_BLOCK_2_10     J9G1             10       CONN12_C73564003_PIP-CONN,C735A
TP_JUMPER_BLOCK_2_12     J9G1             12       CONN12_C73564003_PIP-CONN,C735A
TP_K4B1G16_BMC_NC0       U9F5             J1       K4B1G16_BGA1-IC,G38649-001
TP_K4B1G16_BMC_NC1       U9F5             J9       K4B1G16_BGA1-IC,G38649-001
TP_K4B1G16_BMC_NC2       U9F5             L1       K4B1G16_BGA1-IC,G38649-001
TP_K4B1G16_BMC_NC3       U9F5             L9       K4B1G16_BGA1-IC,G38649-001
TP_K4B1G16_BMC_NC4       U9F5             M7       K4B1G16_BGA1-IC,G38649-001
TP_LED_CPU1_CD_HFI0_N    U2D1             BK21     SKX_EXT_B_BGA1-IC,TBD
TP_LED_M2_ACT_N          J8F1             10       SCONN75K_H17033002_SMT1-SCONN,A
TP_M2_32M_SUSCLK         J8F1             68       SCONN75K_H17033002_SMT1-SCONN,A
TP_M2_DEVSLP             J8F1             38       SCONN75K_H17033002_SMT1-SCONN,A
TP_ME_RCVR_BOOT          J7G3             1        CONN12_C73564003_PIP-CONN,C735A
TP_M_BMC_DDR3_MIOZ       U9F4             V16      AST1250_BGA-IC,G85138-002
TP_NMI_CPU0              U5D1             AP11     SKX_EXT_B_BGA1-IC,TBD
TP_P1V05_PCH_GL_0        EU7A2            6        IR354XX_SM-IR35412,IC,H73684-0A
TP_P1V05_PCH_GL_1        EU7A2            41       IR354XX_SM-IR35412,IC,H73684-0A
TP_P3E_CPU1_PE1_MP_RXN<0> U2D1             CW8      SKX_EXT_B_BGA1-IC,TBD
TP_P3E_CPU1_PE1_MP_RXN<1> U2D1             DA8      SKX_EXT_B_BGA1-IC,TBD
TP_P3E_CPU1_PE1_MP_RXN<2> U2D1             DC8      SKX_EXT_B_BGA1-IC,TBD
TP_P3E_CPU1_PE1_MP_RXN<3> U2D1             DC10     SKX_EXT_B_BGA1-IC,TBD
TP_P3E_CPU1_PE1_MP_RXN<4> U2D1             DE10     SKX_EXT_B_BGA1-IC,TBD
TP_P3E_CPU1_PE1_MP_RXN<5> U2D1             DH9      SKX_EXT_B_BGA1-IC,TBD
TP_P3E_CPU1_PE1_MP_RXN<6> U2D1             DK9      SKX_EXT_B_BGA1-IC,TBD
TP_P3E_CPU1_PE1_MP_RXN<7> U2D1             DM9      SKX_EXT_B_BGA1-IC,TBD
TP_P3E_CPU1_PE1_MP_RXP<0> U2D1             CU8      SKX_EXT_B_BGA1-IC,TBD
TP_P3E_CPU1_PE1_MP_RXP<1> U2D1             CY7      SKX_EXT_B_BGA1-IC,TBD
TP_P3E_CPU1_PE1_MP_RXP<2> U2D1             DB9      SKX_EXT_B_BGA1-IC,TBD
TP_P3E_CPU1_PE1_MP_RXP<3> U2D1             DA10     SKX_EXT_B_BGA1-IC,TBD
TP_P3E_CPU1_PE1_MP_RXP<4> U2D1             DD9      SKX_EXT_B_BGA1-IC,TBD
TP_P3E_CPU1_PE1_MP_RXP<5> U2D1             DF9      SKX_EXT_B_BGA1-IC,TBD
TP_P3E_CPU1_PE1_MP_RXP<6> U2D1             DJ8      SKX_EXT_B_BGA1-IC,TBD
TP_P3E_CPU1_PE1_MP_RXP<7> U2D1             DL10     SKX_EXT_B_BGA1-IC,TBD
TP_P3E_CPU1_PE1_MP_TXN<0> U2D1             DA2      SKX_EXT_B_BGA1-IC,TBD
TP_P3E_CPU1_PE1_MP_TXN<1> U2D1             DC2      SKX_EXT_B_BGA1-IC,TBD
TP_P3E_CPU1_PE1_MP_TXN<2> U2D1             DE2      SKX_EXT_B_BGA1-IC,TBD
TP_P3E_CPU1_PE1_MP_TXN<3> U2D1             DE4      SKX_EXT_B_BGA1-IC,TBD
TP_P3E_CPU1_PE1_MP_TXN<4> U2D1             DG4      SKX_EXT_B_BGA1-IC,TBD
TP_P3E_CPU1_PE1_MP_TXN<5> U2D1             DK3      SKX_EXT_B_BGA1-IC,TBD
TP_P3E_CPU1_PE1_MP_TXN<6> U2D1             DM3      SKX_EXT_B_BGA1-IC,TBD
TP_P3E_CPU1_PE1_MP_TXN<7> U2D1             DN4      SKX_EXT_B_BGA1-IC,TBD
TP_P3E_CPU1_PE1_MP_TXP<0> U2D1             CW2      SKX_EXT_B_BGA1-IC,TBD
TP_P3E_CPU1_PE1_MP_TXP<1> U2D1             DB1      SKX_EXT_B_BGA1-IC,TBD
TP_P3E_CPU1_PE1_MP_TXP<2> U2D1             DD3      SKX_EXT_B_BGA1-IC,TBD
TP_P3E_CPU1_PE1_MP_TXP<3> U2D1             DC4      SKX_EXT_B_BGA1-IC,TBD
TP_P3E_CPU1_PE1_MP_TXP<4> U2D1             DF3      SKX_EXT_B_BGA1-IC,TBD
TP_P3E_CPU1_PE1_MP_TXP<5> U2D1             DH3      SKX_EXT_B_BGA1-IC,TBD
TP_P3E_CPU1_PE1_MP_TXP<6> U2D1             DL2      SKX_EXT_B_BGA1-IC,TBD
TP_P3E_CPU1_PE1_MP_TXP<7> U2D1             DP3      SKX_EXT_B_BGA1-IC,TBD
TP_P3E_CPU1_PE1_RSR3_RXN<8> U2D1             DM11     SKX_EXT_B_BGA1-IC,TBD
TP_P3E_CPU1_PE1_RSR3_RXN<9> U2D1             DP11     SKX_EXT_B_BGA1-IC,TBD
TP_P3E_CPU1_PE1_RSR3_RXN<10> U2D1             DT11     SKX_EXT_B_BGA1-IC,TBD
TP_P3E_CPU1_PE1_RSR3_RXN<11> U2D1             DT13     SKX_EXT_B_BGA1-IC,TBD
TP_P3E_CPU1_PE1_RSR3_RXN<12> U2D1             DV13     SKX_EXT_B_BGA1-IC,TBD
TP_P3E_CPU1_PE1_RSR3_RXN<13> U2D1             DW14     SKX_EXT_B_BGA1-IC,TBD
TP_P3E_CPU1_PE1_RSR3_RXN<14> U2D1             DY15     SKX_EXT_B_BGA1-IC,TBD
TP_P3E_CPU1_PE1_RSR3_RXN<15> U2D1             DU16     SKX_EXT_B_BGA1-IC,TBD
TP_P3E_CPU1_PE1_RSR3_RXP<8> U2D1             DK11     SKX_EXT_B_BGA1-IC,TBD
TP_P3E_CPU1_PE1_RSR3_RXP<9> U2D1             DN10     SKX_EXT_B_BGA1-IC,TBD
TP_P3E_CPU1_PE1_RSR3_RXP<10> U2D1             DR12     SKX_EXT_B_BGA1-IC,TBD
TP_P3E_CPU1_PE1_RSR3_RXP<11> U2D1             DP13     SKX_EXT_B_BGA1-IC,TBD
TP_P3E_CPU1_PE1_RSR3_RXP<12> U2D1             DU12     SKX_EXT_B_BGA1-IC,TBD
TP_P3E_CPU1_PE1_RSR3_RXP<13> U2D1             DY13     SKX_EXT_B_BGA1-IC,TBD
TP_P3E_CPU1_PE1_RSR3_RXP<14> U2D1             DV15     SKX_EXT_B_BGA1-IC,TBD
TP_P3E_CPU1_PE1_RSR3_RXP<15> U2D1             DT15     SKX_EXT_B_BGA1-IC,TBD
TP_P3E_CPU1_PE1_RSR3_TXN<8> U2D1             DT5      SKX_EXT_B_BGA1-IC,TBD
TP_P3E_CPU1_PE1_RSR3_TXN<9> U2D1             DV3      SKX_EXT_B_BGA1-IC,TBD
TP_P3E_CPU1_PE1_RSR3_TXN<10> U2D1             DW4      SKX_EXT_B_BGA1-IC,TBD
TP_P3E_CPU1_PE1_RSR3_TXN<11> U2D1             DU6      SKX_EXT_B_BGA1-IC,TBD
TP_P3E_CPU1_PE1_RSR3_TXN<12> U2D1             DV7      SKX_EXT_B_BGA1-IC,TBD
TP_P3E_CPU1_PE1_RSR3_TXN<13> U2D1             DY7      SKX_EXT_B_BGA1-IC,TBD
TP_P3E_CPU1_PE1_RSR3_TXN<14> U2D1             EA8      SKX_EXT_B_BGA1-IC,TBD
TP_P3E_CPU1_PE1_RSR3_TXN<15> U2D1             ED9      SKX_EXT_B_BGA1-IC,TBD
TP_P3E_CPU1_PE1_RSR3_TXP<8> U2D1             DR4      SKX_EXT_B_BGA1-IC,TBD
TP_P3E_CPU1_PE1_RSR3_TXP<9> U2D1             DU2      SKX_EXT_B_BGA1-IC,TBD
TP_P3E_CPU1_PE1_RSR3_TXP<10> U2D1             DU4      SKX_EXT_B_BGA1-IC,TBD
TP_P3E_CPU1_PE1_RSR3_TXP<11> U2D1             DV5      SKX_EXT_B_BGA1-IC,TBD
TP_P3E_CPU1_PE1_RSR3_TXP<12> U2D1             DT7      SKX_EXT_B_BGA1-IC,TBD
TP_P3E_CPU1_PE1_RSR3_TXP<13> U2D1             DW6      SKX_EXT_B_BGA1-IC,TBD
TP_P3E_CPU1_PE1_RSR3_TXP<14> U2D1             EB7      SKX_EXT_B_BGA1-IC,TBD
TP_P3E_CPU1_PE1_RSR3_TXP<15> U2D1             EC8      SKX_EXT_B_BGA1-IC,TBD
TP_P3E_CPU1_PE2_RSR_RXN<0> U2D1             CT9      SKX_EXT_B_BGA1-IC,TBD
TP_P3E_CPU1_PE2_RSR_RXN<1> U2D1             CP9      SKX_EXT_B_BGA1-IC,TBD
TP_P3E_CPU1_PE2_RSR_RXN<2> U2D1             CP7      SKX_EXT_B_BGA1-IC,TBD
TP_P3E_CPU1_PE2_RSR_RXN<3> U2D1             CM7      SKX_EXT_B_BGA1-IC,TBD
TP_P3E_CPU1_PE2_RSR_RXN<4> U2D1             CK7      SKX_EXT_B_BGA1-IC,TBD
TP_P3E_CPU1_PE2_RSR_RXN<5> U2D1             CG8      SKX_EXT_B_BGA1-IC,TBD
TP_P3E_CPU1_PE2_RSR_RXN<6> U2D1             CE6      SKX_EXT_B_BGA1-IC,TBD
TP_P3E_CPU1_PE2_RSR_RXN<7> U2D1             CE8      SKX_EXT_B_BGA1-IC,TBD
TP_P3E_CPU1_PE2_RSR_RXN<8> U2D1             BY9      SKX_EXT_B_BGA1-IC,TBD
TP_P3E_CPU1_PE2_RSR_RXN<9> U2D1             BY7      SKX_EXT_B_BGA1-IC,TBD
TP_P3E_CPU1_PE2_RSR_RXN<10> U2D1             BV7      SKX_EXT_B_BGA1-IC,TBD
TP_P3E_CPU1_PE2_RSR_RXN<11> U2D1             BT7      SKX_EXT_B_BGA1-IC,TBD
TP_P3E_CPU1_PE2_RSR_RXN<12> U2D1             BR8      SKX_EXT_B_BGA1-IC,TBD
TP_P3E_CPU1_PE2_RSR_RXN<13> U2D1             BN8      SKX_EXT_B_BGA1-IC,TBD
TP_P3E_CPU1_PE2_RSR_RXN<14> U2D1             BL8      SKX_EXT_B_BGA1-IC,TBD
TP_P3E_CPU1_PE2_RSR_RXN<15> U2D1             BK9      SKX_EXT_B_BGA1-IC,TBD
TP_P3E_CPU1_PE2_RSR_RXP<0> U2D1             CR8      SKX_EXT_B_BGA1-IC,TBD
TP_P3E_CPU1_PE2_RSR_RXP<1> U2D1             CM9      SKX_EXT_B_BGA1-IC,TBD
TP_P3E_CPU1_PE2_RSR_RXP<2> U2D1             CN8      SKX_EXT_B_BGA1-IC,TBD
TP_P3E_CPU1_PE2_RSR_RXP<3> U2D1             CL6      SKX_EXT_B_BGA1-IC,TBD
TP_P3E_CPU1_PE2_RSR_RXP<4> U2D1             CH7      SKX_EXT_B_BGA1-IC,TBD
TP_P3E_CPU1_PE2_RSR_RXP<5> U2D1             CF7      SKX_EXT_B_BGA1-IC,TBD
TP_P3E_CPU1_PE2_RSR_RXP<6> U2D1             CD7      SKX_EXT_B_BGA1-IC,TBD
TP_P3E_CPU1_PE2_RSR_RXP<7> U2D1             CC8      SKX_EXT_B_BGA1-IC,TBD
TP_P3E_CPU1_PE2_RSR_RXP<8> U2D1             BV9      SKX_EXT_B_BGA1-IC,TBD
TP_P3E_CPU1_PE2_RSR_RXP<9> U2D1             BW8      SKX_EXT_B_BGA1-IC,TBD
TP_P3E_CPU1_PE2_RSR_RXP<10> U2D1             BU6      SKX_EXT_B_BGA1-IC,TBD
TP_P3E_CPU1_PE2_RSR_RXP<11> U2D1             BP7      SKX_EXT_B_BGA1-IC,TBD
TP_P3E_CPU1_PE2_RSR_RXP<12> U2D1             BP9      SKX_EXT_B_BGA1-IC,TBD
TP_P3E_CPU1_PE2_RSR_RXP<13> U2D1             BM7      SKX_EXT_B_BGA1-IC,TBD
TP_P3E_CPU1_PE2_RSR_RXP<14> U2D1             BJ8      SKX_EXT_B_BGA1-IC,TBD
TP_P3E_CPU1_PE2_RSR_RXP<15> U2D1             BJ10     SKX_EXT_B_BGA1-IC,TBD
TP_P3E_CPU1_PE2_RSR_TXN<0> U2D1             CY3      SKX_EXT_B_BGA1-IC,TBD
TP_P3E_CPU1_PE2_RSR_TXN<1> U2D1             CV3      SKX_EXT_B_BGA1-IC,TBD
TP_P3E_CPU1_PE2_RSR_TXN<2> U2D1             CT1      SKX_EXT_B_BGA1-IC,TBD
TP_P3E_CPU1_PE2_RSR_TXN<3> U2D1             CT3      SKX_EXT_B_BGA1-IC,TBD
TP_P3E_CPU1_PE2_RSR_TXN<4> U2D1             CM1      SKX_EXT_B_BGA1-IC,TBD
TP_P3E_CPU1_PE2_RSR_TXN<5> U2D1             CL2      SKX_EXT_B_BGA1-IC,TBD
TP_P3E_CPU1_PE2_RSR_TXN<6> U2D1             CG2      SKX_EXT_B_BGA1-IC,TBD
TP_P3E_CPU1_PE2_RSR_TXN<7> U2D1             CF3      SKX_EXT_B_BGA1-IC,TBD
TP_P3E_CPU1_PE2_RSR_TXN<8> U2D1             CC2      SKX_EXT_B_BGA1-IC,TBD
TP_P3E_CPU1_PE2_RSR_TXN<9> U2D1             CB3      SKX_EXT_B_BGA1-IC,TBD
TP_P3E_CPU1_PE2_RSR_TXN<10> U2D1             CA4      SKX_EXT_B_BGA1-IC,TBD
TP_P3E_CPU1_PE2_RSR_TXN<11> U2D1             BW4      SKX_EXT_B_BGA1-IC,TBD
TP_P3E_CPU1_PE2_RSR_TXN<12> U2D1             BU4      SKX_EXT_B_BGA1-IC,TBD
TP_P3E_CPU1_PE2_RSR_TXN<13> U2D1             BP5      SKX_EXT_B_BGA1-IC,TBD
TP_P3E_CPU1_PE2_RSR_TXN<14> U2D1             BL4      SKX_EXT_B_BGA1-IC,TBD
TP_P3E_CPU1_PE2_RSR_TXN<15> U2D1             BM5      SKX_EXT_B_BGA1-IC,TBD
TP_P3E_CPU1_PE2_RSR_TXP<0> U2D1             CW4      SKX_EXT_B_BGA1-IC,TBD
TP_P3E_CPU1_PE2_RSR_TXP<1> U2D1             CU2      SKX_EXT_B_BGA1-IC,TBD
TP_P3E_CPU1_PE2_RSR_TXP<2> U2D1             CR2      SKX_EXT_B_BGA1-IC,TBD
TP_P3E_CPU1_PE2_RSR_TXP<3> U2D1             CP3      SKX_EXT_B_BGA1-IC,TBD
TP_P3E_CPU1_PE2_RSR_TXP<4> U2D1             CK1      SKX_EXT_B_BGA1-IC,TBD
TP_P3E_CPU1_PE2_RSR_TXP<5> U2D1             CK3      SKX_EXT_B_BGA1-IC,TBD
TP_P3E_CPU1_PE2_RSR_TXP<6> U2D1             CE2      SKX_EXT_B_BGA1-IC,TBD
TP_P3E_CPU1_PE2_RSR_TXP<7> U2D1             CE4      SKX_EXT_B_BGA1-IC,TBD
TP_P3E_CPU1_PE2_RSR_TXP<8> U2D1             CD3      SKX_EXT_B_BGA1-IC,TBD
TP_P3E_CPU1_PE2_RSR_TXP<9> U2D1             BY3      SKX_EXT_B_BGA1-IC,TBD
TP_P3E_CPU1_PE2_RSR_TXP<10> U2D1             BY5      SKX_EXT_B_BGA1-IC,TBD
TP_P3E_CPU1_PE2_RSR_TXP<11> U2D1             BV3      SKX_EXT_B_BGA1-IC,TBD
TP_P3E_CPU1_PE2_RSR_TXP<12> U2D1             BR4      SKX_EXT_B_BGA1-IC,TBD
TP_P3E_CPU1_PE2_RSR_TXP<13> U2D1             BN4      SKX_EXT_B_BGA1-IC,TBD
TP_P3E_CPU1_PE2_RSR_TXP<14> U2D1             BM3      SKX_EXT_B_BGA1-IC,TBD
TP_P3E_CPU1_PE2_RSR_TXP<15> U2D1             BK5      SKX_EXT_B_BGA1-IC,TBD
TP_PASSWORD_CLEAR        J7G3             7        CONN12_C73564003_PIP-CONN,C735A
TP_PCH_DISPA_BCLK        U7C1             U20      LBG_CORE_QAT_EXT_D_BGA1-IC,H91A
TP_PCH_DISPA_SDI         U7C1             R20      LBG_CORE_QAT_EXT_D_BGA1-IC,H91A
TP_PCH_DISPA_SDO         U7C1             V22      LBG_CORE_QAT_EXT_D_BGA1-IC,H91A
TP_PCH_GPP_D12           U7C1             BN40     LBG_CORE_QAT_EXT_D_BGA1-IC,H91A
TP_PCH_GPP_F12           U7C1             AP7      LBG_CORE_QAT_EXT_D_BGA1-IC,H91A
TP_PCH_GPP_J17           U7C1             CA11     LBG_CORE_QAT_EXT_D_BGA1-IC,H91A
TP_PCH_GPP_J19           U7C1             BY14     LBG_CORE_QAT_EXT_D_BGA1-IC,H91A
TP_PCH_GPP_J21           U7C1             BV12     LBG_CORE_QAT_EXT_D_BGA1-IC,H91A
TP_PCH_GPP_J23           U7C1             BV14     LBG_CORE_QAT_EXT_D_BGA1-IC,H91A
TP_PCH_GPP_L10           U7C1             AF20     LBG_CORE_QAT_EXT_D_BGA1-IC,H91A
TP_PCH_GPP_L11           U7C1             AD20     LBG_CORE_QAT_EXT_D_BGA1-IC,H91A
TP_PCH_HDA_BCLK          U7C1             P18      LBG_CORE_QAT_EXT_D_BGA1-IC,H91A
TP_PCH_HDA_SDI_0         U7C1             K20      LBG_CORE_QAT_EXT_D_BGA1-IC,H91A
TP_PCH_HDA_SDI_1         U7C1             V18      LBG_CORE_QAT_EXT_D_BGA1-IC,H91A
TP_PCH_HDA_SYNC          U7C1             H20      LBG_CORE_QAT_EXT_D_BGA1-IC,H91A
TP_PCH_HSA_RST_N         U7C1             M18      LBG_CORE_QAT_EXT_D_BGA1-IC,H91A
TP_PCH_RSVD0             U7C1             AF61     LBG_CORE_QAT_EXT_D_BGA1-IC,H91A
TP_PCH_RSVD1             U7C1             AC56     LBG_CORE_QAT_EXT_D_BGA1-IC,H91A
TP_PCH_RSVD2             U7C1             AA58     LBG_CORE_QAT_EXT_D_BGA1-IC,H91A
TP_PCH_RSVD3             U7C1             V11      LBG_CORE_QAT_EXT_D_BGA1-IC,H91A
TP_PCH_RSVD4             U7C1             P37      LBG_CORE_QAT_EXT_D_BGA1-IC,H91A
TP_PCH_RSVD5             U7C1             AG15     LBG_CORE_QAT_EXT_D_BGA1-IC,H91A
TP_PCH_RSVD6             U7C1             AT69     LBG_CORE_QAT_EXT_D_BGA1-IC,H91A
TP_PCH_RSVD7             U7C1             F8       LBG_CORE_QAT_EXT_D_BGA1-IC,H91A
TP_PCH_RSVD8             U7C1             F69      LBG_CORE_QAT_EXT_D_BGA1-IC,H91A
TP_PCH_RSVD9             U7C1             F66      LBG_CORE_QAT_EXT_D_BGA1-IC,H91A
TP_PCH_RSVD12            U7C1             C68      LBG_CORE_QAT_EXT_D_BGA1-IC,H91A
TP_PCH_RSVD13            U7C1             C67      LBG_CORE_QAT_EXT_D_BGA1-IC,H91A
TP_PCH_RSVD14            U7C1             E18      LBG_CORE_QAT_EXT_D_BGA1-IC,H91A
TP_PCH_RSVD15            U7C1             C6       LBG_CORE_QAT_EXT_D_BGA1-IC,H91A
TP_PCH_RSVD16            U7C1             C5       LBG_CORE_QAT_EXT_D_BGA1-IC,H91A
TP_PCH_RSVD17            U7C1             B10      LBG_CORE_QAT_EXT_D_BGA1-IC,H91A
TP_PCH_RSVD18            U7C1             C11      LBG_CORE_QAT_EXT_D_BGA1-IC,H91A
TP_PCH_RSVD19            U7C1             C9       LBG_CORE_QAT_EXT_D_BGA1-IC,H91A
TP_PCH_RSVD20            U7C1             D10      LBG_CORE_QAT_EXT_D_BGA1-IC,H91A
TP_PCH_RSVD21            U7C1             A11      LBG_CORE_QAT_EXT_D_BGA1-IC,H91A
TP_PCH_RSVD22            U7C1             AT71     LBG_CORE_QAT_EXT_D_BGA1-IC,H91A
TP_PCH_RSVD23            U7C1             P40      LBG_CORE_QAT_EXT_D_BGA1-IC,H91A
TP_PCH_RSVD24            U7C1             P44      LBG_CORE_QAT_EXT_D_BGA1-IC,H91A
TP_PCH_RSVD25            U7C1             P48      LBG_CORE_QAT_EXT_D_BGA1-IC,H91A
TP_PCH_RSVD26            U7C1             BH24     LBG_CORE_QAT_EXT_D_BGA1-IC,H91A
TP_PCH_RSVD27            U7C1             BG26     LBG_CORE_QAT_EXT_D_BGA1-IC,H91A
TP_PCH_RSVD28            U7C1             R35      LBG_CORE_QAT_EXT_D_BGA1-IC,H91A
TP_PCH_RSVD29            U7C1             P33      LBG_CORE_QAT_EXT_D_BGA1-IC,H91A
TP_PCH_RSVD30            U7C1             R31      LBG_CORE_QAT_EXT_D_BGA1-IC,H91A
TP_PCH_RSVD31            U7C1             P29      LBG_CORE_QAT_EXT_D_BGA1-IC,H91A
TP_PCH_RSVD32            U7C1             AA54     LBG_CORE_QAT_EXT_D_BGA1-IC,H91A
TP_PCH_RSVD33            U7C1             V56      LBG_CORE_QAT_EXT_D_BGA1-IC,H91A
TP_PCH_RSVD34            U7C1             Y56      LBG_CORE_QAT_EXT_D_BGA1-IC,H91A
TP_PCH_RSVD35            U7C1             W54      LBG_CORE_QAT_EXT_D_BGA1-IC,H91A
TP_PCH_RSVD36            U7C1             AK54     LBG_CORE_QAT_EXT_D_BGA1-IC,H91A
TP_PCH_RSVD37            U7C1             BN29     LBG_CORE_QAT_EXT_D_BGA1-IC,H91A
TP_PCH_RSVD38            U7C1             BL29     LBG_CORE_QAT_EXT_D_BGA1-IC,H91A
TP_PCH_RSVD41            U7C1             BJ40     LBG_CORE_QAT_EXT_D_BGA1-IC,H91A
TP_PCH_RSVD42            U7C1             BG40     LBG_CORE_QAT_EXT_D_BGA1-IC,H91A
TP_PCH_RSVD45            U7C1             P22      LBG_CORE_QAT_EXT_D_BGA1-IC,H91A
TP_PCH_RSVD46            U7C1             BW3      LBG_CORE_QAT_EXT_D_BGA1-IC,H91A
TP_PCH_RSVD47            U7C1             AP69     LBG_CORE_QAT_EXT_D_BGA1-IC,H91A
TP_PCH_RSVD48            U7C1             AP71     LBG_CORE_QAT_EXT_D_BGA1-IC,H91A
TP_PCH_RSVD49            U7C1             G67      LBG_CORE_QAT_EXT_D_BGA1-IC,H91A
TP_PCH_RSVD50            U7C1             H69      LBG_CORE_QAT_EXT_D_BGA1-IC,H91A
TP_PCH_RSVD51            U7C1             AA69     LBG_CORE_QAT_EXT_D_BGA1-IC,H91A
TP_PCH_RSVD52            U7C1             AA71     LBG_CORE_QAT_EXT_D_BGA1-IC,H91A
TP_PCH_RSVD53            U7C1             P26      LBG_CORE_QAT_EXT_D_BGA1-IC,H91A
TP_PCH_RSVD54            U7C1             R24      LBG_CORE_QAT_EXT_D_BGA1-IC,H91A
TP_PCH_RSVD55            U7C1             BN68     LBG_CORE_QAT_EXT_D_BGA1-IC,H91A
TP_PCH_RSVD58            U7C1             AP27     LBG_CORE_QAT_EXT_D_BGA1-IC,H91A
TP_PCH_RSVD59            U7C1             AT27     LBG_CORE_QAT_EXT_D_BGA1-IC,H91A
TP_PCH_RSVD64            U7C1             C26      LBG_CORE_QAT_EXT_D_BGA1-IC,H91A
TP_PCH_RSVD65            U7C1             A26      LBG_CORE_QAT_EXT_D_BGA1-IC,H91A
TP_PI7C9X1172_EN485_N    EU9F3            19       PI7C9X1172_QFN-IC,H66899-001
TP_PI7C9X1172_ENIR_N     EU9F3            18       PI7C9X1172_QFN-IC,H66899-001
TP_PI7C9X1172_RTSA_N     EU9F3            21       PI7C9X1172_QFN-IC,H66899-001
TP_PI7C9X1172_RTSB_N     EU9F3            15       PI7C9X1172_QFN-IC,H66899-001
TP_PI7C9X1172_SO         EU9F3            2        PI7C9X1172_QFN-IC,H66899-001
TP_PLTRST_CPU_N          U7C1             U17      LBG_CORE_QAT_EXT_D_BGA1-IC,H91A
TP_PM_SYNC_GTL           U7C1             V7       LBG_CORE_QAT_EXT_D_BGA1-IC,H91A
TP_PVCCINC_CPU1_PH1_GL_0 EU1E2            6        IR354XX_SM-IR35411,IC,H73688-0A
TP_PVCCINC_CPU1_PH1_GL_1 EU1E2            41       IR354XX_SM-IR35411,IC,H73688-0A
TP_PVCCINC_CPU1_PH2_GL_0 EU1D4            6        IR354XX_SM-IR35411,IC,H73688-0A
TP_PVCCINC_CPU1_PH2_GL_1 EU1D4            41       IR354XX_SM-IR35411,IC,H73688-0A
TP_PVCCIN_CPU0_AIREF6    EU4D4            33       PXE1610B_QFN-IC,H79206-001
TP_PVCCIN_CPU0_AISEN6    EU4D4            34       PXE1610B_QFN-IC,H79206-001
TP_PVCCIN_CPU0_APWM6     EU4D4            2        PXE1610B_QFN-IC,H79206-001
TP_PVCCIN_CPU0_FAULT1_20 EU4D4            40       PXE1610B_QFN-IC,H79206-001
TP_PVCCIN_CPU0_GP1       EU4D4            16       PXE1610B_QFN-IC,H79206-001
TP_PVCCIN_CPU0_PH1_GL_0  EU4E1            6        IR354XX_SM-IR35411,IC,H73688-0A
TP_PVCCIN_CPU0_PH1_GL_1  EU4E1            41       IR354XX_SM-IR35411,IC,H73688-0A
TP_PVCCIN_CPU0_PH2_GL_0  EU4D6            6        IR354XX_SM-IR35411,IC,H73688-0A
TP_PVCCIN_CPU0_PH2_GL_1  EU4D6            41       IR354XX_SM-IR35411,IC,H73688-0A
TP_PVCCIN_CPU0_PH3_GL_0  EU4D3            6        IR354XX_SM-IR35411,IC,H73688-0A
TP_PVCCIN_CPU0_PH3_GL_1  EU4D3            41       IR354XX_SM-IR35411,IC,H73688-0A
TP_PVCCIN_CPU0_PH4_GL_0  EU4D1            6        IR354XX_SM-IR35411,IC,H73688-0A
TP_PVCCIN_CPU0_PH4_GL_1  EU4D1            41       IR354XX_SM-IR35411,IC,H73688-0A
TP_PVCCIN_CPU0_PH5_GL_0  EU4C2            6        IR354XX_SM-IR35411,IC,H73688-0A
TP_PVCCIN_CPU0_PH5_GL_1  EU4C2            41       IR354XX_SM-IR35411,IC,H73688-0A
TP_PVCCIN_CPU0_RESET     EU4D4            10       PXE1610B_QFN-IC,H79206-001
TP_PVCCIN_CPU1_AIREF6    EU1C2            33       PXE1610B_QFN-IC,H79206-001
TP_PVCCIN_CPU1_AISEN6    EU1C2            34       PXE1610B_QFN-IC,H79206-001
TP_PVCCIN_CPU1_APWM6     EU1C2            2        PXE1610B_QFN-IC,H79206-001
TP_PVCCIN_CPU1_FAULT1_20 EU1C2            40       PXE1610B_QFN-IC,H79206-001
TP_PVCCIN_CPU1_GP1       EU1C2            16       PXE1610B_QFN-IC,H79206-001
TP_PVCCIN_CPU1_PH3_GL_0  EU1D3            6        IR354XX_SM-IR35411,IC,H73688-0A
TP_PVCCIN_CPU1_PH3_GL_1  EU1D3            41       IR354XX_SM-IR35411,IC,H73688-0A
TP_PVCCIN_CPU1_PH4_GL_0  EU1D1            6        IR354XX_SM-IR35411,IC,H73688-0A
TP_PVCCIN_CPU1_PH4_GL_1  EU1D1            41       IR354XX_SM-IR35411,IC,H73688-0A
TP_PVCCIN_CPU1_PH5_GL_0  EU1C3            6        IR354XX_SM-IR35411,IC,H73688-0A
TP_PVCCIN_CPU1_PH5_GL_1  EU1C3            41       IR354XX_SM-IR35411,IC,H73688-0A
TP_PVCCIN_CPU1_RESET_N   EU1C2            10       PXE1610B_QFN-IC,H79206-001
TP_PVCCIO_CPU0_BIREF1    EU3P1            25       PXE1110B_QFN-IC,H89187-001
TP_PVCCIO_CPU0_BPWM1     EU3P1            3        PXE1110B_QFN-IC,H89187-001
TP_PVCCIO_CPU0_BTSEN     EU3P1            34       PXE1110B_QFN-IC,H89187-001
TP_PVCCIO_CPU0_BVREF     EU3P1            30       PXE1110B_QFN-IC,H89187-001
TP_PVCCIO_CPU0_BVSEN     EU3P1            29       PXE1110B_QFN-IC,H89187-001
TP_PVCCIO_CPU0_GL_0      EU7C1            6        IR354XX_SM-IR35412,IC,H73684-0A
TP_PVCCIO_CPU0_GL_1      EU7C1            41       IR354XX_SM-IR35412,IC,H73684-0A
TP_PVCCIO_CPU0_PINALRT_N EU3P1            12       PXE1110B_QFN-IC,H89187-001
TP_PVCCIO_CPU0_RESET_N   EU3P1            8        PXE1110B_QFN-IC,H89187-001
TP_PVCCIO_CPU1_BIREF1    EU4D5            25       PXE1110B_QFN-IC,H89187-001
TP_PVCCIO_CPU1_BPWM1     EU4D5            3        PXE1110B_QFN-IC,H89187-001
TP_PVCCIO_CPU1_BTSEN     EU4D5            34       PXE1110B_QFN-IC,H89187-001
TP_PVCCIO_CPU1_BVREF     EU4D5            30       PXE1110B_QFN-IC,H89187-001
TP_PVCCIO_CPU1_BVSEN     EU4D5            29       PXE1110B_QFN-IC,H89187-001
TP_PVCCIO_CPU1_GL_0      EU4E2            6        IR354XX_SM-IR35412,IC,H73684-0A
TP_PVCCIO_CPU1_GL_1      EU4E2            41       IR354XX_SM-IR35412,IC,H73684-0A
TP_PVCCIO_CPU1_PINALRT_N EU4D5            12       PXE1110B_QFN-IC,H89187-001
TP_PVCCIO_CPU1_RESET_N   EU4D5            8        PXE1110B_QFN-IC,H89187-001
TP_PVDDQ_ABC_BPWM1       EU7G1            1        PXM1310B_QFN-IC,H89186-001
TP_PVDDQ_ABC_BREF1       EU7G1            31       PXM1310B_QFN-IC,H89186-001
TP_PVDDQ_ABC_BTSEN       EU7G1            34       PXM1310B_QFN-IC,H89186-001
TP_PVDDQ_ABC_BVREF       EU7G1            30       PXM1310B_QFN-IC,H89186-001
TP_PVDDQ_ABC_BVSEN       EU7G1            29       PXM1310B_QFN-IC,H89186-001
TP_PVDDQ_ABC_MP1         EU7G1            14       PXM1310B_QFN-IC,H89186-001
TP_PVDDQ_ABC_MP2         EU7G1            18       PXM1310B_QFN-IC,H89186-001
TP_PVDDQ_ABC_PH1_GL_0    EU7G2            6        IR354XX_SM-IR35411,IC,H73688-0A
TP_PVDDQ_ABC_PH1_GL_1    EU7G2            41       IR354XX_SM-IR35411,IC,H73688-0A
TP_PVDDQ_ABC_PH2_GL_0    EU7G3            6        IR354XX_SM-IR35411,IC,H73688-0A
TP_PVDDQ_ABC_PH2_GL_1    EU7G3            41       IR354XX_SM-IR35411,IC,H73688-0A
TP_PVDDQ_ABC_PH3_IMON    EU7G1            26       PXM1310B_QFN-IC,H89186-001
TP_PVDDQ_ABC_PH3_IMON_REF EU7G1            25       PXM1310B_QFN-IC,H89186-001
TP_PVDDQ_ABC_PINALRT_N   EU7G1            12       PXM1310B_QFN-IC,H89186-001
TP_PVDDQ_ABC_PWM3        EU7G1            3        PXM1310B_QFN-IC,H89186-001
TP_PVDDQ_ABC_RESET_N     EU7G1            8        PXM1310B_QFN-IC,H89186-001
TP_PVDDQ_DEF_BPWM1       EU7A5            1        PXM1310B_QFN-IC,H89186-001
TP_PVDDQ_DEF_BREF1       EU7A5            31       PXM1310B_QFN-IC,H89186-001
TP_PVDDQ_DEF_BTSEN       EU7A5            34       PXM1310B_QFN-IC,H89186-001
TP_PVDDQ_DEF_BVREF       EU7A5            30       PXM1310B_QFN-IC,H89186-001
TP_PVDDQ_DEF_BVSEN       EU7A5            29       PXM1310B_QFN-IC,H89186-001
TP_PVDDQ_DEF_MP1         EU7A5            14       PXM1310B_QFN-IC,H89186-001
TP_PVDDQ_DEF_MP2         EU7A5            18       PXM1310B_QFN-IC,H89186-001
TP_PVDDQ_DEF_PH1_GL_0    EU7A1            6        IR354XX_SM-IR35411,IC,H73688-0A
TP_PVDDQ_DEF_PH1_GL_1    EU7A1            41       IR354XX_SM-IR35411,IC,H73688-0A
TP_PVDDQ_DEF_PH2_GL_0    EU7A4            6        IR354XX_SM-IR35411,IC,H73688-0A
TP_PVDDQ_DEF_PH2_GL_1    EU7A4            41       IR354XX_SM-IR35411,IC,H73688-0A
TP_PVDDQ_DEF_PH3_IMON    EU7A5            26       PXM1310B_QFN-IC,H89186-001
TP_PVDDQ_DEF_PH3_IMON_REF EU7A5            25       PXM1310B_QFN-IC,H89186-001
TP_PVDDQ_DEF_PINALRT_N   EU7A5            12       PXM1310B_QFN-IC,H89186-001
TP_PVDDQ_DEF_PWM3        EU7A5            3        PXM1310B_QFN-IC,H89186-001
TP_PVDDQ_DEF_RESET_N     EU7A5            8        PXM1310B_QFN-IC,H89186-001
TP_PVDDQ_GHJ_BPWM1       EU1G2            1        PXM1310B_QFN-IC,H89186-001
TP_PVDDQ_GHJ_BREF1       EU1G2            31       PXM1310B_QFN-IC,H89186-001
TP_PVDDQ_GHJ_BTSEN       EU1G2            34       PXM1310B_QFN-IC,H89186-001
TP_PVDDQ_GHJ_BVREF       EU1G2            30       PXM1310B_QFN-IC,H89186-001
TP_PVDDQ_GHJ_BVSEN       EU1G2            29       PXM1310B_QFN-IC,H89186-001
TP_PVDDQ_GHJ_MP1         EU1G2            14       PXM1310B_QFN-IC,H89186-001
TP_PVDDQ_GHJ_MP2         EU1G2            18       PXM1310B_QFN-IC,H89186-001
TP_PVDDQ_GHJ_PH1_GL_0    EU1G1            6        IR354XX_SM-IR35411,IC,H73688-0A
TP_PVDDQ_GHJ_PH1_GL_1    EU1G1            41       IR354XX_SM-IR35411,IC,H73688-0A
TP_PVDDQ_GHJ_PH2_GL_0    EU1F1            6        IR354XX_SM-IR35411,IC,H73688-0A
TP_PVDDQ_GHJ_PH2_GL_1    EU1F1            41       IR354XX_SM-IR35411,IC,H73688-0A
TP_PVDDQ_GHJ_PH3_IMON    EU1G2            26       PXM1310B_QFN-IC,H89186-001
TP_PVDDQ_GHJ_PH3_IMON_REF EU1G2            25       PXM1310B_QFN-IC,H89186-001
TP_PVDDQ_GHJ_PWM3        EU1G2            3        PXM1310B_QFN-IC,H89186-001
TP_PVDDQ_GHJ_RESET_N     EU1G2            8        PXM1310B_QFN-IC,H89186-001
TP_PVDDQ_KLM_BPWM1       EU1B1            1        PXM1310B_QFN-IC,H89186-001
TP_PVDDQ_KLM_BREF1       EU1B1            31       PXM1310B_QFN-IC,H89186-001
TP_PVDDQ_KLM_BTSEN       EU1B1            34       PXM1310B_QFN-IC,H89186-001
TP_PVDDQ_KLM_BVREF       EU1B1            30       PXM1310B_QFN-IC,H89186-001
TP_PVDDQ_KLM_BVSEN       EU1B1            29       PXM1310B_QFN-IC,H89186-001
TP_PVDDQ_KLM_PH1_GL_0    EU1A2            6        IR354XX_SM-IR35411,IC,H73688-0A
TP_PVDDQ_KLM_PH1_GL_1    EU1A2            41       IR354XX_SM-IR35411,IC,H73688-0A
TP_PVDDQ_KLM_PH2_GL_0    EU1A1            6        IR354XX_SM-IR35411,IC,H73688-0A
TP_PVDDQ_KLM_PH2_GL_1    EU1A1            41       IR354XX_SM-IR35411,IC,H73688-0A
TP_PVDDQ_KLM_PH3_IMON    EU1B1            26       PXM1310B_QFN-IC,H89186-001
TP_PVDDQ_KLM_PH3_IMON_REF EU1B1            25       PXM1310B_QFN-IC,H89186-001
TP_PVDDQ_KLM_RESET_N     EU1B1            8        PXM1310B_QFN-IC,H89186-001
TP_PVNN_PCH_GL_0         EU7A3            6        IR354XX_SM-IR35412,IC,H73684-0A
TP_PVNN_PCH_GL_1         EU7A3            41       IR354XX_SM-IR35412,IC,H73684-0A
TP_PVNN_PCH_MP2          EU8A1            18       PXE1110B_QFN-IC,H89187-001
TP_PVNN_PCH_MP3          EU8A1            31       PXE1110B_QFN-IC,H89187-001
TP_PVNN_PCH_PINALRT_N    EU8A1            12       PXE1110B_QFN-IC,H89187-001
TP_PVNN_PCH_RESET_N      EU8A1            8        PXE1110B_QFN-IC,H89187-001
TP_PVNN_PCH_SVID_ALERT   EU8A1            17       PXE1110B_QFN-IC,H89187-001
TP_PVNN_PCH_VCLK         EU8A1            15       PXE1110B_QFN-IC,H89187-001
TP_PVNN_PCH_VDIO         EU8A1            16       PXE1110B_QFN-IC,H89187-001
TP_PVSA_CPU0_GL_0        EU4C1            6        IR354XX_SM-IR35412,IC,H73684-0A
TP_PVSA_CPU0_GL_1        EU4C1            41       IR354XX_SM-IR35412,IC,H73684-0A
TP_PVSA_CPU1_GL_0        EU1C1            6        IR354XX_SM-IR35412,IC,H73684-0A
TP_PVSA_CPU1_GL_1        EU1C1            41       IR354XX_SM-IR35412,IC,H73684-0A
TP_RGMII1TXCTL_GPIOT1    U9F4             E9       AST1250_BGA-IC,G85138-002
TP_RGMII1TXD2_GPIOT4     U9F4             C10      AST1250_BGA-IC,G85138-002
TP_RGMII1TXD3_GPIOT5     U9F4             D10      AST1250_BGA-IC,G85138-002
TP_RGMII2TXCTL_GPIOT7    U9F4             B12      AST1250_BGA-IC,G85138-002
TP_RGMII2TXD2_GPIOT4     U9F4             E12      AST1250_BGA-IC,G85138-002
TP_RGMII2TXD3_GPIOT5     U9F4             A13      AST1250_BGA-IC,G85138-002
TP_RST_CPU1_CD_HFI0_N    U2D1             BN24     SKX_EXT_B_BGA1-IC,TBD
TP_RST_RTCRST_N          J9G1             2        CONN12_C73564003_PIP-CONN,C735A
TP_RSVD<0>               J8E4             36       SCONN64_H87568002_A_SMT-CONN,HA
TP_RSVD_B1               J8E3             6        SCONN80_E67482007_SM-CONN,E674A
TP_SGPIO_SATA_CLOCK1_R   J8A1             2A2      CONN72_G97614002_A_CP-CONN,G97A
TP_SGPIO_SATA_DATA1_R    J8A1             2C1      CONN72_G97614002_A_CP-CONN,G97A
TP_SGPIO_SATA_LOAD1_R    J8A1             2B2      CONN72_G97614002_A_CP-CONN,G97A
TP_SHARED_KR_MDC_0       J8E4             49       SCONN64_H87568002_A_SMT-CONN,HA
TP_SHARED_KR_MDIO_0      J8E4             50       SCONN64_H87568002_A_SMT-CONN,HA
TP_SLG55021_P12V_FAN_8   EU9M1            8        SLG55021_SM-IC,G56246-001
TP_SLG55021_P12V_MAIN_8  EU7E1            8        SLG55021_SM-IC,G56246-001
TP_SLG55021_P3V3_8       EU2T1            8        SLG55021_SM-IC,G56246-001
TP_SLG55021_P5V_8        EU8B1            8        SLG55021_SM-IC,G56246-001
TP_SLP_LAN_N             U7C1             M15      LBG_CORE_QAT_EXT_D_BGA1-IC,H91A
TP_SMB_CPU1_CD_HFI0_I2CCLK U2D1             BN22     SKX_EXT_B_BGA1-IC,TBD
TP_SMB_CPU1_CD_HFI0_I2CDAT U2D1             BP23     SKX_EXT_B_BGA1-IC,TBD
TP_SMB_DDR_ABC_EN        U6F1             5        PCA9617_SSOP-IC,G81764-001-GNDA
TP_SMB_DDR_DEF_EN        U7E1             5        PCA9617_SSOP-IC,G81764-001-GNDA
TP_SMB_DDR_GHJ_EN        U4G1             5        PCA9617_SSOP-IC,G81764-001-GNDA
TP_SMB_DDR_KLM_EN        U3B1             5        PCA9617_SSOP-IC,G81764-001-GNDA
TP_SMB_PEHPCPU1_EN       U1B2             5        PCA9517_SM-IC,G77073-001-GND=GA
TP_SPI_0_0               U7F1             14       W25Q256_XSOI-IC,H25002-001
TP_SPI_0_1               U7F1             13       W25Q256_XSOI-IC,H25002-001
TP_SPI_0_2               U7F1             12       W25Q256_XSOI-IC,H25002-001
TP_SPI_0_3               U7F1             11       W25Q256_XSOI-IC,H25002-001
TP_SPI_0_4               U7F1             6        W25Q256_XSOI-IC,H25002-001
TP_SPI_0_5               U7F1             5        W25Q256_XSOI-IC,H25002-001
TP_SPI_0_6               U7F1             4        W25Q256_XSOI-IC,H25002-001
TP_SPI_1_0               U3T1             14       W25Q256_XSOI-IC,H25002-001
TP_SPI_1_1               U3T1             13       W25Q256_XSOI-IC,H25002-001
TP_SPI_1_2               U3T1             12       W25Q256_XSOI-IC,H25002-001
TP_SPI_1_3               U3T1             11       W25Q256_XSOI-IC,H25002-001
TP_SPI_1_4               U3T1             6        W25Q256_XSOI-IC,H25002-001
TP_SPI_1_5               U3T1             5        W25Q256_XSOI-IC,H25002-001
TP_SPI_1_6               U3T1             4        W25Q256_XSOI-IC,H25002-001
TP_SPI_2_0               U8F2             4        W25Q128_SKT16-IC,H12709-001
TP_SPI_2_1               U8F2             5        W25Q128_SKT16-IC,H12709-001
TP_SPI_2_2               U8F2             6        W25Q128_SKT16-IC,H12709-001
TP_SPI_2_3               U8F2             11       W25Q128_SKT16-IC,H12709-001
TP_SPI_2_4               U8F2             12       W25Q128_SKT16-IC,H12709-001
TP_SPI_2_5               U8F2             13       W25Q128_SKT16-IC,H12709-001
TP_SPI_2_6               U8F2             14       W25Q128_SKT16-IC,H12709-001
TP_SPI_BMC_BT_D2         U9F4             U22      AST1250_BGA-IC,G85138-002
TP_SPI_PCH_BIOS_CLK_R    U9F4             G18      AST1250_BGA-IC,G85138-002
TP_SPI_PCH_BIOS_CS0_R_N  U9F4             C22      AST1250_BGA-IC,G85138-002
TP_SPI_PCH_BIOS_MISO_R   U9F4             C20      AST1250_BGA-IC,G85138-002
TP_SPI_PCH_BIOS_MOSI_R   U9F4             D19      AST1250_BGA-IC,G85138-002
TP_SPI_PCH_CS1_R1_N      U7C1             G7       LBG_CORE_QAT_EXT_D_BGA1-IC,H91A
TP_SPI_SWITCH1_3         U2T1             3        PI3B3257A_TSSOPLF-IC,E16801-001
TP_SPI_SWITCH1_6         U2T1             6        PI3B3257A_TSSOPLF-IC,E16801-001
TP_SPI_SWITCH1_9         U2T1             9        PI3B3257A_TSSOPLF-IC,E16801-001
TP_SPI_SWITCH1_10        U2T1             10       PI3B3257A_TSSOPLF-IC,E16801-001
TP_SPI_SWITCH1_11        U2T1             11       PI3B3257A_TSSOPLF-IC,E16801-001
TP_SPI_SWITCH1_12        U2T1             12       PI3B3257A_TSSOPLF-IC,E16801-001
TP_SPI_SWITCH1_13        U2T1             13       PI3B3257A_TSSOPLF-IC,E16801-001
TP_SPI_SWITCH1_14        U2T1             14       PI3B3257A_TSSOPLF-IC,E16801-001
TP_SPRV_SDP0             EU9E1            63       SPRINGVILLE_SM1-IC,G47144-004
TP_SPRV_SDP1             EU9E1            61       SPRINGVILLE_SM1-IC,G47144-004
TP_SPRV_SDP2             EU9E1            62       SPRINGVILLE_SM1-IC,G47144-004
TP_SPRV_SDP3             EU9E1            60       SPRINGVILLE_SM1-IC,G47144-004
TP_USB2_P02_DN           U7C1             CA61     LBG_CORE_QAT_EXT_D_BGA1-IC,H91A
TP_USB2_P02_DP           U7C1             BW61     LBG_CORE_QAT_EXT_D_BGA1-IC,H91A
TP_USB2_P03_DN           U7C1             CA59     LBG_CORE_QAT_EXT_D_BGA1-IC,H91A
TP_USB2_P03_DP           U7C1             BW59     LBG_CORE_QAT_EXT_D_BGA1-IC,H91A
TP_USB2_P06_DN           U7C1             CA63     LBG_CORE_QAT_EXT_D_BGA1-IC,H91A
TP_USB2_P06_DP           U7C1             BW63     LBG_CORE_QAT_EXT_D_BGA1-IC,H91A
TP_USB2_P07_DN           U7C1             CA57     LBG_CORE_QAT_EXT_D_BGA1-IC,H91A
TP_USB2_P07_DP           U7C1             BW57     LBG_CORE_QAT_EXT_D_BGA1-IC,H91A
TP_USB2_P10_DN           U7C1             BW65     LBG_CORE_QAT_EXT_D_BGA1-IC,H91A
TP_USB2_P10_DP           U7C1             BU65     LBG_CORE_QAT_EXT_D_BGA1-IC,H91A
TP_USB2_P11_DN           U7C1             CA54     LBG_CORE_QAT_EXT_D_BGA1-IC,H91A
TP_USB2_P11_DP           U7C1             BW54     LBG_CORE_QAT_EXT_D_BGA1-IC,H91A
TP_USB2_P12_DN           U7C1             BW67     LBG_CORE_QAT_EXT_D_BGA1-IC,H91A
TP_USB2_P12_DP           U7C1             BV66     LBG_CORE_QAT_EXT_D_BGA1-IC,H91A
TP_USB2_P13_DN           U7C1             BY53     LBG_CORE_QAT_EXT_D_BGA1-IC,H91A
TP_USB2_P13_DP           U7C1             BV53     LBG_CORE_QAT_EXT_D_BGA1-IC,H91A
TP_USB2_P14_DN           U7C1             BW68     LBG_CORE_QAT_EXT_D_BGA1-IC,H91A
TP_USB2_P14_DP           U7C1             BU67     LBG_CORE_QAT_EXT_D_BGA1-IC,H91A
TP_USB2_P8_DN            U7C1             BY64     LBG_CORE_QAT_EXT_D_BGA1-IC,H91A
TP_USB2_P8_DP            U7C1             BV64     LBG_CORE_QAT_EXT_D_BGA1-IC,H91A
TP_USB2_P9_DN            U7C1             BY55     LBG_CORE_QAT_EXT_D_BGA1-IC,H91A
TP_USB2_P9_DP            U7C1             BV55     LBG_CORE_QAT_EXT_D_BGA1-IC,H91A
TP_USB3_P02_RXN          U7C1             BJ72     LBG_CORE_QAT_EXT_D_BGA1-IC,H91A
TP_USB3_P02_RXP          U7C1             BJ70     LBG_CORE_QAT_EXT_D_BGA1-IC,H91A
TP_USB3_P02_TXN          U7C1             BL56     LBG_CORE_QAT_EXT_D_BGA1-IC,H91A
TP_USB3_P02_TXP          U7C1             BJ56     LBG_CORE_QAT_EXT_D_BGA1-IC,H91A
TP_USB3_P03_RXN          U7C1             BH71     LBG_CORE_QAT_EXT_D_BGA1-IC,H91A
TP_USB3_P03_RXP          U7C1             BH69     LBG_CORE_QAT_EXT_D_BGA1-IC,H91A
TP_USB3_P03_TXN          U7C1             BM54     LBG_CORE_QAT_EXT_D_BGA1-IC,H91A
TP_USB3_P03_TXP          U7C1             BN56     LBG_CORE_QAT_EXT_D_BGA1-IC,H91A
TP_USB3_P04_RXN          U7C1             BF72     LBG_CORE_QAT_EXT_D_BGA1-IC,H91A
TP_USB3_P04_RXP          U7C1             BF70     LBG_CORE_QAT_EXT_D_BGA1-IC,H91A
TP_USB3_P04_TXN          U7C1             BH58     LBG_CORE_QAT_EXT_D_BGA1-IC,H91A
TP_USB3_P04_TXP          U7C1             BG56     LBG_CORE_QAT_EXT_D_BGA1-IC,H91A
TP_USB3_P05_RXN          U7C1             BE71     LBG_CORE_QAT_EXT_D_BGA1-IC,H91A
TP_USB3_P05_RXP          U7C1             BE69     LBG_CORE_QAT_EXT_D_BGA1-IC,H91A
TP_USB3_P05_TXN          U7C1             BK58     LBG_CORE_QAT_EXT_D_BGA1-IC,H91A
TP_USB3_P05_TXP          U7C1             BJ59     LBG_CORE_QAT_EXT_D_BGA1-IC,H91A
TP_USB3_P06_RXN          U7C1             BD72     LBG_CORE_QAT_EXT_D_BGA1-IC,H91A
TP_USB3_P06_RXP          U7C1             BD70     LBG_CORE_QAT_EXT_D_BGA1-IC,H91A
TP_USB3_P06_TXN          U7C1             BL59     LBG_CORE_QAT_EXT_D_BGA1-IC,H91A
TP_USB3_P06_TXP          U7C1             BM61     LBG_CORE_QAT_EXT_D_BGA1-IC,H91A
TP_USB_ESD_AC2           CR1M2            4        DIODEAC_DUAL_ARRAY_SM9-ESD3V3UA
TP_USB_ESD_AC3           CR1M2            5        DIODEAC_DUAL_ARRAY_SM9-ESD3V3UA
TP_USB_ESD_OUT2          CR1M2            7        DIODEAC_DUAL_ARRAY_SM9-ESD3V3UA
TP_USB_ESD_OUT3          CR1M2            6        DIODEAC_DUAL_ARRAY_SM9-ESD3V3UA
TP_VGAHS_GPIOJ4          U9F4             T4       AST1250_BGA-IC,G85138-002
TP_VGAVS_GPIOJ5          U9F4             U2       AST1250_BGA-IC,G85138-002
TP_VR_PVCCIO_CPU0_AIINSEN EU3P1            38       PXE1110B_QFN-IC,H89187-001
TP_VR_PVCCIO_CPU0_MP0    EU3P1            13       PXE1110B_QFN-IC,H89187-001
TP_VR_PVCCIO_CPU0_MP1    EU3P1            14       PXE1110B_QFN-IC,H89187-001
TP_VR_PVCCIO_CPU0_MP2    EU3P1            18       PXE1110B_QFN-IC,H89187-001
TP_VR_PVCCIO_CPU0_MP3    EU3P1            31       PXE1110B_QFN-IC,H89187-001
TP_VR_PVCCIO_CPU1_AIINSEN EU4D5            38       PXE1110B_QFN-IC,H89187-001
TP_VR_PVCCIO_CPU1_MP0    EU4D5            13       PXE1110B_QFN-IC,H89187-001
TP_VR_PVCCIO_CPU1_MP1    EU4D5            14       PXE1110B_QFN-IC,H89187-001
TP_VR_PVCCIO_CPU1_MP2    EU4D5            18       PXE1110B_QFN-IC,H89187-001
TP_VR_PVCCIO_CPU1_MP3    EU4D5            31       PXE1110B_QFN-IC,H89187-001
TP_VR_PVNN_PCH_AIINSEN   EU8A1            38       PXE1110B_QFN-IC,H89187-001
TP_XDP_CPU0_OBSDATA_A0_MBP2_N U5D1             AG10     SKX_EXT_B_BGA1-IC,TBD
TP_XDP_CPU0_OBSDATA_A1_MBP3_N U5D1             AF11     SKX_EXT_B_BGA1-IC,TBD
TP_XDP_CPU0_OBSDATA_A2_MBP4_N U5D1             AA12     SKX_EXT_B_BGA1-IC,TBD
TP_XDP_CPU0_OBSDATA_A3_MBP5_N U5D1             Y11      SKX_EXT_B_BGA1-IC,TBD
TP_XDP_CPU1_OBSDATA_B0_MBP2_N U2D1             AG10     SKX_EXT_B_BGA1-IC,TBD
TP_XDP_CPU1_OBSDATA_B1_MBP3_N U2D1             AF11     SKX_EXT_B_BGA1-IC,TBD
TP_XDP_CPU1_OBSDATA_B2_MBP4_N U2D1             AA12     SKX_EXT_B_BGA1-IC,TBD
TP_XDP_CPU1_OBSDATA_B3_MBP5_N U2D1             Y11      SKX_EXT_B_BGA1-IC,TBD
TP_XDP_CPU_OBSDATA_C0    J9A3             10       SCONN60_C21100002_SMLF-CONN,C2A
TP_XDP_CPU_OBSDATA_C1    J9A3             12       SCONN60_C21100002_SMLF-CONN,C2A
TP_XDP_CPU_OBSDATA_C2    J9A3             16       SCONN60_C21100002_SMLF-CONN,C2A
TP_XDP_CPU_OBSDATA_C3    J9A3             18       SCONN60_C21100002_SMLF-CONN,C2A
TP_XDP_CPU_OBSDATA_D0    J9A3             28       SCONN60_C21100002_SMLF-CONN,C2A
TP_XDP_CPU_OBSDATA_D1    J9A3             30       SCONN60_C21100002_SMLF-CONN,C2A
TP_XDP_CPU_OBSDATA_D2    J9A3             34       SCONN60_C21100002_SMLF-CONN,C2A
TP_XDP_CPU_OBSDATA_D3    J9A3             36       SCONN60_C21100002_SMLF-CONN,C2A
TP_XDP_CPU_OBSFN_C0      J9A3             4        SCONN60_C21100002_SMLF-CONN,C2A
TP_XDP_OBSDATA_A0        J9A3             9        SCONN60_C21100002_SMLF-CONN,C2A
TP_XDP_OBSDATA_A1        J9A3             11       SCONN60_C21100002_SMLF-CONN,C2A
TP_XDP_OBSDATA_A2        J9A3             15       SCONN60_C21100002_SMLF-CONN,C2A
TP_XDP_OBSDATA_A3        J9A3             17       SCONN60_C21100002_SMLF-CONN,C2A
TP_XDP_OBSDATA_B0        J9A3             27       SCONN60_C21100002_SMLF-CONN,C2A
TP_XDP_OBSDATA_B1        J9A3             29       SCONN60_C21100002_SMLF-CONN,C2A
TP_XDP_OBSDATA_B2        J9A3             33       SCONN60_C21100002_SMLF-CONN,C2A
TP_XDP_OBSDATA_B3        J9A3             35       SCONN60_C21100002_SMLF-CONN,C2A
TP_XDP_OBSFN_B0          J9A3             21       SCONN60_C21100002_SMLF-CONN,C2A
TP_XDP_OBSFN_B1          J9A3             23       SCONN60_C21100002_SMLF-CONN,C2A
UART_BMC_RXD5            R9F53            1        RES_0402-0.0,5%,1/16W,CHIP,G21A
UART_BMC_RXD5            U8D7             J5       LCMXO2_A_256BGA-IC,H63395-001
UART_BMC_RXD5            U9F1             2        FSA3357_SM-IC,C63273-001
UART_BMC_RXD5            U9F4             G1       AST1250_BGA-IC,G85138-002
UART_BMC_TXD5            R9F57            2        RES_0402-0.0,5%,1/16W,CHIP,G21A
UART_BMC_TXD5            U8D7             K6       LCMXO2_A_256BGA-IC,H63395-001
UART_BMC_TXD5            U9F2             2        FSA3357_SM-IC,C63273-001
UART_BMC_TXD5            U9F4             H5       AST1250_BGA-IC,G85138-002
UART_BRIDGE_RXD5         EU9F3            4        PI7C9X1172_QFN-IC,H66899-001
UART_BRIDGE_RXD5         R9F53            2        RES_0402-0.0,5%,1/16W,CHIP,G21A
UART_BRIDGE_TXD5         EU9F3            7        PI7C9X1172_QFN-IC,H66899-001
UART_BRIDGE_TXD5         R9F57            1        RES_0402-0.0,5%,1/16W,CHIP,G21A
UART_MUX_IN_R            R9F25            2        RES_0402-100.0,1%,1/16W,CHIP,GA
UART_MUX_IN_R            U9F1             7        FSA3357_SM-IC,C63273-001
UART_MUX_OUT_R           R9F27            1        RES_0402-0.0,5%,1/16W,CHIP,G21A
UART_MUX_OUT_R           U9F2             7        FSA3357_SM-IC,C63273-001
UNNAMED_202_3D01R5F-GP_I75_2 CTI3             2        SC2K2P50V3KX-GP_SMD-BCG6-SC2K2A
UNNAMED_202_3D01R5F-GP_I75_2 RTI2             2        3D01R5F-GP_SMD-RG5-3D01R5F-GP,A
UNNAMED_202_3D01R5F-GP_I83_2 CTI5             2        SC2K2P50V3KX-GP_SMD-BCG6-SC2K2A
UNNAMED_202_3D01R5F-GP_I83_2 RTI4             2        3D01R5F-GP_SMD-RG5-3D01R5F-GP,A
UNNAMED_203_3D01R5F-GP_I102_2 CTI38            2        SC2K2P50V3KX-GP_SMD-BCG6-SC2K2A
UNNAMED_203_3D01R5F-GP_I102_2 RTI26            2        3D01R5F-GP_SMD-RG5-3D01R5F-GP,A
UNNAMED_203_3D01R5F-GP_I105_2 CTI41            2        SC2K2P50V3KX-GP_SMD-BCG6-SC2K2A
UNNAMED_203_3D01R5F-GP_I105_2 RTI27            2        3D01R5F-GP_SMD-RG5-3D01R5F-GP,A
UNNAMED_204_3D01R5F-GP_I91_2 CTI35            2        SC2K2P50V3KX-GP_SMD-BCG6-SC2K2A
UNNAMED_204_3D01R5F-GP_I91_2 RTI24            2        3D01R5F-GP_SMD-RG5-3D01R5F-GP,A
UNNAMED_205_3D01R5F-GP_I68_2 CTI59            2        SC2K2P50V3KX-GP_SMD-BCG6-SC2K2A
UNNAMED_205_3D01R5F-GP_I68_2 RTI39            2        3D01R5F-GP_SMD-RG5-3D01R5F-GP,A
UNNAMED_207_3D01R5F-GP_I76_2 CTI23            2        SC2K2P50V3KX-GP_SMD-BCG6-SC2K2A
UNNAMED_207_3D01R5F-GP_I76_2 RTI16            2        3D01R5F-GP_SMD-RG5-3D01R5F-GP,A
UNNAMED_207_3D01R5F-GP_I85_2 CTI27            2        SC2K2P50V3KX-GP_SMD-BCG6-SC2K2A
UNNAMED_207_3D01R5F-GP_I85_2 RTI18            2        3D01R5F-GP_SMD-RG5-3D01R5F-GP,A
UNNAMED_208_3D01R5F-GP_I86_2 CTI18            2        SC2K2P50V3KX-GP_SMD-BCG6-SC2K2A
UNNAMED_208_3D01R5F-GP_I86_2 RTI12            2        3D01R5F-GP_SMD-RG5-3D01R5F-GP,A
UNNAMED_208_3D01R5F-GP_I94_2 CTI20            2        SC2K2P50V3KX-GP_SMD-BCG6-SC2K2A
UNNAMED_208_3D01R5F-GP_I94_2 RTI13            2        3D01R5F-GP_SMD-RG5-3D01R5F-GP,A
UNNAMED_209_3D01R5F-GP_I66_2 CTI14            2        SC2K2P50V3KX-GP_SMD-BCG6-SC2K2A
UNNAMED_209_3D01R5F-GP_I66_2 RTI10            2        3D01R5F-GP_SMD-RG5-3D01R5F-GP,A
UNNAMED_210_3D01R5F-GP_I59_2 CTI56            2        SC2K2P50V3KX-GP_SMD-BCG6-SC2K2A
UNNAMED_210_3D01R5F-GP_I59_2 RTI38            2        3D01R5F-GP_SMD-RG5-3D01R5F-GP,A
UNNAMED_212_3D01R5F-GP_I112_2 CTI72            2        SC2K2P50V3KX-GP_SMD-BCG6-SC2K2A
UNNAMED_212_3D01R5F-GP_I112_2 RTI48            2        3D01R5F-GP_SMD-RG5-3D01R5F-GP,A
UNNAMED_214_3D01R5F-GP_I132_2 CTI62            2        SC2K2P50V3KX-GP_SMD-BCG6-SC2K2A
UNNAMED_214_3D01R5F-GP_I132_2 RTI42            2        3D01R5F-GP_SMD-RG5-3D01R5F-GP,A
UNNAMED_216_3D01R5F-GP_I114_2 CTI50            2        SC2K2P50V3KX-GP_SMD-BCG6-SC2K2A
UNNAMED_216_3D01R5F-GP_I114_2 RTI34            2        3D01R5F-GP_SMD-RG5-3D01R5F-GP,A
UNNAMED_216_3D01R5F-GP_I123_2 CTI53            2        SC2K2P50V3KX-GP_SMD-BCG6-SC2K2A
UNNAMED_216_3D01R5F-GP_I123_2 RTI35            2        3D01R5F-GP_SMD-RG5-3D01R5F-GP,A
UNNAMED_219_3D01R5F-GP_I123_2 CTI47            2        SC2K2P50V3KX-GP_SMD-BCG6-SC2K2A
UNNAMED_219_3D01R5F-GP_I123_2 RTI32            2        3D01R5F-GP_SMD-RG5-3D01R5F-GP,A
UNNAMED_219_3D01R5F-GP_I126_2 CTI44            2        SC2K2P50V3KX-GP_SMD-BCG6-SC2K2A
UNNAMED_219_3D01R5F-GP_I126_2 RTI29            2        3D01R5F-GP_SMD-RG5-3D01R5F-GP,A
UNNAMED_224_3D01R5F-GP_I119_2 CTI29            2        SC2K2P50V3KX-GP_SMD-BCG6-SC2K2A
UNNAMED_224_3D01R5F-GP_I119_2 RTI20            2        3D01R5F-GP_SMD-RG5-3D01R5F-GP,A
UNNAMED_224_3D01R5F-GP_I129_2 CTI33            2        SC2K2P50V3KX-GP_SMD-BCG6-SC2K2A
UNNAMED_224_3D01R5F-GP_I129_2 RTI22            2        3D01R5F-GP_SMD-RG5-3D01R5F-GP,A
UNNAMED_227_3D01R5F-GP_I124_1 CTI11            2        SC2K2P50V3KX-GP_SMD-BCG6-SC2K2A
UNNAMED_227_3D01R5F-GP_I124_1 RTI7             1        3D01R5F-GP_SMD-RG5-3D01R5F-GP,A
UNNAMED_227_3D01R5F-GP_I125_1 CTI9             2        SC2K2P50V3KX-GP_SMD-BCG6-SC2K2A
UNNAMED_227_3D01R5F-GP_I125_1 RTI6             1        3D01R5F-GP_SMD-RG5-3D01R5F-GP,A
UNNAMED_236_3D01R5F-GP_I132_2 CTI65            2        SC2K2P50V3KX-GP_SMD-BCG6-SC2K2A
UNNAMED_236_3D01R5F-GP_I132_2 RTI43            2        3D01R5F-GP_SMD-RG5-3D01R5F-GP,A
UNNAMED_236_3D01R5F-GP_I137_2 CTI68            2        SC2K2P50V3KX-GP_SMD-BCG6-SC2K2A
UNNAMED_236_3D01R5F-GP_I137_2 RTI45            2        3D01R5F-GP_SMD-RG5-3D01R5F-GP,A
UPI_CPU0_CPU1_P0P0_DN<0> U2D1             AB9      SKX_EXT_B_BGA1-IC,TBD
UPI_CPU0_CPU1_P0P0_DN<0> U5D1             BG4      SKX_EXT_B_BGA1-IC,TBD
UPI_CPU0_CPU1_P0P0_DN<1> U2D1             AA8      SKX_EXT_B_BGA1-IC,TBD
UPI_CPU0_CPU1_P0P0_DN<1> U5D1             BF3      SKX_EXT_B_BGA1-IC,TBD
UPI_CPU0_CPU1_P0P0_DN<2> U2D1             AB7      SKX_EXT_B_BGA1-IC,TBD
UPI_CPU0_CPU1_P0P0_DN<2> U5D1             BB3      SKX_EXT_B_BGA1-IC,TBD
UPI_CPU0_CPU1_P0P0_DN<3> U2D1             AC6      SKX_EXT_B_BGA1-IC,TBD
UPI_CPU0_CPU1_P0P0_DN<3> U5D1             BA4      SKX_EXT_B_BGA1-IC,TBD
UPI_CPU0_CPU1_P0P0_DN<4> U2D1             AG6      SKX_EXT_B_BGA1-IC,TBD
UPI_CPU0_CPU1_P0P0_DN<4> U5D1             AV5      SKX_EXT_B_BGA1-IC,TBD
UPI_CPU0_CPU1_P0P0_DN<5> U2D1             AF7      SKX_EXT_B_BGA1-IC,TBD
UPI_CPU0_CPU1_P0P0_DN<5> U5D1             AU4      SKX_EXT_B_BGA1-IC,TBD
UPI_CPU0_CPU1_P0P0_DN<6> U2D1             AH7      SKX_EXT_B_BGA1-IC,TBD
UPI_CPU0_CPU1_P0P0_DN<6> U5D1             AT3      SKX_EXT_B_BGA1-IC,TBD
UPI_CPU0_CPU1_P0P0_DN<7> U2D1             AK5      SKX_EXT_B_BGA1-IC,TBD
UPI_CPU0_CPU1_P0P0_DN<7> U5D1             AT1      SKX_EXT_B_BGA1-IC,TBD
UPI_CPU0_CPU1_P0P0_DN<8> U2D1             AM7      SKX_EXT_B_BGA1-IC,TBD
UPI_CPU0_CPU1_P0P0_DN<8> U5D1             AN4      SKX_EXT_B_BGA1-IC,TBD
UPI_CPU0_CPU1_P0P0_DN<9> U2D1             AL8      SKX_EXT_B_BGA1-IC,TBD
UPI_CPU0_CPU1_P0P0_DN<9> U5D1             AM3      SKX_EXT_B_BGA1-IC,TBD
UPI_CPU0_CPU1_P0P0_DN<10> U2D1             AP7      SKX_EXT_B_BGA1-IC,TBD
UPI_CPU0_CPU1_P0P0_DN<10> U5D1             AL2      SKX_EXT_B_BGA1-IC,TBD
UPI_CPU0_CPU1_P0P0_DN<11> U2D1             AU8      SKX_EXT_B_BGA1-IC,TBD
UPI_CPU0_CPU1_P0P0_DN<11> U5D1             AH3      SKX_EXT_B_BGA1-IC,TBD
UPI_CPU0_CPU1_P0P0_DN<12> U2D1             AU10     SKX_EXT_B_BGA1-IC,TBD
UPI_CPU0_CPU1_P0P0_DN<12> U5D1             AE2      SKX_EXT_B_BGA1-IC,TBD
UPI_CPU0_CPU1_P0P0_DN<13> U2D1             BA8      SKX_EXT_B_BGA1-IC,TBD
UPI_CPU0_CPU1_P0P0_DN<13> U5D1             AG4      SKX_EXT_B_BGA1-IC,TBD
UPI_CPU0_CPU1_P0P0_DN<14> U2D1             BB7      SKX_EXT_B_BGA1-IC,TBD
UPI_CPU0_CPU1_P0P0_DN<14> U5D1             AC2      SKX_EXT_B_BGA1-IC,TBD
UPI_CPU0_CPU1_P0P0_DN<15> U2D1             BD7      SKX_EXT_B_BGA1-IC,TBD
UPI_CPU0_CPU1_P0P0_DN<15> U5D1             AB3      SKX_EXT_B_BGA1-IC,TBD
UPI_CPU0_CPU1_P0P0_DN<16> U2D1             AW8      SKX_EXT_B_BGA1-IC,TBD
UPI_CPU0_CPU1_P0P0_DN<16> U5D1             Y1       SKX_EXT_B_BGA1-IC,TBD
UPI_CPU0_CPU1_P0P0_DN<17> U2D1             AY9      SKX_EXT_B_BGA1-IC,TBD
UPI_CPU0_CPU1_P0P0_DN<17> U5D1             V3       SKX_EXT_B_BGA1-IC,TBD
UPI_CPU0_CPU1_P0P0_DN<18> U2D1             BC10     SKX_EXT_B_BGA1-IC,TBD
UPI_CPU0_CPU1_P0P0_DN<18> U5D1             P1       SKX_EXT_B_BGA1-IC,TBD
UPI_CPU0_CPU1_P0P0_DN<19> U2D1             BA10     SKX_EXT_B_BGA1-IC,TBD
UPI_CPU0_CPU1_P0P0_DN<19> U5D1             N2       SKX_EXT_B_BGA1-IC,TBD
UPI_CPU0_CPU1_P0P0_DP<0> U2D1             AC10     SKX_EXT_B_BGA1-IC,TBD
UPI_CPU0_CPU1_P0P0_DP<0> U5D1             BH3      SKX_EXT_B_BGA1-IC,TBD
UPI_CPU0_CPU1_P0P0_DP<1> U2D1             AC8      SKX_EXT_B_BGA1-IC,TBD
UPI_CPU0_CPU1_P0P0_DP<1> U5D1             BD3      SKX_EXT_B_BGA1-IC,TBD
UPI_CPU0_CPU1_P0P0_DP<2> U2D1             AA6      SKX_EXT_B_BGA1-IC,TBD
UPI_CPU0_CPU1_P0P0_DP<2> U5D1             BC2      SKX_EXT_B_BGA1-IC,TBD
UPI_CPU0_CPU1_P0P0_DP<3> U2D1             AD5      SKX_EXT_B_BGA1-IC,TBD
UPI_CPU0_CPU1_P0P0_DP<3> U5D1             AY3      SKX_EXT_B_BGA1-IC,TBD
UPI_CPU0_CPU1_P0P0_DP<4> U2D1             AE6      SKX_EXT_B_BGA1-IC,TBD
UPI_CPU0_CPU1_P0P0_DP<4> U5D1             AW4      SKX_EXT_B_BGA1-IC,TBD
UPI_CPU0_CPU1_P0P0_DP<5> U2D1             AG8      SKX_EXT_B_BGA1-IC,TBD
UPI_CPU0_CPU1_P0P0_DP<5> U5D1             AR4      SKX_EXT_B_BGA1-IC,TBD
UPI_CPU0_CPU1_P0P0_DP<6> U2D1             AJ6      SKX_EXT_B_BGA1-IC,TBD
UPI_CPU0_CPU1_P0P0_DP<6> U5D1             AR2      SKX_EXT_B_BGA1-IC,TBD
UPI_CPU0_CPU1_P0P0_DP<7> U2D1             AL6      SKX_EXT_B_BGA1-IC,TBD
UPI_CPU0_CPU1_P0P0_DP<7> U5D1             AP1      SKX_EXT_B_BGA1-IC,TBD
UPI_CPU0_CPU1_P0P0_DP<8> U2D1             AK7      SKX_EXT_B_BGA1-IC,TBD
UPI_CPU0_CPU1_P0P0_DP<8> U5D1             AP3      SKX_EXT_B_BGA1-IC,TBD
UPI_CPU0_CPU1_P0P0_DP<9> U2D1             AM9      SKX_EXT_B_BGA1-IC,TBD
UPI_CPU0_CPU1_P0P0_DP<9> U5D1             AK3      SKX_EXT_B_BGA1-IC,TBD
UPI_CPU0_CPU1_P0P0_DP<10> U2D1             AN8      SKX_EXT_B_BGA1-IC,TBD
UPI_CPU0_CPU1_P0P0_DP<10> U5D1             AK1      SKX_EXT_B_BGA1-IC,TBD
UPI_CPU0_CPU1_P0P0_DP<11> U2D1             AR8      SKX_EXT_B_BGA1-IC,TBD
UPI_CPU0_CPU1_P0P0_DP<11> U5D1             AJ2      SKX_EXT_B_BGA1-IC,TBD
UPI_CPU0_CPU1_P0P0_DP<12> U2D1             AT9      SKX_EXT_B_BGA1-IC,TBD
UPI_CPU0_CPU1_P0P0_DP<12> U5D1             AG2      SKX_EXT_B_BGA1-IC,TBD
UPI_CPU0_CPU1_P0P0_DP<13> U2D1             AY7      SKX_EXT_B_BGA1-IC,TBD
UPI_CPU0_CPU1_P0P0_DP<13> U5D1             AF3      SKX_EXT_B_BGA1-IC,TBD
UPI_CPU0_CPU1_P0P0_DP<14> U2D1             BC6      SKX_EXT_B_BGA1-IC,TBD
UPI_CPU0_CPU1_P0P0_DP<14> U5D1             AD1      SKX_EXT_B_BGA1-IC,TBD
UPI_CPU0_CPU1_P0P0_DP<15> U2D1             BF7      SKX_EXT_B_BGA1-IC,TBD
UPI_CPU0_CPU1_P0P0_DP<15> U5D1             AA2      SKX_EXT_B_BGA1-IC,TBD
UPI_CPU0_CPU1_P0P0_DP<16> U2D1             AV9      SKX_EXT_B_BGA1-IC,TBD
UPI_CPU0_CPU1_P0P0_DP<16> U5D1             W2       SKX_EXT_B_BGA1-IC,TBD
UPI_CPU0_CPU1_P0P0_DP<17> U2D1             BB9      SKX_EXT_B_BGA1-IC,TBD
UPI_CPU0_CPU1_P0P0_DP<17> U5D1             Y3       SKX_EXT_B_BGA1-IC,TBD
UPI_CPU0_CPU1_P0P0_DP<18> U2D1             BD9      SKX_EXT_B_BGA1-IC,TBD
UPI_CPU0_CPU1_P0P0_DP<18> U5D1             T1       SKX_EXT_B_BGA1-IC,TBD
UPI_CPU0_CPU1_P0P0_DP<19> U2D1             BB11     SKX_EXT_B_BGA1-IC,TBD
UPI_CPU0_CPU1_P0P0_DP<19> U5D1             M1       SKX_EXT_B_BGA1-IC,TBD
UPI_CPU0_CPU1_P1P1_DN<0> U2D1             R6       SKX_EXT_B_BGA1-IC,TBD
UPI_CPU0_CPU1_P1P1_DN<0> U5D1             H21      SKX_EXT_B_BGA1-IC,TBD
UPI_CPU0_CPU1_P1P1_DN<1> U2D1             P7       SKX_EXT_B_BGA1-IC,TBD
UPI_CPU0_CPU1_P1P1_DN<1> U5D1             F21      SKX_EXT_B_BGA1-IC,TBD
UPI_CPU0_CPU1_P1P1_DN<2> U2D1             V7       SKX_EXT_B_BGA1-IC,TBD
UPI_CPU0_CPU1_P1P1_DN<2> U5D1             J20      SKX_EXT_B_BGA1-IC,TBD
UPI_CPU0_CPU1_P1P1_DN<3> U2D1             T9       SKX_EXT_B_BGA1-IC,TBD
UPI_CPU0_CPU1_P1P1_DN<3> U5D1             G18      SKX_EXT_B_BGA1-IC,TBD
UPI_CPU0_CPU1_P1P1_DN<4> U2D1             P9       SKX_EXT_B_BGA1-IC,TBD
UPI_CPU0_CPU1_P1P1_DN<4> U5D1             K19      SKX_EXT_B_BGA1-IC,TBD
UPI_CPU0_CPU1_P1P1_DN<5> U2D1             R10      SKX_EXT_B_BGA1-IC,TBD
UPI_CPU0_CPU1_P1P1_DN<5> U5D1             H17      SKX_EXT_B_BGA1-IC,TBD
UPI_CPU0_CPU1_P1P1_DN<6> U2D1             U12      SKX_EXT_B_BGA1-IC,TBD
UPI_CPU0_CPU1_P1P1_DN<6> U5D1             F15      SKX_EXT_B_BGA1-IC,TBD
UPI_CPU0_CPU1_P1P1_DN<7> U2D1             L12      SKX_EXT_B_BGA1-IC,TBD
UPI_CPU0_CPU1_P1P1_DN<7> U5D1             D15      SKX_EXT_B_BGA1-IC,TBD
UPI_CPU0_CPU1_P1P1_DN<8> U2D1             M13      SKX_EXT_B_BGA1-IC,TBD
UPI_CPU0_CPU1_P1P1_DN<8> U5D1             G14      SKX_EXT_B_BGA1-IC,TBD
UPI_CPU0_CPU1_P1P1_DN<9> U2D1             R12      SKX_EXT_B_BGA1-IC,TBD
UPI_CPU0_CPU1_P1P1_DN<9> U5D1             E12      SKX_EXT_B_BGA1-IC,TBD
UPI_CPU0_CPU1_P1P1_DN<10> U2D1             R16      SKX_EXT_B_BGA1-IC,TBD
UPI_CPU0_CPU1_P1P1_DN<10> U5D1             G10      SKX_EXT_B_BGA1-IC,TBD
UPI_CPU0_CPU1_P1P1_DN<11> U2D1             N16      SKX_EXT_B_BGA1-IC,TBD
UPI_CPU0_CPU1_P1P1_DN<11> U5D1             F11      SKX_EXT_B_BGA1-IC,TBD
UPI_CPU0_CPU1_P1P1_DN<12> U2D1             W16      SKX_EXT_B_BGA1-IC,TBD
UPI_CPU0_CPU1_P1P1_DN<12> U5D1             D9       SKX_EXT_B_BGA1-IC,TBD
UPI_CPU0_CPU1_P1P1_DN<13> U2D1             V17      SKX_EXT_B_BGA1-IC,TBD
UPI_CPU0_CPU1_P1P1_DN<13> U5D1             K9       SKX_EXT_B_BGA1-IC,TBD
UPI_CPU0_CPU1_P1P1_DN<14> U2D1             R20      SKX_EXT_B_BGA1-IC,TBD
UPI_CPU0_CPU1_P1P1_DN<14> U5D1             H7       SKX_EXT_B_BGA1-IC,TBD
UPI_CPU0_CPU1_P1P1_DN<15> U2D1             U18      SKX_EXT_B_BGA1-IC,TBD
UPI_CPU0_CPU1_P1P1_DN<15> U5D1             G6       SKX_EXT_B_BGA1-IC,TBD
UPI_CPU0_CPU1_P1P1_DN<16> U2D1             P21      SKX_EXT_B_BGA1-IC,TBD
UPI_CPU0_CPU1_P1P1_DN<16> U5D1             J6       SKX_EXT_B_BGA1-IC,TBD
UPI_CPU0_CPU1_P1P1_DN<17> U2D1             V19      SKX_EXT_B_BGA1-IC,TBD
UPI_CPU0_CPU1_P1P1_DN<17> U5D1             K5       SKX_EXT_B_BGA1-IC,TBD
UPI_CPU0_CPU1_P1P1_DN<18> U2D1             W20      SKX_EXT_B_BGA1-IC,TBD
UPI_CPU0_CPU1_P1P1_DN<18> U5D1             L4       SKX_EXT_B_BGA1-IC,TBD
UPI_CPU0_CPU1_P1P1_DN<19> U2D1             AA20     SKX_EXT_B_BGA1-IC,TBD
UPI_CPU0_CPU1_P1P1_DN<19> U5D1             M3       SKX_EXT_B_BGA1-IC,TBD
UPI_CPU0_CPU1_P1P1_DP<0> U2D1             T5       SKX_EXT_B_BGA1-IC,TBD
UPI_CPU0_CPU1_P1P1_DP<0> U5D1             K21      SKX_EXT_B_BGA1-IC,TBD
UPI_CPU0_CPU1_P1P1_DP<1> U2D1             T7       SKX_EXT_B_BGA1-IC,TBD
UPI_CPU0_CPU1_P1P1_DP<1> U5D1             G20      SKX_EXT_B_BGA1-IC,TBD
UPI_CPU0_CPU1_P1P1_DP<2> U2D1             U8       SKX_EXT_B_BGA1-IC,TBD
UPI_CPU0_CPU1_P1P1_DP<2> U5D1             H19      SKX_EXT_B_BGA1-IC,TBD
UPI_CPU0_CPU1_P1P1_DP<3> U2D1             R8       SKX_EXT_B_BGA1-IC,TBD
UPI_CPU0_CPU1_P1P1_DP<3> U5D1             J18      SKX_EXT_B_BGA1-IC,TBD
UPI_CPU0_CPU1_P1P1_DP<4> U2D1             N10      SKX_EXT_B_BGA1-IC,TBD
UPI_CPU0_CPU1_P1P1_DP<4> U5D1             L18      SKX_EXT_B_BGA1-IC,TBD
UPI_CPU0_CPU1_P1P1_DP<5> U2D1             U10      SKX_EXT_B_BGA1-IC,TBD
UPI_CPU0_CPU1_P1P1_DP<5> U5D1             G16      SKX_EXT_B_BGA1-IC,TBD
UPI_CPU0_CPU1_P1P1_DP<6> U2D1             T11      SKX_EXT_B_BGA1-IC,TBD
UPI_CPU0_CPU1_P1P1_DP<6> U5D1             H15      SKX_EXT_B_BGA1-IC,TBD
UPI_CPU0_CPU1_P1P1_DP<7> U2D1             N12      SKX_EXT_B_BGA1-IC,TBD
UPI_CPU0_CPU1_P1P1_DP<7> U5D1             E14      SKX_EXT_B_BGA1-IC,TBD
UPI_CPU0_CPU1_P1P1_DP<8> U2D1             N14      SKX_EXT_B_BGA1-IC,TBD
UPI_CPU0_CPU1_P1P1_DP<8> U5D1             F13      SKX_EXT_B_BGA1-IC,TBD
UPI_CPU0_CPU1_P1P1_DP<9> U2D1             P13      SKX_EXT_B_BGA1-IC,TBD
UPI_CPU0_CPU1_P1P1_DP<9> U5D1             G12      SKX_EXT_B_BGA1-IC,TBD
UPI_CPU0_CPU1_P1P1_DP<10> U2D1             T15      SKX_EXT_B_BGA1-IC,TBD
UPI_CPU0_CPU1_P1P1_DP<10> U5D1             H9       SKX_EXT_B_BGA1-IC,TBD
UPI_CPU0_CPU1_P1P1_DP<11> U2D1             P17      SKX_EXT_B_BGA1-IC,TBD
UPI_CPU0_CPU1_P1P1_DP<11> U5D1             E10      SKX_EXT_B_BGA1-IC,TBD
UPI_CPU0_CPU1_P1P1_DP<12> U2D1             U16      SKX_EXT_B_BGA1-IC,TBD
UPI_CPU0_CPU1_P1P1_DP<12> U5D1             F9       SKX_EXT_B_BGA1-IC,TBD
UPI_CPU0_CPU1_P1P1_DP<13> U2D1             W18      SKX_EXT_B_BGA1-IC,TBD
UPI_CPU0_CPU1_P1P1_DP<13> U5D1             J8       SKX_EXT_B_BGA1-IC,TBD
UPI_CPU0_CPU1_P1P1_DP<14> U2D1             P19      SKX_EXT_B_BGA1-IC,TBD
UPI_CPU0_CPU1_P1P1_DP<14> U5D1             K7       SKX_EXT_B_BGA1-IC,TBD
UPI_CPU0_CPU1_P1P1_DP<15> U2D1             T19      SKX_EXT_B_BGA1-IC,TBD
UPI_CPU0_CPU1_P1P1_DP<15> U5D1             F7       SKX_EXT_B_BGA1-IC,TBD
UPI_CPU0_CPU1_P1P1_DP<16> U2D1             T21      SKX_EXT_B_BGA1-IC,TBD
UPI_CPU0_CPU1_P1P1_DP<16> U5D1             H5       SKX_EXT_B_BGA1-IC,TBD
UPI_CPU0_CPU1_P1P1_DP<17> U2D1             Y19      SKX_EXT_B_BGA1-IC,TBD
UPI_CPU0_CPU1_P1P1_DP<17> U5D1             M5       SKX_EXT_B_BGA1-IC,TBD
UPI_CPU0_CPU1_P1P1_DP<18> U2D1             Y21      SKX_EXT_B_BGA1-IC,TBD
UPI_CPU0_CPU1_P1P1_DP<18> U5D1             K3       SKX_EXT_B_BGA1-IC,TBD
UPI_CPU0_CPU1_P1P1_DP<19> U2D1             AB19     SKX_EXT_B_BGA1-IC,TBD
UPI_CPU0_CPU1_P1P1_DP<19> U5D1             P3       SKX_EXT_B_BGA1-IC,TBD
UPI_CPU1_CPU0_P0P0_DN<0> U2D1             M1       SKX_EXT_B_BGA1-IC,TBD
UPI_CPU1_CPU0_P0P0_DN<0> U5D1             BB11     SKX_EXT_B_BGA1-IC,TBD
UPI_CPU1_CPU0_P0P0_DN<1> U2D1             T1       SKX_EXT_B_BGA1-IC,TBD
UPI_CPU1_CPU0_P0P0_DN<1> U5D1             BD9      SKX_EXT_B_BGA1-IC,TBD
UPI_CPU1_CPU0_P0P0_DN<2> U2D1             V3       SKX_EXT_B_BGA1-IC,TBD
UPI_CPU1_CPU0_P0P0_DN<2> U5D1             AY9      SKX_EXT_B_BGA1-IC,TBD
UPI_CPU1_CPU0_P0P0_DN<3> U2D1             Y1       SKX_EXT_B_BGA1-IC,TBD
UPI_CPU1_CPU0_P0P0_DN<3> U5D1             AW8      SKX_EXT_B_BGA1-IC,TBD
UPI_CPU1_CPU0_P0P0_DN<4> U2D1             AB3      SKX_EXT_B_BGA1-IC,TBD
UPI_CPU1_CPU0_P0P0_DN<4> U5D1             BD7      SKX_EXT_B_BGA1-IC,TBD
UPI_CPU1_CPU0_P0P0_DN<5> U2D1             AD1      SKX_EXT_B_BGA1-IC,TBD
UPI_CPU1_CPU0_P0P0_DN<5> U5D1             BC6      SKX_EXT_B_BGA1-IC,TBD
UPI_CPU1_CPU0_P0P0_DN<6> U2D1             AG4      SKX_EXT_B_BGA1-IC,TBD
UPI_CPU1_CPU0_P0P0_DN<6> U5D1             BA8      SKX_EXT_B_BGA1-IC,TBD
UPI_CPU1_CPU0_P0P0_DN<7> U2D1             AE2      SKX_EXT_B_BGA1-IC,TBD
UPI_CPU1_CPU0_P0P0_DN<7> U5D1             AU10     SKX_EXT_B_BGA1-IC,TBD
UPI_CPU1_CPU0_P0P0_DN<8> U2D1             AJ2      SKX_EXT_B_BGA1-IC,TBD
UPI_CPU1_CPU0_P0P0_DN<8> U5D1             AR8      SKX_EXT_B_BGA1-IC,TBD
UPI_CPU1_CPU0_P0P0_DN<9> U2D1             AL2      SKX_EXT_B_BGA1-IC,TBD
UPI_CPU1_CPU0_P0P0_DN<9> U5D1             AP7      SKX_EXT_B_BGA1-IC,TBD
UPI_CPU1_CPU0_P0P0_DN<10> U2D1             AK3      SKX_EXT_B_BGA1-IC,TBD
UPI_CPU1_CPU0_P0P0_DN<10> U5D1             AM9      SKX_EXT_B_BGA1-IC,TBD
UPI_CPU1_CPU0_P0P0_DN<11> U2D1             AP3      SKX_EXT_B_BGA1-IC,TBD
UPI_CPU1_CPU0_P0P0_DN<11> U5D1             AK7      SKX_EXT_B_BGA1-IC,TBD
UPI_CPU1_CPU0_P0P0_DN<12> U2D1             AP1      SKX_EXT_B_BGA1-IC,TBD
UPI_CPU1_CPU0_P0P0_DN<12> U5D1             AL6      SKX_EXT_B_BGA1-IC,TBD
UPI_CPU1_CPU0_P0P0_DN<13> U2D1             AR2      SKX_EXT_B_BGA1-IC,TBD
UPI_CPU1_CPU0_P0P0_DN<13> U5D1             AJ6      SKX_EXT_B_BGA1-IC,TBD
UPI_CPU1_CPU0_P0P0_DN<14> U2D1             AR4      SKX_EXT_B_BGA1-IC,TBD
UPI_CPU1_CPU0_P0P0_DN<14> U5D1             AG8      SKX_EXT_B_BGA1-IC,TBD
UPI_CPU1_CPU0_P0P0_DN<15> U2D1             AW4      SKX_EXT_B_BGA1-IC,TBD
UPI_CPU1_CPU0_P0P0_DN<15> U5D1             AE6      SKX_EXT_B_BGA1-IC,TBD
UPI_CPU1_CPU0_P0P0_DN<16> U2D1             AY3      SKX_EXT_B_BGA1-IC,TBD
UPI_CPU1_CPU0_P0P0_DN<16> U5D1             AD5      SKX_EXT_B_BGA1-IC,TBD
UPI_CPU1_CPU0_P0P0_DN<17> U2D1             BB3      SKX_EXT_B_BGA1-IC,TBD
UPI_CPU1_CPU0_P0P0_DN<17> U5D1             AB7      SKX_EXT_B_BGA1-IC,TBD
UPI_CPU1_CPU0_P0P0_DN<18> U2D1             BF3      SKX_EXT_B_BGA1-IC,TBD
UPI_CPU1_CPU0_P0P0_DN<18> U5D1             AA8      SKX_EXT_B_BGA1-IC,TBD
UPI_CPU1_CPU0_P0P0_DN<19> U2D1             BH3      SKX_EXT_B_BGA1-IC,TBD
UPI_CPU1_CPU0_P0P0_DN<19> U5D1             AC10     SKX_EXT_B_BGA1-IC,TBD
UPI_CPU1_CPU0_P0P0_DP<0> U2D1             N2       SKX_EXT_B_BGA1-IC,TBD
UPI_CPU1_CPU0_P0P0_DP<0> U5D1             BA10     SKX_EXT_B_BGA1-IC,TBD
UPI_CPU1_CPU0_P0P0_DP<1> U2D1             P1       SKX_EXT_B_BGA1-IC,TBD
UPI_CPU1_CPU0_P0P0_DP<1> U5D1             BC10     SKX_EXT_B_BGA1-IC,TBD
UPI_CPU1_CPU0_P0P0_DP<2> U2D1             Y3       SKX_EXT_B_BGA1-IC,TBD
UPI_CPU1_CPU0_P0P0_DP<2> U5D1             BB9      SKX_EXT_B_BGA1-IC,TBD
UPI_CPU1_CPU0_P0P0_DP<3> U2D1             W2       SKX_EXT_B_BGA1-IC,TBD
UPI_CPU1_CPU0_P0P0_DP<3> U5D1             AV9      SKX_EXT_B_BGA1-IC,TBD
UPI_CPU1_CPU0_P0P0_DP<4> U2D1             AA2      SKX_EXT_B_BGA1-IC,TBD
UPI_CPU1_CPU0_P0P0_DP<4> U5D1             BF7      SKX_EXT_B_BGA1-IC,TBD
UPI_CPU1_CPU0_P0P0_DP<5> U2D1             AC2      SKX_EXT_B_BGA1-IC,TBD
UPI_CPU1_CPU0_P0P0_DP<5> U5D1             BB7      SKX_EXT_B_BGA1-IC,TBD
UPI_CPU1_CPU0_P0P0_DP<6> U2D1             AF3      SKX_EXT_B_BGA1-IC,TBD
UPI_CPU1_CPU0_P0P0_DP<6> U5D1             AY7      SKX_EXT_B_BGA1-IC,TBD
UPI_CPU1_CPU0_P0P0_DP<7> U2D1             AG2      SKX_EXT_B_BGA1-IC,TBD
UPI_CPU1_CPU0_P0P0_DP<7> U5D1             AT9      SKX_EXT_B_BGA1-IC,TBD
UPI_CPU1_CPU0_P0P0_DP<8> U2D1             AH3      SKX_EXT_B_BGA1-IC,TBD
UPI_CPU1_CPU0_P0P0_DP<8> U5D1             AU8      SKX_EXT_B_BGA1-IC,TBD
UPI_CPU1_CPU0_P0P0_DP<9> U2D1             AK1      SKX_EXT_B_BGA1-IC,TBD
UPI_CPU1_CPU0_P0P0_DP<9> U5D1             AN8      SKX_EXT_B_BGA1-IC,TBD
UPI_CPU1_CPU0_P0P0_DP<10> U2D1             AM3      SKX_EXT_B_BGA1-IC,TBD
UPI_CPU1_CPU0_P0P0_DP<10> U5D1             AL8      SKX_EXT_B_BGA1-IC,TBD
UPI_CPU1_CPU0_P0P0_DP<11> U2D1             AN4      SKX_EXT_B_BGA1-IC,TBD
UPI_CPU1_CPU0_P0P0_DP<11> U5D1             AM7      SKX_EXT_B_BGA1-IC,TBD
UPI_CPU1_CPU0_P0P0_DP<12> U2D1             AT1      SKX_EXT_B_BGA1-IC,TBD
UPI_CPU1_CPU0_P0P0_DP<12> U5D1             AK5      SKX_EXT_B_BGA1-IC,TBD
UPI_CPU1_CPU0_P0P0_DP<13> U2D1             AT3      SKX_EXT_B_BGA1-IC,TBD
UPI_CPU1_CPU0_P0P0_DP<13> U5D1             AH7      SKX_EXT_B_BGA1-IC,TBD
UPI_CPU1_CPU0_P0P0_DP<14> U2D1             AU4      SKX_EXT_B_BGA1-IC,TBD
UPI_CPU1_CPU0_P0P0_DP<14> U5D1             AF7      SKX_EXT_B_BGA1-IC,TBD
UPI_CPU1_CPU0_P0P0_DP<15> U2D1             AV5      SKX_EXT_B_BGA1-IC,TBD
UPI_CPU1_CPU0_P0P0_DP<15> U5D1             AG6      SKX_EXT_B_BGA1-IC,TBD
UPI_CPU1_CPU0_P0P0_DP<16> U2D1             BA4      SKX_EXT_B_BGA1-IC,TBD
UPI_CPU1_CPU0_P0P0_DP<16> U5D1             AC6      SKX_EXT_B_BGA1-IC,TBD
UPI_CPU1_CPU0_P0P0_DP<17> U2D1             BC2      SKX_EXT_B_BGA1-IC,TBD
UPI_CPU1_CPU0_P0P0_DP<17> U5D1             AA6      SKX_EXT_B_BGA1-IC,TBD
UPI_CPU1_CPU0_P0P0_DP<18> U2D1             BD3      SKX_EXT_B_BGA1-IC,TBD
UPI_CPU1_CPU0_P0P0_DP<18> U5D1             AC8      SKX_EXT_B_BGA1-IC,TBD
UPI_CPU1_CPU0_P0P0_DP<19> U2D1             BG4      SKX_EXT_B_BGA1-IC,TBD
UPI_CPU1_CPU0_P0P0_DP<19> U5D1             AB9      SKX_EXT_B_BGA1-IC,TBD
UPI_CPU1_CPU0_P1P1_DN<0> U2D1             P3       SKX_EXT_B_BGA1-IC,TBD
UPI_CPU1_CPU0_P1P1_DN<0> U5D1             AB19     SKX_EXT_B_BGA1-IC,TBD
UPI_CPU1_CPU0_P1P1_DN<1> U2D1             K3       SKX_EXT_B_BGA1-IC,TBD
UPI_CPU1_CPU0_P1P1_DN<1> U5D1             Y21      SKX_EXT_B_BGA1-IC,TBD
UPI_CPU1_CPU0_P1P1_DN<2> U2D1             K5       SKX_EXT_B_BGA1-IC,TBD
UPI_CPU1_CPU0_P1P1_DN<2> U5D1             V19      SKX_EXT_B_BGA1-IC,TBD
UPI_CPU1_CPU0_P1P1_DN<3> U2D1             J6       SKX_EXT_B_BGA1-IC,TBD
UPI_CPU1_CPU0_P1P1_DN<3> U5D1             P21      SKX_EXT_B_BGA1-IC,TBD
UPI_CPU1_CPU0_P1P1_DN<4> U2D1             G6       SKX_EXT_B_BGA1-IC,TBD
UPI_CPU1_CPU0_P1P1_DN<4> U5D1             U18      SKX_EXT_B_BGA1-IC,TBD
UPI_CPU1_CPU0_P1P1_DN<5> U2D1             H7       SKX_EXT_B_BGA1-IC,TBD
UPI_CPU1_CPU0_P1P1_DN<5> U5D1             R20      SKX_EXT_B_BGA1-IC,TBD
UPI_CPU1_CPU0_P1P1_DN<6> U2D1             J8       SKX_EXT_B_BGA1-IC,TBD
UPI_CPU1_CPU0_P1P1_DN<6> U5D1             W18      SKX_EXT_B_BGA1-IC,TBD
UPI_CPU1_CPU0_P1P1_DN<7> U2D1             F9       SKX_EXT_B_BGA1-IC,TBD
UPI_CPU1_CPU0_P1P1_DN<7> U5D1             U16      SKX_EXT_B_BGA1-IC,TBD
UPI_CPU1_CPU0_P1P1_DN<8> U2D1             E10      SKX_EXT_B_BGA1-IC,TBD
UPI_CPU1_CPU0_P1P1_DN<8> U5D1             P17      SKX_EXT_B_BGA1-IC,TBD
UPI_CPU1_CPU0_P1P1_DN<9> U2D1             G10      SKX_EXT_B_BGA1-IC,TBD
UPI_CPU1_CPU0_P1P1_DN<9> U5D1             R16      SKX_EXT_B_BGA1-IC,TBD
UPI_CPU1_CPU0_P1P1_DN<10> U2D1             E12      SKX_EXT_B_BGA1-IC,TBD
UPI_CPU1_CPU0_P1P1_DN<10> U5D1             R12      SKX_EXT_B_BGA1-IC,TBD
UPI_CPU1_CPU0_P1P1_DN<11> U2D1             F13      SKX_EXT_B_BGA1-IC,TBD
UPI_CPU1_CPU0_P1P1_DN<11> U5D1             N14      SKX_EXT_B_BGA1-IC,TBD
UPI_CPU1_CPU0_P1P1_DN<12> U2D1             D15      SKX_EXT_B_BGA1-IC,TBD
UPI_CPU1_CPU0_P1P1_DN<12> U5D1             L12      SKX_EXT_B_BGA1-IC,TBD
UPI_CPU1_CPU0_P1P1_DN<13> U2D1             F15      SKX_EXT_B_BGA1-IC,TBD
UPI_CPU1_CPU0_P1P1_DN<13> U5D1             U12      SKX_EXT_B_BGA1-IC,TBD
UPI_CPU1_CPU0_P1P1_DN<14> U2D1             H17      SKX_EXT_B_BGA1-IC,TBD
UPI_CPU1_CPU0_P1P1_DN<14> U5D1             R10      SKX_EXT_B_BGA1-IC,TBD
UPI_CPU1_CPU0_P1P1_DN<15> U2D1             K19      SKX_EXT_B_BGA1-IC,TBD
UPI_CPU1_CPU0_P1P1_DN<15> U5D1             P9       SKX_EXT_B_BGA1-IC,TBD
UPI_CPU1_CPU0_P1P1_DN<16> U2D1             G18      SKX_EXT_B_BGA1-IC,TBD
UPI_CPU1_CPU0_P1P1_DN<16> U5D1             T9       SKX_EXT_B_BGA1-IC,TBD
UPI_CPU1_CPU0_P1P1_DN<17> U2D1             J20      SKX_EXT_B_BGA1-IC,TBD
UPI_CPU1_CPU0_P1P1_DN<17> U5D1             V7       SKX_EXT_B_BGA1-IC,TBD
UPI_CPU1_CPU0_P1P1_DN<18> U2D1             G20      SKX_EXT_B_BGA1-IC,TBD
UPI_CPU1_CPU0_P1P1_DN<18> U5D1             P7       SKX_EXT_B_BGA1-IC,TBD
UPI_CPU1_CPU0_P1P1_DN<19> U2D1             K21      SKX_EXT_B_BGA1-IC,TBD
UPI_CPU1_CPU0_P1P1_DN<19> U5D1             T5       SKX_EXT_B_BGA1-IC,TBD
UPI_CPU1_CPU0_P1P1_DP<0> U2D1             M3       SKX_EXT_B_BGA1-IC,TBD
UPI_CPU1_CPU0_P1P1_DP<0> U5D1             AA20     SKX_EXT_B_BGA1-IC,TBD
UPI_CPU1_CPU0_P1P1_DP<1> U2D1             L4       SKX_EXT_B_BGA1-IC,TBD
UPI_CPU1_CPU0_P1P1_DP<1> U5D1             W20      SKX_EXT_B_BGA1-IC,TBD
UPI_CPU1_CPU0_P1P1_DP<2> U2D1             M5       SKX_EXT_B_BGA1-IC,TBD
UPI_CPU1_CPU0_P1P1_DP<2> U5D1             Y19      SKX_EXT_B_BGA1-IC,TBD
UPI_CPU1_CPU0_P1P1_DP<3> U2D1             H5       SKX_EXT_B_BGA1-IC,TBD
UPI_CPU1_CPU0_P1P1_DP<3> U5D1             T21      SKX_EXT_B_BGA1-IC,TBD
UPI_CPU1_CPU0_P1P1_DP<4> U2D1             F7       SKX_EXT_B_BGA1-IC,TBD
UPI_CPU1_CPU0_P1P1_DP<4> U5D1             T19      SKX_EXT_B_BGA1-IC,TBD
UPI_CPU1_CPU0_P1P1_DP<5> U2D1             K7       SKX_EXT_B_BGA1-IC,TBD
UPI_CPU1_CPU0_P1P1_DP<5> U5D1             P19      SKX_EXT_B_BGA1-IC,TBD
UPI_CPU1_CPU0_P1P1_DP<6> U2D1             K9       SKX_EXT_B_BGA1-IC,TBD
UPI_CPU1_CPU0_P1P1_DP<6> U5D1             V17      SKX_EXT_B_BGA1-IC,TBD
UPI_CPU1_CPU0_P1P1_DP<7> U2D1             D9       SKX_EXT_B_BGA1-IC,TBD
UPI_CPU1_CPU0_P1P1_DP<7> U5D1             W16      SKX_EXT_B_BGA1-IC,TBD
UPI_CPU1_CPU0_P1P1_DP<8> U2D1             F11      SKX_EXT_B_BGA1-IC,TBD
UPI_CPU1_CPU0_P1P1_DP<8> U5D1             N16      SKX_EXT_B_BGA1-IC,TBD
UPI_CPU1_CPU0_P1P1_DP<9> U2D1             H9       SKX_EXT_B_BGA1-IC,TBD
UPI_CPU1_CPU0_P1P1_DP<9> U5D1             T15      SKX_EXT_B_BGA1-IC,TBD
UPI_CPU1_CPU0_P1P1_DP<10> U2D1             G12      SKX_EXT_B_BGA1-IC,TBD
UPI_CPU1_CPU0_P1P1_DP<10> U5D1             P13      SKX_EXT_B_BGA1-IC,TBD
UPI_CPU1_CPU0_P1P1_DP<11> U2D1             G14      SKX_EXT_B_BGA1-IC,TBD
UPI_CPU1_CPU0_P1P1_DP<11> U5D1             M13      SKX_EXT_B_BGA1-IC,TBD
UPI_CPU1_CPU0_P1P1_DP<12> U2D1             E14      SKX_EXT_B_BGA1-IC,TBD
UPI_CPU1_CPU0_P1P1_DP<12> U5D1             N12      SKX_EXT_B_BGA1-IC,TBD
UPI_CPU1_CPU0_P1P1_DP<13> U2D1             H15      SKX_EXT_B_BGA1-IC,TBD
UPI_CPU1_CPU0_P1P1_DP<13> U5D1             T11      SKX_EXT_B_BGA1-IC,TBD
UPI_CPU1_CPU0_P1P1_DP<14> U2D1             G16      SKX_EXT_B_BGA1-IC,TBD
UPI_CPU1_CPU0_P1P1_DP<14> U5D1             U10      SKX_EXT_B_BGA1-IC,TBD
UPI_CPU1_CPU0_P1P1_DP<15> U2D1             L18      SKX_EXT_B_BGA1-IC,TBD
UPI_CPU1_CPU0_P1P1_DP<15> U5D1             N10      SKX_EXT_B_BGA1-IC,TBD
UPI_CPU1_CPU0_P1P1_DP<16> U2D1             J18      SKX_EXT_B_BGA1-IC,TBD
UPI_CPU1_CPU0_P1P1_DP<16> U5D1             R8       SKX_EXT_B_BGA1-IC,TBD
UPI_CPU1_CPU0_P1P1_DP<17> U2D1             H19      SKX_EXT_B_BGA1-IC,TBD
UPI_CPU1_CPU0_P1P1_DP<17> U5D1             U8       SKX_EXT_B_BGA1-IC,TBD
UPI_CPU1_CPU0_P1P1_DP<18> U2D1             F21      SKX_EXT_B_BGA1-IC,TBD
UPI_CPU1_CPU0_P1P1_DP<18> U5D1             T7       SKX_EXT_B_BGA1-IC,TBD
UPI_CPU1_CPU0_P1P1_DP<19> U2D1             H21      SKX_EXT_B_BGA1-IC,TBD
UPI_CPU1_CPU0_P1P1_DP<19> U5D1             R6       SKX_EXT_B_BGA1-IC,TBD
USB2_P01_DN              L1M2             1        CHOKE_4PIN_SMLF-90 OHM,EMPTY,7A
USB2_P01_DN              R1M6             1        RES_0402-0.0,5%,1/16W,CHIP,G21A
USB2_P01_DN              U7C1             BY60     LBG_CORE_QAT_EXT_D_BGA1-IC,H91A
USB2_P01_DP              L1M2             2        CHOKE_4PIN_SMLF-90 OHM,EMPTY,7A
USB2_P01_DP              R1M5             1        RES_0402-0.0,5%,1/16W,CHIP,G21A
USB2_P01_DP              U7C1             BV60     LBG_CORE_QAT_EXT_D_BGA1-IC,H91A
USB2_P01_ESD_DN          CR1M2            2        DIODEAC_DUAL_ARRAY_SM9-ESD3V3UA
USB2_P01_ESD_DN          CR1M2            8        DIODEAC_DUAL_ARRAY_SM9-ESD3V3UA
USB2_P01_ESD_DN          J9B1             2        CONN9_H51826001_PIP2-CONN,H518A
USB2_P01_ESD_DN          L1M2             4        CHOKE_4PIN_SMLF-90 OHM,EMPTY,7A
USB2_P01_ESD_DN          R1M6             2        RES_0402-0.0,5%,1/16W,CHIP,G21A
USB2_P01_ESD_DP          CR1M2            1        DIODEAC_DUAL_ARRAY_SM9-ESD3V3UA
USB2_P01_ESD_DP          CR1M2            9        DIODEAC_DUAL_ARRAY_SM9-ESD3V3UA
USB2_P01_ESD_DP          J9B1             3        CONN9_H51826001_PIP2-CONN,H518A
USB2_P01_ESD_DP          L1M2             3        CHOKE_4PIN_SMLF-90 OHM,EMPTY,7A
USB2_P01_ESD_DP          R1M5             2        RES_0402-0.0,5%,1/16W,CHIP,G21A
USB2_PCH_BMC_P5_DN       U7C1             BY58     LBG_CORE_QAT_EXT_D_BGA1-IC,H91A
USB2_PCH_BMC_P5_DN       U9F4             AB20     AST1250_BGA-IC,G85138-002
USB2_PCH_BMC_P5_DP       U7C1             BV58     LBG_CORE_QAT_EXT_D_BGA1-IC,H91A
USB2_PCH_BMC_P5_DP       U9F4             AB21     AST1250_BGA-IC,G85138-002
USB3_P01_C_TXN           C1M2             2        CAP_A_0402V-0.1UF,16V,10%,X7R,A
USB3_P01_C_TXN           L1M1             1        CHOKE_4PIN_SM_B-67 OHM,EMPTY,7A
USB3_P01_C_TXN           R1M2             1        RES_0402-0.0,5%,1/16W,CHIP,G21A
USB3_P01_C_TXP           C1M1             2        CAP_A_0402V-0.1UF,16V,10%,X7R,A
USB3_P01_C_TXP           L1M1             4        CHOKE_4PIN_SM_B-67 OHM,EMPTY,7A
USB3_P01_C_TXP           R1M1             1        RES_0402-0.0,5%,1/16W,CHIP,G21A
USB3_P01_FB_RXN          CR1M1            4        DIODEAC_DUAL_ARRAY_SM9-ESD3V3UA
USB3_P01_FB_RXN          CR1M1            7        DIODEAC_DUAL_ARRAY_SM9-ESD3V3UA
USB3_P01_FB_RXN          J9B1             5        CONN9_H51826001_PIP2-CONN,H518A
USB3_P01_FB_RXN          L1L1             2        CHOKE_4PIN_SM_B-67 OHM,EMPTY,7A
USB3_P01_FB_RXN          R1L42            2        RES_0402-0.0,5%,1/16W,CHIP,G21A
USB3_P01_FB_RXP          CR1M1            5        DIODEAC_DUAL_ARRAY_SM9-ESD3V3UA
USB3_P01_FB_RXP          CR1M1            6        DIODEAC_DUAL_ARRAY_SM9-ESD3V3UA
USB3_P01_FB_RXP          J9B1             6        CONN9_H51826001_PIP2-CONN,H518A
USB3_P01_FB_RXP          L1L1             3        CHOKE_4PIN_SM_B-67 OHM,EMPTY,7A
USB3_P01_FB_RXP          R1L40            2        RES_0402-0.0,5%,1/16W,CHIP,G21A
USB3_P01_FB_TXN          CR1M1            1        DIODEAC_DUAL_ARRAY_SM9-ESD3V3UA
USB3_P01_FB_TXN          CR1M1            9        DIODEAC_DUAL_ARRAY_SM9-ESD3V3UA
USB3_P01_FB_TXN          J9B1             8        CONN9_H51826001_PIP2-CONN,H518A
USB3_P01_FB_TXN          L1M1             2        CHOKE_4PIN_SM_B-67 OHM,EMPTY,7A
USB3_P01_FB_TXN          R1M2             2        RES_0402-0.0,5%,1/16W,CHIP,G21A
USB3_P01_FB_TXP          CR1M1            2        DIODEAC_DUAL_ARRAY_SM9-ESD3V3UA
USB3_P01_FB_TXP          CR1M1            8        DIODEAC_DUAL_ARRAY_SM9-ESD3V3UA
USB3_P01_FB_TXP          J9B1             9        CONN9_H51826001_PIP2-CONN,H518A
USB3_P01_FB_TXP          L1M1             3        CHOKE_4PIN_SM_B-67 OHM,EMPTY,7A
USB3_P01_FB_TXP          R1M1             2        RES_0402-0.0,5%,1/16W,CHIP,G21A
USB3_P01_RXN             L1L1             1        CHOKE_4PIN_SM_B-67 OHM,EMPTY,7A
USB3_P01_RXN             R1L42            1        RES_0402-0.0,5%,1/16W,CHIP,G21A
USB3_P01_RXN             U7C1             BK71     LBG_CORE_QAT_EXT_D_BGA1-IC,H91A
USB3_P01_RXP             L1L1             4        CHOKE_4PIN_SM_B-67 OHM,EMPTY,7A
USB3_P01_RXP             R1L40            1        RES_0402-0.0,5%,1/16W,CHIP,G21A
USB3_P01_RXP             U7C1             BK69     LBG_CORE_QAT_EXT_D_BGA1-IC,H91A
USB3_P01_TXN             C1M2             1        CAP_A_0402V-0.1UF,16V,10%,X7R,A
USB3_P01_TXN             U7C1             BL52     LBG_CORE_QAT_EXT_D_BGA1-IC,H91A
USB3_P01_TXP             C1M1             1        CAP_A_0402V-0.1UF,16V,10%,X7R,A
USB3_P01_TXP             U7C1             BK54     LBG_CORE_QAT_EXT_D_BGA1-IC,H91A
USB_PCH_BMC_P4_DN        R1U52            2        RES_0402-1.5K,1%,1/16W,CHIP,G2A
USB_PCH_BMC_P4_DN        U7C1             BY62     LBG_CORE_QAT_EXT_D_BGA1-IC,H91A
USB_PCH_BMC_P4_DN        U9F4             K3       AST1250_BGA-IC,G85138-002
USB_PCH_BMC_P4_DP        U7C1             BV62     LBG_CORE_QAT_EXT_D_BGA1-IC,H91A
USB_PCH_BMC_P4_DP        U9F4             K4       AST1250_BGA-IC,G85138-002
VID_PCH_CORE_PVNN_AUX_VID_0 EU8A1            13       PXE1110B_QFN-IC,H89187-001
VID_PCH_CORE_PVNN_AUX_VID_0 R2L26            2        RES_0402-100.0K,1%,1/16W,EMPTYA
VID_PCH_CORE_PVNN_AUX_VID_0 U7C1             BL7      LBG_CORE_QAT_EXT_D_BGA1-IC,H91A
VID_PCH_CORE_PVNN_AUX_VID_1 EU8A1            14       PXE1110B_QFN-IC,H89187-001
VID_PCH_CORE_PVNN_AUX_VID_1 R2L25            2        RES_0402-100.0K,1%,1/16W,EMPTYA
VID_PCH_CORE_PVNN_AUX_VID_1 U7C1             BH9      LBG_CORE_QAT_EXT_D_BGA1-IC,H91A
VR_COMP_PVPP_ABC         C7F13            1        CAP_0402LF-2200PF,50V,10%,X7R,A
VR_COMP_PVPP_ABC         R7F17            2        RES_0402-1.0K,0.1%,1/16W,CHIP,A
VR_COMP_PVPP_ABC_3       C7F9             2        CAP_0402LF-100.0PF,50V,5%,COG,A
VR_COMP_PVPP_ABC_3       C7F12            2        CAP_0402LF-2200PF,50V,10%,X7R,A
VR_COMP_PVPP_ABC_3       EU7F1            3        NCP3232L_SM-IC,H86355-001
VR_COMP_PVPP_DEF         C7B13            1        CAP_0402LF-2200PF,50V,10%,X7R,A
VR_COMP_PVPP_DEF         R7B18            2        RES_0402-1.0K,0.1%,1/16W,CHIP,A
VR_COMP_PVPP_DEF_3       C7B10            2        CAP_0402LF-100.0PF,50V,5%,COG,A
VR_COMP_PVPP_DEF_3       C7B14            2        CAP_0402LF-2200PF,50V,10%,X7R,A
VR_COMP_PVPP_DEF_3       EU7B1            3        NCP3232L_SM-IC,H86355-001
VR_COMP_PVPP_GHJ         C4G11            1        CAP_0402LF-2200PF,50V,10%,X7R,A
VR_COMP_PVPP_GHJ         R4G10            2        RES_0402-1.0K,0.1%,1/16W,CHIP,A
VR_COMP_PVPP_GHJ_3       C4G6             2        CAP_0402LF-100.0PF,50V,5%,COG,A
VR_COMP_PVPP_GHJ_3       C4G10            2        CAP_0402LF-2200PF,50V,10%,X7R,A
VR_COMP_PVPP_GHJ_3       EU4G1            3        NCP3232L_SM-IC,H86355-001
VR_COMP_PVPP_KLM         C4B7             1        CAP_0402LF-2200PF,50V,10%,X7R,A
VR_COMP_PVPP_KLM         R4B9             2        RES_0402-1.0K,0.1%,1/16W,CHIP,A
VR_COMP_PVPP_KLM_3       C4B4             2        CAP_0402LF-100.0PF,50V,5%,COG,A
VR_COMP_PVPP_KLM_3       C4B9             2        CAP_0402LF-2200PF,50V,10%,X7R,A
VR_COMP_PVPP_KLM_3       EU4A3            3        NCP3232L_SM-IC,H86355-001
VR_COMP_RC_PVPP_ABC      C7F12            1        CAP_0402LF-2200PF,50V,10%,X7R,A
VR_COMP_RC_PVPP_ABC      R7F18            1        RES_0402-7.87K,1.0%,1/16W,CHIPA
VR_COMP_RC_PVPP_DEF      C7B14            1        CAP_0402LF-2200PF,50V,10%,X7R,A
VR_COMP_RC_PVPP_DEF      R7B16            1        RES_0402-7.87K,1.0%,1/16W,CHIPA
VR_COMP_RC_PVPP_GHJ      C4G10            1        CAP_0402LF-2200PF,50V,10%,X7R,A
VR_COMP_RC_PVPP_GHJ      R4G13            1        RES_0402-7.87K,1.0%,1/16W,CHIPA
VR_COMP_RC_PVPP_KLM      C4B9             1        CAP_0402LF-2200PF,50V,10%,X7R,A
VR_COMP_RC_PVPP_KLM      R4B8             1        RES_0402-7.87K,1.0%,1/16W,CHIPA
VR_FB_PVPP_ABC           C7F9             1        CAP_0402LF-100.0PF,50V,5%,COG,A
VR_FB_PVPP_ABC           C7F13            2        CAP_0402LF-2200PF,50V,10%,X7R,A
VR_FB_PVPP_ABC           EU7F1            2        NCP3232L_SM-IC,H86355-001
VR_FB_PVPP_ABC           R7F11            1        RES_0402-6.34K,1%,1/16W,CHIP,GA
VR_FB_PVPP_ABC           R7F13            2        RES_0402-20.0K,1%,1/16W,CHIP,GA
VR_FB_PVPP_ABC           R7F18            2        RES_0402-7.87K,1.0%,1/16W,CHIPA
VR_FB_PVPP_DEF           C7B10            1        CAP_0402LF-100.0PF,50V,5%,COG,A
VR_FB_PVPP_DEF           C7B13            2        CAP_0402LF-2200PF,50V,10%,X7R,A
VR_FB_PVPP_DEF           EU7B1            2        NCP3232L_SM-IC,H86355-001
VR_FB_PVPP_DEF           R7B13            1        RES_0402-6.34K,1%,1/16W,CHIP,GA
VR_FB_PVPP_DEF           R7B15            2        RES_0402-20.0K,1%,1/16W,CHIP,GA
VR_FB_PVPP_DEF           R7B16            2        RES_0402-7.87K,1.0%,1/16W,CHIPA
VR_FB_PVPP_GHJ           C4G6             1        CAP_0402LF-100.0PF,50V,5%,COG,A
VR_FB_PVPP_GHJ           C4G11            2        CAP_0402LF-2200PF,50V,10%,X7R,A
VR_FB_PVPP_GHJ           EU4G1            2        NCP3232L_SM-IC,H86355-001
VR_FB_PVPP_GHJ           R4G7             2        RES_0402-20.0K,1%,1/16W,CHIP,GA
VR_FB_PVPP_GHJ           R4G9             1        RES_0402-6.34K,1%,1/16W,CHIP,GA
VR_FB_PVPP_GHJ           R4G13            2        RES_0402-7.87K,1.0%,1/16W,CHIPA
VR_FB_PVPP_KLM           C4B4             1        CAP_0402LF-100.0PF,50V,5%,COG,A
VR_FB_PVPP_KLM           C4B7             2        CAP_0402LF-2200PF,50V,10%,X7R,A
VR_FB_PVPP_KLM           EU4A3            2        NCP3232L_SM-IC,H86355-001
VR_FB_PVPP_KLM           R4B4             1        RES_0402-6.34K,1%,1/16W,CHIP,GA
VR_FB_PVPP_KLM           R4B5             2        RES_0402-20.0K,1%,1/16W,CHIP,GA
VR_FB_PVPP_KLM           R4B8             2        RES_0402-7.87K,1.0%,1/16W,CHIPA
VR_FET_SW_P12V_PVCCIN_CPU0_R C4C2             1        CAP_A_0402V-0.1UF,16V,10%,EMPTA
VR_FET_SW_P12V_PVCCIN_CPU0_R L4C1             2        INDUCTOR_SM-100NH,IND,D92183-0A
VR_FET_SW_P12V_PVCCIN_CPU0_R R4C6             1        RES_2010-0.001,1%,1W,CHIP,E309A
VR_FET_SW_P12V_PVCCIN_CPU0_R U4C1             3        ADM4073_SM-EMPTY,G12194-001
VR_FET_SW_P12V_PVCCIN_CPU0_R U4C1             4        ADM4073_SM-EMPTY,G12194-001
VR_FET_SW_P12V_PVCCIN_CPU1_R C1B16            1        CAP_A_0402V-0.1UF,16V,10%,EMPTA
VR_FET_SW_P12V_PVCCIN_CPU1_R L1B2             2        INDUCTOR_SM-100NH,IND,D92183-0A
VR_FET_SW_P12V_PVCCIN_CPU1_R R1B20            1        RES_2010-0.001,1%,1W,CHIP,E309A
VR_FET_SW_P12V_PVCCIN_CPU1_R U1B3             3        ADM4073_SM-EMPTY,G12194-001
VR_FET_SW_P12V_PVCCIN_CPU1_R U1B3             4        ADM4073_SM-EMPTY,G12194-001
VR_FET_SW_P12V_STBY_P3V3_STBY C8E10            1        CAP_1206LF-22UF,16V,10%,X6S,D3A
VR_FET_SW_P12V_STBY_P3V3_STBY C8E11            1        CAP_1210-47UF,16V,20%,X6S,D384A
VR_FET_SW_P12V_STBY_P3V3_STBY C8E14            1        CAP_0402-1.0UF,16V,10%,X6S,D97A
VR_FET_SW_P12V_STBY_P3V3_STBY C9F1             1        CAP_1210-47UF,16V,20%,X6S,D384A
VR_FET_SW_P12V_STBY_P3V3_STBY EU8E1            2        CSD87384M_SM-IC,H66258-001
VR_FET_SW_P12V_STBY_P3V3_STBY FB9E1            2        FERRITE_SM-22,FB,656554-051
VR_FET_SW_P12V_STBY_PVCCIN_CPU0 C4C9             1        CAP_0402-1.0UF,16V,10%,X6S,D97A
VR_FET_SW_P12V_STBY_PVCCIN_CPU0 C4C10            1        CAP_A_0402V-0.1UF,16V,10%,X7R,A
VR_FET_SW_P12V_STBY_PVCCIN_CPU0 C4C12            1        CAPP_2626-270UF,16V,20%,OSCON,A
VR_FET_SW_P12V_STBY_PVCCIN_CPU0 C4C18            1        CAP_0402-1.0UF,16V,10%,X6S,D97A
VR_FET_SW_P12V_STBY_PVCCIN_CPU0 C4C19            1        CAP_A_0402V-0.1UF,16V,10%,X7R,A
VR_FET_SW_P12V_STBY_PVCCIN_CPU0 C4D2             1        CAPP_2626-270UF,16V,20%,OSCON,A
VR_FET_SW_P12V_STBY_PVCCIN_CPU0 C4D10            1        CAP_0402-1.0UF,16V,10%,X6S,D97A
VR_FET_SW_P12V_STBY_PVCCIN_CPU0 C4D11            1        CAP_A_0402V-0.1UF,16V,10%,X7R,A
VR_FET_SW_P12V_STBY_PVCCIN_CPU0 C4D30            1        CAP_0402-1.0UF,16V,10%,X6S,D97A
VR_FET_SW_P12V_STBY_PVCCIN_CPU0 C4D35            1        CAP_A_0402V-0.1UF,16V,10%,X7R,A
VR_FET_SW_P12V_STBY_PVCCIN_CPU0 C4D48            1        CAP_0402-1.0UF,16V,10%,X6S,D97A
VR_FET_SW_P12V_STBY_PVCCIN_CPU0 C4D49            1        CAP_A_0402V-0.1UF,16V,10%,X7R,A
VR_FET_SW_P12V_STBY_PVCCIN_CPU0 C4E8             1        CAP_1210-100UF,16V,20%,X5R,644A
VR_FET_SW_P12V_STBY_PVCCIN_CPU0 C4E9             1        CAP_1210-100UF,16V,20%,X5R,644A
VR_FET_SW_P12V_STBY_PVCCIN_CPU0 C4E13            1        CAP_A_0402V-0.1UF,16V,10%,X7R,A
VR_FET_SW_P12V_STBY_PVCCIN_CPU0 C4E14            1        CAP_1210-100UF,16V,20%,X5R,644A
VR_FET_SW_P12V_STBY_PVCCIN_CPU0 C4E15            1        CAP_0402-1.0UF,16V,10%,X6S,D97A
VR_FET_SW_P12V_STBY_PVCCIN_CPU0 C4E16            1        CAPP_2626-270UF,16V,20%,OSCON,A
VR_FET_SW_P12V_STBY_PVCCIN_CPU0 C4E19            1        CAP_0402-1.0UF,16V,10%,X6S,D97A
VR_FET_SW_P12V_STBY_PVCCIN_CPU0 C4E20            1        CAP_A_0402V-0.1UF,16V,10%,X7R,A
VR_FET_SW_P12V_STBY_PVCCIN_CPU0 C6N2             1        CAP_0805-10UF,16V,10%,X6S,C953A
VR_FET_SW_P12V_STBY_PVCCIN_CPU0 C6N3             1        CAP_0805-10UF,16V,10%,X6S,C953A
VR_FET_SW_P12V_STBY_PVCCIN_CPU0 C6N6             1        CAP_0805-10UF,16V,10%,X6S,C953A
VR_FET_SW_P12V_STBY_PVCCIN_CPU0 C6N8             1        CAP_0805-10UF,16V,10%,X6S,C953A
VR_FET_SW_P12V_STBY_PVCCIN_CPU0 C6N10            1        CAP_0805-10UF,16V,10%,X6S,C953A
VR_FET_SW_P12V_STBY_PVCCIN_CPU0 C6N11            1        CAP_0805-10UF,16V,10%,X6S,C953A
VR_FET_SW_P12V_STBY_PVCCIN_CPU0 C6P7             1        CAP_0805-10UF,16V,10%,X6S,C953A
VR_FET_SW_P12V_STBY_PVCCIN_CPU0 C6P13            1        CAP_0805-10UF,16V,10%,X6S,C953A
VR_FET_SW_P12V_STBY_PVCCIN_CPU0 C6P15            1        CAP_0805-10UF,16V,10%,X6S,C953A
VR_FET_SW_P12V_STBY_PVCCIN_CPU0 C6P17            1        CAP_0805-10UF,16V,10%,X6S,C953A
VR_FET_SW_P12V_STBY_PVCCIN_CPU0 C6P19            1        CAP_0805-10UF,16V,10%,X6S,C953A
VR_FET_SW_P12V_STBY_PVCCIN_CPU0 C6P20            1        CAP_0805-10UF,16V,10%,X6S,C953A
VR_FET_SW_P12V_STBY_PVCCIN_CPU0 C6P22            1        CAP_0805-10UF,16V,10%,X6S,C953A
VR_FET_SW_P12V_STBY_PVCCIN_CPU0 C6P24            1        CAP_0805-10UF,16V,10%,X6S,C953A
VR_FET_SW_P12V_STBY_PVCCIN_CPU0 C6R4             1        CAP_0805-10UF,16V,10%,X6S,C953A
VR_FET_SW_P12V_STBY_PVCCIN_CPU0 C6R6             1        CAP_0805-10UF,16V,10%,X6S,C953A
VR_FET_SW_P12V_STBY_PVCCIN_CPU0 C6R8             1        CAP_0805-10UF,16V,10%,X6S,C953A
VR_FET_SW_P12V_STBY_PVCCIN_CPU0 C6R10            1        CAP_0805-10UF,16V,10%,X6S,C953A
VR_FET_SW_P12V_STBY_PVCCIN_CPU0 C6R11            1        CAP_0805-10UF,16V,10%,X6S,C953A
VR_FET_SW_P12V_STBY_PVCCIN_CPU0 C6R13            1        CAP_0805-10UF,16V,10%,X6S,C953A
VR_FET_SW_P12V_STBY_PVCCIN_CPU0 C6R14            1        CAP_0805-10UF,16V,10%,X6S,C953A
VR_FET_SW_P12V_STBY_PVCCIN_CPU0 EU4C1            25       IR354XX_SM-IR35412,IC,H73684-0A
VR_FET_SW_P12V_STBY_PVCCIN_CPU0 EU4C1            30       IR354XX_SM-IR35412,IC,H73684-0A
VR_FET_SW_P12V_STBY_PVCCIN_CPU0 EU4C2            25       IR354XX_SM-IR35411,IC,H73688-0A
VR_FET_SW_P12V_STBY_PVCCIN_CPU0 EU4C2            30       IR354XX_SM-IR35411,IC,H73688-0A
VR_FET_SW_P12V_STBY_PVCCIN_CPU0 EU4D1            25       IR354XX_SM-IR35411,IC,H73688-0A
VR_FET_SW_P12V_STBY_PVCCIN_CPU0 EU4D1            30       IR354XX_SM-IR35411,IC,H73688-0A
VR_FET_SW_P12V_STBY_PVCCIN_CPU0 EU4D3            25       IR354XX_SM-IR35411,IC,H73688-0A
VR_FET_SW_P12V_STBY_PVCCIN_CPU0 EU4D3            30       IR354XX_SM-IR35411,IC,H73688-0A
VR_FET_SW_P12V_STBY_PVCCIN_CPU0 EU4D6            25       IR354XX_SM-IR35411,IC,H73688-0A
VR_FET_SW_P12V_STBY_PVCCIN_CPU0 EU4D6            30       IR354XX_SM-IR35411,IC,H73688-0A
VR_FET_SW_P12V_STBY_PVCCIN_CPU0 EU4E1            25       IR354XX_SM-IR35411,IC,H73688-0A
VR_FET_SW_P12V_STBY_PVCCIN_CPU0 EU4E1            30       IR354XX_SM-IR35411,IC,H73688-0A
VR_FET_SW_P12V_STBY_PVCCIN_CPU0 EU4E2            25       IR354XX_SM-IR35412,IC,H73684-0A
VR_FET_SW_P12V_STBY_PVCCIN_CPU0 EU4E2            30       IR354XX_SM-IR35412,IC,H73684-0A
VR_FET_SW_P12V_STBY_PVCCIN_CPU0 R4C6             2        RES_2010-0.001,1%,1W,CHIP,E309A
VR_FET_SW_P12V_STBY_PVCCIN_CPU0 R4D27            1        RES_0402-100.0K,1%,1/16W,CHIP,B
VR_FET_SW_P12V_STBY_PVCCIN_CPU0 R4D60            1        RES_0402-100.0K,1%,1/16W,CHIP,B
VR_FET_SW_P12V_STBY_PVCCIN_CPU0 U4C1             5        ADM4073_SM-EMPTY,G12194-001
VR_FET_SW_P12V_STBY_PVCCIN_CPU1 C1C1             1        CAPP_2626-270UF,16V,20%,OSCON,A
VR_FET_SW_P12V_STBY_PVCCIN_CPU1 C1C2             1        CAPP_2626-270UF,16V,20%,OSCON,A
VR_FET_SW_P12V_STBY_PVCCIN_CPU1 C1C15            1        CAP_0402-1.0UF,16V,10%,X6S,D97A
VR_FET_SW_P12V_STBY_PVCCIN_CPU1 C1C17            1        CAP_A_0402V-0.1UF,16V,10%,X7R,A
VR_FET_SW_P12V_STBY_PVCCIN_CPU1 C1C25            1        CAP_A_0402V-0.1UF,16V,10%,X7R,A
VR_FET_SW_P12V_STBY_PVCCIN_CPU1 C1C26            1        CAP_0402-1.0UF,16V,10%,X6S,D97A
VR_FET_SW_P12V_STBY_PVCCIN_CPU1 C1D12            1        CAP_0402-1.0UF,16V,10%,X6S,D97A
VR_FET_SW_P12V_STBY_PVCCIN_CPU1 C1D13            1        CAP_A_0402V-0.1UF,16V,10%,X7R,A
VR_FET_SW_P12V_STBY_PVCCIN_CPU1 C1D23            1        CAP_0402-1.0UF,16V,10%,X6S,D97A
VR_FET_SW_P12V_STBY_PVCCIN_CPU1 C1D28            1        CAP_A_0402V-0.1UF,16V,10%,X7R,A
VR_FET_SW_P12V_STBY_PVCCIN_CPU1 C1D34            1        CAP_A_0402V-0.1UF,16V,10%,X7R,A
VR_FET_SW_P12V_STBY_PVCCIN_CPU1 C1D35            1        CAP_0402-1.0UF,16V,10%,X6S,D97A
VR_FET_SW_P12V_STBY_PVCCIN_CPU1 C1E13            1        CAP_0402-1.0UF,16V,10%,X6S,D97A
VR_FET_SW_P12V_STBY_PVCCIN_CPU1 C1E14            1        CAP_A_0402V-0.1UF,16V,10%,X7R,A
VR_FET_SW_P12V_STBY_PVCCIN_CPU1 C1E18            1        CAPP_2626-270UF,16V,20%,OSCON,A
VR_FET_SW_P12V_STBY_PVCCIN_CPU1 C9N13            1        CAP_0805-10UF,16V,10%,X6S,C953A
VR_FET_SW_P12V_STBY_PVCCIN_CPU1 C9N19            1        CAP_0805-10UF,16V,10%,X6S,C953A
VR_FET_SW_P12V_STBY_PVCCIN_CPU1 C9N21            1        CAP_0805-10UF,16V,10%,X6S,C953A
VR_FET_SW_P12V_STBY_PVCCIN_CPU1 C9N25            1        CAP_0805-10UF,16V,10%,X6S,C953A
VR_FET_SW_P12V_STBY_PVCCIN_CPU1 C9N26            1        CAP_0805-10UF,16V,10%,X6S,C953A
VR_FET_SW_P12V_STBY_PVCCIN_CPU1 C9N27            1        CAP_0805-10UF,16V,10%,X6S,C953A
VR_FET_SW_P12V_STBY_PVCCIN_CPU1 C9P1             1        CAP_0805-10UF,16V,10%,X6S,C953A
VR_FET_SW_P12V_STBY_PVCCIN_CPU1 C9P2             1        CAP_0805-10UF,16V,10%,X6S,C953A
VR_FET_SW_P12V_STBY_PVCCIN_CPU1 C9P4             1        CAP_0805-10UF,16V,10%,X6S,C953A
VR_FET_SW_P12V_STBY_PVCCIN_CPU1 C9P7             1        CAP_0805-10UF,16V,10%,X6S,C953A
VR_FET_SW_P12V_STBY_PVCCIN_CPU1 C9P9             1        CAP_0805-10UF,16V,10%,X6S,C953A
VR_FET_SW_P12V_STBY_PVCCIN_CPU1 C9P22            1        CAP_0805-10UF,16V,10%,X6S,C953A
VR_FET_SW_P12V_STBY_PVCCIN_CPU1 C9P24            1        CAP_0805-10UF,16V,10%,X6S,C953A
VR_FET_SW_P12V_STBY_PVCCIN_CPU1 C9P25            1        CAP_0805-10UF,16V,10%,X6S,C953A
VR_FET_SW_P12V_STBY_PVCCIN_CPU1 C9P26            1        CAP_0805-10UF,16V,10%,X6S,C953A
VR_FET_SW_P12V_STBY_PVCCIN_CPU1 C9R7             1        CAP_0805-10UF,16V,10%,X6S,C953A
VR_FET_SW_P12V_STBY_PVCCIN_CPU1 C9R10            1        CAP_0805-10UF,16V,10%,X6S,C953A
VR_FET_SW_P12V_STBY_PVCCIN_CPU1 C9R11            1        CAP_0805-10UF,16V,10%,X6S,C953A
VR_FET_SW_P12V_STBY_PVCCIN_CPU1 EU1C1            25       IR354XX_SM-IR35412,IC,H73684-0A
VR_FET_SW_P12V_STBY_PVCCIN_CPU1 EU1C1            30       IR354XX_SM-IR35412,IC,H73684-0A
VR_FET_SW_P12V_STBY_PVCCIN_CPU1 EU1C3            25       IR354XX_SM-IR35411,IC,H73688-0A
VR_FET_SW_P12V_STBY_PVCCIN_CPU1 EU1C3            30       IR354XX_SM-IR35411,IC,H73688-0A
VR_FET_SW_P12V_STBY_PVCCIN_CPU1 EU1D1            25       IR354XX_SM-IR35411,IC,H73688-0A
VR_FET_SW_P12V_STBY_PVCCIN_CPU1 EU1D1            30       IR354XX_SM-IR35411,IC,H73688-0A
VR_FET_SW_P12V_STBY_PVCCIN_CPU1 EU1D3            25       IR354XX_SM-IR35411,IC,H73688-0A
VR_FET_SW_P12V_STBY_PVCCIN_CPU1 EU1D3            30       IR354XX_SM-IR35411,IC,H73688-0A
VR_FET_SW_P12V_STBY_PVCCIN_CPU1 EU1D4            25       IR354XX_SM-IR35411,IC,H73688-0A
VR_FET_SW_P12V_STBY_PVCCIN_CPU1 EU1D4            30       IR354XX_SM-IR35411,IC,H73688-0A
VR_FET_SW_P12V_STBY_PVCCIN_CPU1 EU1E2            25       IR354XX_SM-IR35411,IC,H73688-0A
VR_FET_SW_P12V_STBY_PVCCIN_CPU1 EU1E2            30       IR354XX_SM-IR35411,IC,H73688-0A
VR_FET_SW_P12V_STBY_PVCCIN_CPU1 R1B20            2        RES_2010-0.001,1%,1W,CHIP,E309A
VR_FET_SW_P12V_STBY_PVCCIN_CPU1 R1C13            1        RES_0402-100.0K,1%,1/16W,CHIP,B
VR_FET_SW_P12V_STBY_PVCCIN_CPU1 U1B3             5        ADM4073_SM-EMPTY,G12194-001
VR_FET_SW_P12V_STBY_PVCCIO_CPU0 C3N33            1        CAP_0805-10UF,16V,10%,X6S,C953A
VR_FET_SW_P12V_STBY_PVCCIO_CPU0 C3N34            1        CAP_0805-10UF,16V,10%,X6S,C953A
VR_FET_SW_P12V_STBY_PVCCIO_CPU0 C3N36            1        CAP_0805-10UF,16V,10%,X6S,C953A
VR_FET_SW_P12V_STBY_PVCCIO_CPU0 C7C7             1        CAP_1210-100UF,16V,20%,X5R,644A
VR_FET_SW_P12V_STBY_PVCCIO_CPU0 C7C8             1        CAP_1210-100UF,16V,20%,X5R,644A
VR_FET_SW_P12V_STBY_PVCCIO_CPU0 C7C11            1        CAP_A_0402V-0.1UF,16V,10%,X7R,A
VR_FET_SW_P12V_STBY_PVCCIO_CPU0 C7C12            1        CAP_0402-1.0UF,16V,10%,X6S,D97A
VR_FET_SW_P12V_STBY_PVCCIO_CPU0 EU7C1            25       IR354XX_SM-IR35412,IC,H73684-0A
VR_FET_SW_P12V_STBY_PVCCIO_CPU0 EU7C1            30       IR354XX_SM-IR35412,IC,H73684-0A
VR_FET_SW_P12V_STBY_PVCCIO_CPU0 L7C1             2        INDUCTOR_SM-100NH,IND,D92183-0B
VR_FET_SW_P12V_STBY_PVCCIO_CPU0 R3P12            1        RES_0402-100.0K,1%,1/16W,CHIP,B
VR_FET_SW_P12V_STBY_PVDDQ_ABC C3U2             1        CAP_0805-10UF,16V,10%,X6S,C953A
VR_FET_SW_P12V_STBY_PVDDQ_ABC C3U3             1        CAP_0805-10UF,16V,10%,X6S,C953A
VR_FET_SW_P12V_STBY_PVDDQ_ABC C3U4             1        CAP_0805-10UF,16V,10%,X6S,C953A
VR_FET_SW_P12V_STBY_PVDDQ_ABC C3U6             1        CAP_0805-10UF,16V,10%,X6S,C953A
VR_FET_SW_P12V_STBY_PVDDQ_ABC C3U7             1        CAP_0805-10UF,16V,10%,X6S,C953A
VR_FET_SW_P12V_STBY_PVDDQ_ABC C3U9             1        CAP_0805-10UF,16V,10%,X6S,C953A
VR_FET_SW_P12V_STBY_PVDDQ_ABC C7G2             1        CAPP_2626-270UF,16V,20%,OSCON,A
VR_FET_SW_P12V_STBY_PVDDQ_ABC C7G29            1        CAP_A_0402V-0.1UF,16V,10%,X7R,A
VR_FET_SW_P12V_STBY_PVDDQ_ABC C7G30            1        CAP_0402-1.0UF,16V,10%,X6S,D97A
VR_FET_SW_P12V_STBY_PVDDQ_ABC C7G36            1        CAP_A_0402V-0.1UF,16V,10%,X7R,A
VR_FET_SW_P12V_STBY_PVDDQ_ABC C7G37            1        CAP_0402-1.0UF,16V,10%,X6S,D97A
VR_FET_SW_P12V_STBY_PVDDQ_ABC EU7G2            25       IR354XX_SM-IR35411,IC,H73688-0A
VR_FET_SW_P12V_STBY_PVDDQ_ABC EU7G2            30       IR354XX_SM-IR35411,IC,H73688-0A
VR_FET_SW_P12V_STBY_PVDDQ_ABC EU7G3            25       IR354XX_SM-IR35411,IC,H73688-0A
VR_FET_SW_P12V_STBY_PVDDQ_ABC EU7G3            30       IR354XX_SM-IR35411,IC,H73688-0A
VR_FET_SW_P12V_STBY_PVDDQ_ABC L7F2             2        INDUCTOR_SM-100NH,IND,D92183-0B
VR_FET_SW_P12V_STBY_PVDDQ_ABC R7F34            1        RES_0402-100.0K,1%,1/16W,CHIP,B
VR_FET_SW_P12V_STBY_PVDDQ_DEF C3L2             1        CAP_0805-10UF,16V,10%,X6S,C953A
VR_FET_SW_P12V_STBY_PVDDQ_DEF C3L4             1        CAP_0805-10UF,16V,10%,X6S,C953A
VR_FET_SW_P12V_STBY_PVDDQ_DEF C3L7             1        CAP_0805-10UF,16V,10%,X6S,C953A
VR_FET_SW_P12V_STBY_PVDDQ_DEF C3L8             1        CAP_0805-10UF,16V,10%,X6S,C953A
VR_FET_SW_P12V_STBY_PVDDQ_DEF C3L9             1        CAP_0805-10UF,16V,10%,X6S,C953A
VR_FET_SW_P12V_STBY_PVDDQ_DEF C3L10            1        CAP_0805-10UF,16V,10%,X6S,C953A
VR_FET_SW_P12V_STBY_PVDDQ_DEF C3L11            1        CAP_0805-10UF,16V,10%,X6S,C953A
VR_FET_SW_P12V_STBY_PVDDQ_DEF C3L12            1        CAP_0805-10UF,16V,10%,X6S,C953A
VR_FET_SW_P12V_STBY_PVDDQ_DEF C3L13            1        CAP_0805-10UF,16V,10%,X6S,C953A
VR_FET_SW_P12V_STBY_PVDDQ_DEF C3L15            1        CAP_0805-10UF,16V,10%,X6S,C953A
VR_FET_SW_P12V_STBY_PVDDQ_DEF C3L16            1        CAP_0805-10UF,16V,10%,X6S,C953A
VR_FET_SW_P12V_STBY_PVDDQ_DEF C3L17            1        CAP_0805-10UF,16V,10%,X6S,C953A
VR_FET_SW_P12V_STBY_PVDDQ_DEF C7A5             1        CAP_A_0402V-0.1UF,16V,10%,X7R,A
VR_FET_SW_P12V_STBY_PVDDQ_DEF C7A7             1        CAP_0402-1.0UF,16V,10%,X6S,D97A
VR_FET_SW_P12V_STBY_PVDDQ_DEF C7A9             1        CAP_0402-1.0UF,16V,10%,X6S,D97A
VR_FET_SW_P12V_STBY_PVDDQ_DEF C7A11            1        CAP_0402-1.0UF,16V,10%,X6S,D97A
VR_FET_SW_P12V_STBY_PVDDQ_DEF C7A13            1        CAP_1210-100UF,16V,20%,X5R,644A
VR_FET_SW_P12V_STBY_PVDDQ_DEF C7A14            1        CAP_1210-100UF,16V,20%,X5R,644A
VR_FET_SW_P12V_STBY_PVDDQ_DEF C7A19            1        CAPP_2626-270UF,16V,20%,OSCON,A
VR_FET_SW_P12V_STBY_PVDDQ_DEF C7A20            1        CAP_A_0402V-0.1UF,16V,10%,X7R,A
VR_FET_SW_P12V_STBY_PVDDQ_DEF C7A21            1        CAP_0402-1.0UF,16V,10%,X6S,D97A
VR_FET_SW_P12V_STBY_PVDDQ_DEF C7A39            1        CAP_A_0402V-0.1UF,16V,10%,X7R,A
VR_FET_SW_P12V_STBY_PVDDQ_DEF C7A40            1        CAP_A_0402V-0.1UF,16V,10%,X7R,A
VR_FET_SW_P12V_STBY_PVDDQ_DEF EU7A1            25       IR354XX_SM-IR35411,IC,H73688-0A
VR_FET_SW_P12V_STBY_PVDDQ_DEF EU7A1            30       IR354XX_SM-IR35411,IC,H73688-0A
VR_FET_SW_P12V_STBY_PVDDQ_DEF EU7A2            25       IR354XX_SM-IR35412,IC,H73684-0A
VR_FET_SW_P12V_STBY_PVDDQ_DEF EU7A2            30       IR354XX_SM-IR35412,IC,H73684-0A
VR_FET_SW_P12V_STBY_PVDDQ_DEF EU7A3            25       IR354XX_SM-IR35412,IC,H73684-0A
VR_FET_SW_P12V_STBY_PVDDQ_DEF EU7A3            30       IR354XX_SM-IR35412,IC,H73684-0A
VR_FET_SW_P12V_STBY_PVDDQ_DEF EU7A4            25       IR354XX_SM-IR35411,IC,H73688-0A
VR_FET_SW_P12V_STBY_PVDDQ_DEF EU7A4            30       IR354XX_SM-IR35411,IC,H73688-0A
VR_FET_SW_P12V_STBY_PVDDQ_DEF L7A5             2        INDUCTOR_SM-100NH,IND,D92183-0B
VR_FET_SW_P12V_STBY_PVDDQ_DEF R3L12            1        RES_0402-100.0K,1%,1/16W,CHIP,B
VR_FET_SW_P12V_STBY_PVDDQ_DEF R8A4             1        RES_0402-100.0K,1%,1/16W,CHIP,B
VR_FET_SW_P12V_STBY_PVDDQ_GHJ C1F27            1        CAP_0402-1.0UF,16V,10%,X6S,D97A
VR_FET_SW_P12V_STBY_PVDDQ_GHJ C1F28            1        CAP_A_0402V-0.1UF,16V,10%,X7R,A
VR_FET_SW_P12V_STBY_PVDDQ_GHJ C1G2             1        CAP_1210-47UF,16V,20%,X6S,D384A
VR_FET_SW_P12V_STBY_PVDDQ_GHJ C1G7             1        CAP_1210-47UF,16V,20%,X6S,D384A
VR_FET_SW_P12V_STBY_PVDDQ_GHJ C1G12            1        CAP_1210-47UF,16V,20%,X6S,D384A
VR_FET_SW_P12V_STBY_PVDDQ_GHJ C1G13            1        CAP_0402-1.0UF,16V,10%,X6S,D97A
VR_FET_SW_P12V_STBY_PVDDQ_GHJ C1G14            1        CAP_A_0402V-0.1UF,16V,10%,X7R,A
VR_FET_SW_P12V_STBY_PVDDQ_GHJ C1G15            1        CAP_1210-47UF,16V,20%,X6S,D384A
VR_FET_SW_P12V_STBY_PVDDQ_GHJ C9T4             1        CAP_0805-10UF,16V,10%,X6S,C953A
VR_FET_SW_P12V_STBY_PVDDQ_GHJ C9T6             1        CAP_0805-10UF,16V,10%,X6S,C953A
VR_FET_SW_P12V_STBY_PVDDQ_GHJ C9T9             1        CAP_0805-10UF,16V,10%,X6S,C953A
VR_FET_SW_P12V_STBY_PVDDQ_GHJ C9U3             1        CAP_0805-10UF,16V,10%,X6S,C953A
VR_FET_SW_P12V_STBY_PVDDQ_GHJ C9U4             1        CAP_0805-10UF,16V,10%,X6S,C953A
VR_FET_SW_P12V_STBY_PVDDQ_GHJ C9U6             1        CAP_0805-10UF,16V,10%,X6S,C953A
VR_FET_SW_P12V_STBY_PVDDQ_GHJ EU1F1            25       IR354XX_SM-IR35411,IC,H73688-0A
VR_FET_SW_P12V_STBY_PVDDQ_GHJ EU1F1            30       IR354XX_SM-IR35411,IC,H73688-0A
VR_FET_SW_P12V_STBY_PVDDQ_GHJ EU1G1            25       IR354XX_SM-IR35411,IC,H73688-0A
VR_FET_SW_P12V_STBY_PVDDQ_GHJ EU1G1            30       IR354XX_SM-IR35411,IC,H73688-0A
VR_FET_SW_P12V_STBY_PVDDQ_GHJ L1F1             2        INDUCTOR_SM-100NH,IND,D92183-0B
VR_FET_SW_P12V_STBY_PVDDQ_GHJ R9U11            1        RES_0402-100.0K,1%,1/16W,CHIP,B
VR_FET_SW_P12V_STBY_PVDDQ_KLM C1A9             1        CAP_0402-1.0UF,16V,10%,X6S,D97A
VR_FET_SW_P12V_STBY_PVDDQ_KLM C1A10            1        CAP_A_0402V-0.1UF,16V,10%,X7R,A
VR_FET_SW_P12V_STBY_PVDDQ_KLM C1A19            1        CAP_0402-1.0UF,16V,10%,X6S,D97A
VR_FET_SW_P12V_STBY_PVDDQ_KLM C1A20            1        CAP_A_0402V-0.1UF,16V,10%,X7R,A
VR_FET_SW_P12V_STBY_PVDDQ_KLM C1B10            1        CAPP_2626-270UF,16V,20%,OSCON,A
VR_FET_SW_P12V_STBY_PVDDQ_KLM C9L5             1        CAP_0805-10UF,16V,10%,X6S,C953A
VR_FET_SW_P12V_STBY_PVDDQ_KLM C9L6             1        CAP_0805-10UF,16V,10%,X6S,C953A
VR_FET_SW_P12V_STBY_PVDDQ_KLM C9L10            1        CAP_0805-10UF,16V,10%,X6S,C953A
VR_FET_SW_P12V_STBY_PVDDQ_KLM C9L11            1        CAP_0805-10UF,16V,10%,X6S,C953A
VR_FET_SW_P12V_STBY_PVDDQ_KLM C9L13            1        CAP_0805-10UF,16V,10%,X6S,C953A
VR_FET_SW_P12V_STBY_PVDDQ_KLM C9L14            1        CAP_0805-10UF,16V,10%,X6S,C953A
VR_FET_SW_P12V_STBY_PVDDQ_KLM EU1A1            25       IR354XX_SM-IR35411,IC,H73688-0A
VR_FET_SW_P12V_STBY_PVDDQ_KLM EU1A1            30       IR354XX_SM-IR35411,IC,H73688-0A
VR_FET_SW_P12V_STBY_PVDDQ_KLM EU1A2            25       IR354XX_SM-IR35411,IC,H73688-0A
VR_FET_SW_P12V_STBY_PVDDQ_KLM EU1A2            30       IR354XX_SM-IR35411,IC,H73688-0A
VR_FET_SW_P12V_STBY_PVDDQ_KLM L1B1             2        INDUCTOR_SM-100NH,IND,D92183-0B
VR_FET_SW_P12V_STBY_PVDDQ_KLM R9M8             1        RES_0402-100.0K,1%,1/16W,CHIP,B
VR_FET_SW_P12V_STBY_PVPP_ABC C3T8             1        CAP_0805-10UF,16V,10%,X6S,C953A
VR_FET_SW_P12V_STBY_PVPP_ABC C3T10            1        CAP_0402-1.0UF,16V,10%,X6S,D97A
VR_FET_SW_P12V_STBY_PVPP_ABC C3T12            1        CAP_0805-10UF,16V,10%,X6S,C953A
VR_FET_SW_P12V_STBY_PVPP_ABC C3T14            1        CAP_0805-10UF,16V,10%,X6S,C953A
VR_FET_SW_P12V_STBY_PVPP_ABC C7F5             1        CAP_0805-10UF,16V,10%,X6S,C953A
VR_FET_SW_P12V_STBY_PVPP_ABC C7F6             1        CAP_A_0402V-0.1UF,16V,10%,X7R,A
VR_FET_SW_P12V_STBY_PVPP_ABC C7F7             1        CAP_1210-47UF,16V,20%,X6S,D384A
VR_FET_SW_P12V_STBY_PVPP_ABC EU7F1            8        NCP3232L_SM-IC,H86355-001
VR_FET_SW_P12V_STBY_PVPP_ABC EU7F1            9        NCP3232L_SM-IC,H86355-001
VR_FET_SW_P12V_STBY_PVPP_ABC EU7F1            10       NCP3232L_SM-IC,H86355-001
VR_FET_SW_P12V_STBY_PVPP_ABC EU7F1            11       NCP3232L_SM-IC,H86355-001
VR_FET_SW_P12V_STBY_PVPP_ABC EU7F1            12       NCP3232L_SM-IC,H86355-001
VR_FET_SW_P12V_STBY_PVPP_ABC EU7F1            13       NCP3232L_SM-IC,H86355-001
VR_FET_SW_P12V_STBY_PVPP_ABC EU7F1            14       NCP3232L_SM-IC,H86355-001
VR_FET_SW_P12V_STBY_PVPP_ABC EU7F1            39       NCP3232L_SM-IC,H86355-001
VR_FET_SW_P12V_STBY_PVPP_ABC EU7F1            42       NCP3232L_SM-IC,H86355-001
VR_FET_SW_P12V_STBY_PVPP_ABC FB7F1            2        FERRITE_SM-22,FB,656554-051
VR_FET_SW_P12V_STBY_PVPP_DEF C3M8             1        CAP_0805-10UF,16V,10%,X6S,C953A
VR_FET_SW_P12V_STBY_PVPP_DEF C3M9             1        CAP_0402-1.0UF,16V,10%,X6S,D97A
VR_FET_SW_P12V_STBY_PVPP_DEF C3M15            1        CAP_0805-10UF,16V,10%,X6S,C953A
VR_FET_SW_P12V_STBY_PVPP_DEF C3M16            1        CAP_0805-10UF,16V,10%,X6S,C953A
VR_FET_SW_P12V_STBY_PVPP_DEF C7B5             1        CAP_0805-10UF,16V,10%,X6S,C953A
VR_FET_SW_P12V_STBY_PVPP_DEF C7B6             1        CAP_A_0402V-0.1UF,16V,10%,X7R,A
VR_FET_SW_P12V_STBY_PVPP_DEF C7B8             1        CAP_1210-47UF,16V,20%,X6S,D384A
VR_FET_SW_P12V_STBY_PVPP_DEF EU7B1            8        NCP3232L_SM-IC,H86355-001
VR_FET_SW_P12V_STBY_PVPP_DEF EU7B1            9        NCP3232L_SM-IC,H86355-001
VR_FET_SW_P12V_STBY_PVPP_DEF EU7B1            10       NCP3232L_SM-IC,H86355-001
VR_FET_SW_P12V_STBY_PVPP_DEF EU7B1            11       NCP3232L_SM-IC,H86355-001
VR_FET_SW_P12V_STBY_PVPP_DEF EU7B1            12       NCP3232L_SM-IC,H86355-001
VR_FET_SW_P12V_STBY_PVPP_DEF EU7B1            13       NCP3232L_SM-IC,H86355-001
VR_FET_SW_P12V_STBY_PVPP_DEF EU7B1            14       NCP3232L_SM-IC,H86355-001
VR_FET_SW_P12V_STBY_PVPP_DEF EU7B1            39       NCP3232L_SM-IC,H86355-001
VR_FET_SW_P12V_STBY_PVPP_DEF EU7B1            42       NCP3232L_SM-IC,H86355-001
VR_FET_SW_P12V_STBY_PVPP_DEF FB7B1            2        FERRITE_SM-22,FB,656554-051
VR_FET_SW_P12V_STBY_PVPP_GHJ C4G2             1        CAP_0805-10UF,16V,10%,X6S,C953A
VR_FET_SW_P12V_STBY_PVPP_GHJ C4G4             1        CAP_0402-1.0UF,16V,10%,X6S,D97A
VR_FET_SW_P12V_STBY_PVPP_GHJ C4G5             1        CAP_1210-47UF,16V,20%,X6S,D384A
VR_FET_SW_P12V_STBY_PVPP_GHJ C6U4             1        CAP_0805-10UF,16V,10%,X6S,C953A
VR_FET_SW_P12V_STBY_PVPP_GHJ C6U5             1        CAP_A_0402V-0.1UF,16V,10%,X7R,A
VR_FET_SW_P12V_STBY_PVPP_GHJ C6U7             1        CAP_0805-10UF,16V,10%,X6S,C953A
VR_FET_SW_P12V_STBY_PVPP_GHJ C6U8             1        CAP_0805-10UF,16V,10%,X6S,C953A
VR_FET_SW_P12V_STBY_PVPP_GHJ EU4G1            8        NCP3232L_SM-IC,H86355-001
VR_FET_SW_P12V_STBY_PVPP_GHJ EU4G1            9        NCP3232L_SM-IC,H86355-001
VR_FET_SW_P12V_STBY_PVPP_GHJ EU4G1            10       NCP3232L_SM-IC,H86355-001
VR_FET_SW_P12V_STBY_PVPP_GHJ EU4G1            11       NCP3232L_SM-IC,H86355-001
VR_FET_SW_P12V_STBY_PVPP_GHJ EU4G1            12       NCP3232L_SM-IC,H86355-001
VR_FET_SW_P12V_STBY_PVPP_GHJ EU4G1            13       NCP3232L_SM-IC,H86355-001
VR_FET_SW_P12V_STBY_PVPP_GHJ EU4G1            14       NCP3232L_SM-IC,H86355-001
VR_FET_SW_P12V_STBY_PVPP_GHJ EU4G1            39       NCP3232L_SM-IC,H86355-001
VR_FET_SW_P12V_STBY_PVPP_GHJ EU4G1            42       NCP3232L_SM-IC,H86355-001
VR_FET_SW_P12V_STBY_PVPP_GHJ FB4G1            2        FERRITE_SM-22,FB,656554-051
VR_FET_SW_P12V_STBY_PVPP_KLM C4A19            1        CAP_0805-10UF,16V,10%,X6S,C953A
VR_FET_SW_P12V_STBY_PVPP_KLM C4A20            1        CAP_A_0402V-0.1UF,16V,10%,X7R,A
VR_FET_SW_P12V_STBY_PVPP_KLM C4B1             1        CAP_1210-47UF,16V,20%,X6S,D384A
VR_FET_SW_P12V_STBY_PVPP_KLM C6L10            1        CAP_0805-10UF,16V,10%,X6S,C953A
VR_FET_SW_P12V_STBY_PVPP_KLM C6L11            1        CAP_0402-1.0UF,16V,10%,X6S,D97A
VR_FET_SW_P12V_STBY_PVPP_KLM C6M3             1        CAP_0805-10UF,16V,10%,X6S,C953A
VR_FET_SW_P12V_STBY_PVPP_KLM C6M5             1        CAP_0805-10UF,16V,10%,X6S,C953A
VR_FET_SW_P12V_STBY_PVPP_KLM EU4A3            8        NCP3232L_SM-IC,H86355-001
VR_FET_SW_P12V_STBY_PVPP_KLM EU4A3            9        NCP3232L_SM-IC,H86355-001
VR_FET_SW_P12V_STBY_PVPP_KLM EU4A3            10       NCP3232L_SM-IC,H86355-001
VR_FET_SW_P12V_STBY_PVPP_KLM EU4A3            11       NCP3232L_SM-IC,H86355-001
VR_FET_SW_P12V_STBY_PVPP_KLM EU4A3            12       NCP3232L_SM-IC,H86355-001
VR_FET_SW_P12V_STBY_PVPP_KLM EU4A3            13       NCP3232L_SM-IC,H86355-001
VR_FET_SW_P12V_STBY_PVPP_KLM EU4A3            14       NCP3232L_SM-IC,H86355-001
VR_FET_SW_P12V_STBY_PVPP_KLM EU4A3            39       NCP3232L_SM-IC,H86355-001
VR_FET_SW_P12V_STBY_PVPP_KLM EU4A3            42       NCP3232L_SM-IC,H86355-001
VR_FET_SW_P12V_STBY_PVPP_KLM FB4A1            2        FERRITE_SM-22,FB,656554-051
VR_FET_SW_P5V_STBY_PVIN  C7E11            1        CAP_1206LF-22UF,16V,10%,X6S,D3A
VR_FET_SW_P5V_STBY_PVIN  C7E12            1        CAP_1210-47UF,16V,20%,X6S,D384A
VR_FET_SW_P5V_STBY_PVIN  C7E13            1        CAP_1210-47UF,16V,20%,X6S,D384A
VR_FET_SW_P5V_STBY_PVIN  EU7E2            4        TPS54821_LCC-IC,H63269-001
VR_FET_SW_P5V_STBY_PVIN  EU7E2            5        TPS54821_LCC-IC,H63269-001
VR_FET_SW_P5V_STBY_PVIN  FB7E1            2        FERRITE_SM-22,FB,656554-051
VR_FET_SW_P5V_STBY_PVIN  R7E17            1        RES_0402-0.0,5%,1/16W,CHIP,G21A
VR_P1V05_PCH_BIREF1      CTI67            1        CAP_A_0402V-0.1UF,16V,10%,X7R,A
VR_P1V05_PCH_BIREF1      EU7A2            39       IR354XX_SM-IR35412,IC,H73684-0A
VR_P1V05_PCH_BIREF1      EU8A1            25       PXE1110B_QFN-IC,H89187-001
VR_P1V05_PCH_BIREF1      R2L7             2        RES_0402-0.0,5%,1/16W,CHIP,G21A
VR_P1V05_PCH_STBY_AVSP   C2L2             1        CAP_0402LF-220PF,50V,10%,X7R,AA
VR_P1V05_PCH_STBY_AVSP   EU8A1            29       PXE1110B_QFN-IC,H89187-001
VR_P1V05_PCH_STBY_AVSP   R2L8             2        RES_0603-10.0,1%,1/10W,CHIP,G2A
VR_P1V05_PCH_STBY_OCSET  EU7A2            37       IR354XX_SM-IR35412,IC,H73684-0A
VR_P1V05_PCH_STBY_OCSET  R3L14            1        RES_0402-68.1K,1%,1/16W,EMPTY,A
VR_P1V05_PCH_STBY_PH1_BOOT C7A44            1        CAP_0402-0.220UF,16V,10%,X7R,AA
VR_P1V05_PCH_STBY_PH1_BOOT RTI46            1        2D2R2F-GP_SMD-RG1-2D2R2F-GP,64A
VR_P1V05_PCH_STBY_PH1_BOOT_R EU7A2            33       IR354XX_SM-IR35412,IC,H73684-0A
VR_P1V05_PCH_STBY_PH1_BOOT_R RTI46            2        2D2R2F-GP_SMD-RG1-2D2R2F-GP,64A
VR_P1V05_PCH_STBY_PH1_PHASE C7A44            2        CAP_0402-0.220UF,16V,10%,X7R,AA
VR_P1V05_PCH_STBY_PH1_PHASE EU7A2            32       IR354XX_SM-IR35412,IC,H73684-0A
VR_P1V05_PCH_STBY_PH1_PHASE_SW CTI68            1        SC2K2P50V3KX-GP_SMD-BCG6-SC2K2A
VR_P1V05_PCH_STBY_PH1_PHASE_SW EU7A2            10       IR354XX_SM-IR35412,IC,H73684-0A
VR_P1V05_PCH_STBY_PH1_PHASE_SW L7A4             1        INDUCTOR_SM-0.3UH,IND,D92183-0A
VR_P1V05_PCH_STBY_PH1_VCIN C7A10            1        CAP_0402-1.0UF,16V,10%,X6S,D97A
VR_P1V05_PCH_STBY_PH1_VCIN EU7A2            3        IR354XX_SM-IR35412,IC,H73684-0A
VR_P1V05_PCH_STBY_PH1_VCIN R3L4             1        RES_0402-1.0,1%,1/16W,CHIP,G21A
VR_P1V05_PCH_STBY_PWM1   EU7A2            34       IR354XX_SM-IR35412,IC,H73684-0A
VR_P1V05_PCH_STBY_PWM1   EU8A1            3        PXE1110B_QFN-IC,H89187-001
VR_P1V26_BMC_STBY_FB     EU9F1            4        RT9059_DFN-IC,H65765-001
VR_P1V26_BMC_STBY_FB     R9F6             2        RES_0402-5.76K,1%,1/16W,CHIP,GA
VR_P1V26_BMC_STBY_FB     R9F8             2        RES_0402-10.0K,1%,1/16W,CHIP,GA
VR_P1V538_BMC_STBY_FB    EU9F2            4        RT9059_DFN-IC,H65765-001
VR_P1V538_BMC_STBY_FB    R9F31            2        RES_0402-12K,1%,1/16W,CHIP,G21A
VR_P1V538_BMC_STBY_FB    R9F32            2        RES_0402-13K,1.0%,1/16W,CHIP,GA
VR_P1V8_PCH_STBY_FB      EU8A2            4        RT9059_DFN-IC,H65765-001
VR_P1V8_PCH_STBY_FB      R2L19            1        RES_0402-49.9K,1%,1/16W,CHIP,GA
VR_P1V8_PCH_STBY_FB      R2L20            2        RES_0402-63.4K,1.0%,1/16W,CHIPA
VR_P3V3_STBY_BOOT        EU8F1            4        RT8240_QFN-IC,H66262-001
VR_P3V3_STBY_BOOT        R8E35            1        RES_0402-0.0,5%,1/16W,CHIP,G21A
VR_P3V3_STBY_BOOT_R      C8E12            2        CAP_0603LF-0.1UF,25V,10%,X7R,6A
VR_P3V3_STBY_BOOT_R      R8E35            2        RES_0402-0.0,5%,1/16W,CHIP,G21A
VR_P3V3_STBY_EN          EU8F1            8        RT8240_QFN-IC,H66262-001
VR_P3V3_STBY_EN          R8E40            2        RES_0402-100.0K,1%,1/16W,EMPTYA
VR_P3V3_STBY_EN          R8F2             2        RES_0402-0.0,5%,1/16W,CHIP,G21A
VR_P3V3_STBY_LGATE       EU8E1            4        CSD87384M_SM-IC,H66258-001
VR_P3V3_STBY_LGATE       EU8F1            1        RT8240_QFN-IC,H66262-001
VR_P3V3_STBY_OCSELECT    EU8F1            10       RT8240_QFN-IC,H66262-001
VR_P3V3_STBY_OCSELECT    R8F9             1        RES_0402-64.9K,1%,1/16W,CHIP,GA
VR_P3V3_STBY_PHASE       C8E12            1        CAP_0603LF-0.1UF,25V,10%,X7R,6A
VR_P3V3_STBY_PHASE       C8F3             1        CAP_0402LF-3300PF,50V,10%,EMPTA
VR_P3V3_STBY_PHASE       EU8E1            5        CSD87384M_SM-IC,H66258-001
VR_P3V3_STBY_PHASE       EU8F1            2        RT8240_QFN-IC,H66262-001
VR_P3V3_STBY_PHASE       L8F1             1        INDUCTOR_SM-1.00UH,IND,E98679-A
VR_P3V3_STBY_SNUB        C8F3             2        CAP_0402LF-3300PF,50V,10%,EMPTA
VR_P3V3_STBY_SNUB        R8F3             1        RES_0402-2.2,5%,1/16W,EMPTY,G2A
VR_P3V3_STBY_UGATE       EU8E1            1        CSD87384M_SM-IC,H66258-001
VR_P3V3_STBY_UGATE       EU8F1            3        RT8240_QFN-IC,H66262-001
VR_P5V_STBY_BOOT         C8E6             1        CAP_0603LF-0.1UF,25V,10%,X7R,6A
VR_P5V_STBY_BOOT         EU7E2            13       TPS54821_LCC-IC,H63269-001
VR_P5V_STBY_COMP         C8E16            1        CAP_0402LF-270PF,50V,10%,X7R,AA
VR_P5V_STBY_COMP         EU7E2            8        TPS54821_LCC-IC,H63269-001
VR_P5V_STBY_COMP         R8E39            1        RES_0402-24.9K,1%,1/16W,CHIP,GA
VR_P5V_STBY_EN           EU7E2            10       TPS54821_LCC-IC,H63269-001
VR_P5V_STBY_EN           R8E33            2        RES_0402-0.0,5%,1/16W,CHIP,G21A
VR_P5V_STBY_PHASE        C8E6             2        CAP_0603LF-0.1UF,25V,10%,X7R,6A
VR_P5V_STBY_PHASE        EU7E2            11       TPS54821_LCC-IC,H63269-001
VR_P5V_STBY_PHASE        EU7E2            12       TPS54821_LCC-IC,H63269-001
VR_P5V_STBY_PHASE        L8E1             1        INDUCTOR_SM-2.2UH,IND,E98761-0A
VR_P5V_STBY_RC_COMP      C8F1             1        CAP_0402LF-2200PF,50V,10%,X7R,A
VR_P5V_STBY_RC_COMP      R8E39            2        RES_0402-24.9K,1%,1/16W,CHIP,GA
VR_P5V_STBY_RT           EU7E2            1        TPS54821_LCC-IC,H63269-001
VR_P5V_STBY_RT           R7E14            1        RES_0402-75K,1%,1/16W,CHIP,G21A
VR_P5V_STBY_SS           C8E15            1        CAP_0402LF-0.022UF,16V,10%,X7RA
VR_P5V_STBY_SS           EU7E2            9        TPS54821_LCC-IC,H63269-001
VR_P5V_STBY_VIN          C7E14            1        CAP_0402-1.0UF,16V,10%,X6S,D97A
VR_P5V_STBY_VIN          EU7E2            6        TPS54821_LCC-IC,H63269-001
VR_P5V_STBY_VIN          R7E17            2        RES_0402-0.0,5%,1/16W,CHIP,G21A
VR_P5V_STBY_VSENSE       EU7E2            7        TPS54821_LCC-IC,H63269-001
VR_P5V_STBY_VSENSE       R7E16            1        RES_0402-1.37K,1%,1/16W,CHIP,GA
VR_P5V_STBY_VSENSE       R7F1             2        RES_0402-10.0K,1%,1/16W,CHIP,GA
VR_P5V_STBY_VSENSE_R     R7F1             1        RES_0402-10.0K,1%,1/16W,CHIP,GA
VR_P5V_STBY_VSENSE_R     R8E37            1        RES_0402-0.0,5%,1/16W,CHIP,G21A
VR_PVCCIN_CPU0_AIREF1    CTI1             1        CAP_A_0402V-0.1UF,16V,10%,X7R,A
VR_PVCCIN_CPU0_AIREF1    EU4D4            23       PXE1610B_QFN-IC,H79206-001
VR_PVCCIN_CPU0_AIREF1    EU4E1            39       IR354XX_SM-IR35411,IC,H73688-0A
VR_PVCCIN_CPU0_AIREF1    R6P43            2        RES_0402-0.0,5%,1/16W,CHIP,G21A
VR_PVCCIN_CPU0_AIREF2    CTI6             1        CAP_A_0402V-0.1UF,16V,10%,X7R,A
VR_PVCCIN_CPU0_AIREF2    EU4D4            25       PXE1610B_QFN-IC,H79206-001
VR_PVCCIN_CPU0_AIREF2    EU4D6            39       IR354XX_SM-IR35411,IC,H73688-0A
VR_PVCCIN_CPU0_AIREF2    R6P42            2        RES_0402-0.0,5%,1/16W,CHIP,G21A
VR_PVCCIN_CPU0_AIREF3    CTI39            1        CAP_A_0402V-0.1UF,16V,10%,X7R,A
VR_PVCCIN_CPU0_AIREF3    EU4D3            39       IR354XX_SM-IR35411,IC,H73688-0A
VR_PVCCIN_CPU0_AIREF3    EU4D4            27       PXE1610B_QFN-IC,H79206-001
VR_PVCCIN_CPU0_AIREF3    R6P38            2        RES_0402-0.0,5%,1/16W,CHIP,G21A
VR_PVCCIN_CPU0_AIREF4    CTI40            1        CAP_A_0402V-0.1UF,16V,10%,X7R,A
VR_PVCCIN_CPU0_AIREF4    EU4D1            39       IR354XX_SM-IR35411,IC,H73688-0A
VR_PVCCIN_CPU0_AIREF4    EU4D4            29       PXE1610B_QFN-IC,H79206-001
VR_PVCCIN_CPU0_AIREF4    R6P34            2        RES_0402-0.0,5%,1/16W,CHIP,G21A
VR_PVCCIN_CPU0_AIREF5    CTI36            1        CAP_A_0402V-0.1UF,16V,10%,X7R,A
VR_PVCCIN_CPU0_AIREF5    EU4C2            39       IR354XX_SM-IR35411,IC,H73688-0A
VR_PVCCIN_CPU0_AIREF5    EU4D4            31       PXE1610B_QFN-IC,H79206-001
VR_PVCCIN_CPU0_AIREF5    R6P30            2        RES_0402-0.0,5%,1/16W,CHIP,G21A
VR_PVCCIN_CPU0_AVINSEN   C4D20            1        CAP_0402LF-1000PF,50V,10%,X7R,A
VR_PVCCIN_CPU0_AVINSEN   EU4D4            45       PXE1610B_QFN-IC,H79206-001
VR_PVCCIN_CPU0_AVINSEN   R4D27            2        RES_0402-100.0K,1%,1/16W,CHIP,B
VR_PVCCIN_CPU0_AVINSEN   R4D32            1        RES_0402-1.5K,1%,1/16W,CHIP,G2A
VR_PVCCIN_CPU0_PH1_BOOT  C4E17            1        CAP_0402-0.220UF,16V,10%,X7R,AA
VR_PVCCIN_CPU0_PH1_BOOT  RTI1             1        2D2R2F-GP_SMD-RG1-2D2R2F-GP,64A
VR_PVCCIN_CPU0_PH1_BOOT_R EU4E1            33       IR354XX_SM-IR35411,IC,H73688-0A
VR_PVCCIN_CPU0_PH1_BOOT_R RTI1             2        2D2R2F-GP_SMD-RG1-2D2R2F-GP,64A
VR_PVCCIN_CPU0_PH1_OCSET EU4E1            37       IR354XX_SM-IR35411,IC,H73688-0A
VR_PVCCIN_CPU0_PH1_OCSET R4E22            1        RES_0402-68.1K,1%,1/16W,EMPTY,A
VR_PVCCIN_CPU0_PH1_PHASE C4E17            2        CAP_0402-0.220UF,16V,10%,X7R,AA
VR_PVCCIN_CPU0_PH1_PHASE EU4E1            32       IR354XX_SM-IR35411,IC,H73688-0A
VR_PVCCIN_CPU0_PH1_VCIN  C4E10            1        CAP_0402-1.0UF,16V,10%,X6S,D97A
VR_PVCCIN_CPU0_PH1_VCIN  EU4E1            3        IR354XX_SM-IR35411,IC,H73688-0A
VR_PVCCIN_CPU0_PH1_VCIN  R6R2             1        RES_0402-1.0,1%,1/16W,CHIP,G21A
VR_PVCCIN_CPU0_PH2_BOOT  C4D50            1        CAP_0402-0.220UF,16V,10%,X7R,AA
VR_PVCCIN_CPU0_PH2_BOOT  RTI3             1        2D2R2F-GP_SMD-RG1-2D2R2F-GP,64A
VR_PVCCIN_CPU0_PH2_BOOT_R EU4D6            33       IR354XX_SM-IR35411,IC,H73688-0A
VR_PVCCIN_CPU0_PH2_BOOT_R RTI3             2        2D2R2F-GP_SMD-RG1-2D2R2F-GP,64A
VR_PVCCIN_CPU0_PH2_OCSET EU4D6            37       IR354XX_SM-IR35411,IC,H73688-0A
VR_PVCCIN_CPU0_PH2_OCSET R4E19            1        RES_0402-68.1K,1%,1/16W,EMPTY,A
VR_PVCCIN_CPU0_PH2_PHASE C4D50            2        CAP_0402-0.220UF,16V,10%,X7R,AA
VR_PVCCIN_CPU0_PH2_PHASE EU4D6            32       IR354XX_SM-IR35411,IC,H73688-0A
VR_PVCCIN_CPU0_PH2_VCIN  C4E26            1        CAP_0402-1.0UF,16V,10%,X6S,D97A
VR_PVCCIN_CPU0_PH2_VCIN  EU4D6            3        IR354XX_SM-IR35411,IC,H73688-0A
VR_PVCCIN_CPU0_PH2_VCIN  R6R6             1        RES_0402-1.0,1%,1/16W,CHIP,G21A
VR_PVCCIN_CPU0_PH3_BOOT  C4D28            1        CAP_0402-0.220UF,16V,10%,X7R,AA
VR_PVCCIN_CPU0_PH3_BOOT  RTI25            1        2D2R2F-GP_SMD-RG1-2D2R2F-GP,64A
VR_PVCCIN_CPU0_PH3_BOOT_R EU4D3            33       IR354XX_SM-IR35411,IC,H73688-0A
VR_PVCCIN_CPU0_PH3_BOOT_R RTI25            2        2D2R2F-GP_SMD-RG1-2D2R2F-GP,64A
VR_PVCCIN_CPU0_PH3_OCSET EU4D3            37       IR354XX_SM-IR35411,IC,H73688-0A
VR_PVCCIN_CPU0_PH3_OCSET R4D72            1        RES_0402-68.1K,1%,1/16W,EMPTY,A
VR_PVCCIN_CPU0_PH3_PHASE C4D28            2        CAP_0402-0.220UF,16V,10%,X7R,AA
VR_PVCCIN_CPU0_PH3_PHASE EU4D3            32       IR354XX_SM-IR35411,IC,H73688-0A
VR_PVCCIN_CPU0_PH3_VCIN  C4D16            1        CAP_0402-1.0UF,16V,10%,X6S,D97A
VR_PVCCIN_CPU0_PH3_VCIN  EU4D3            3        IR354XX_SM-IR35411,IC,H73688-0A
VR_PVCCIN_CPU0_PH3_VCIN  R6P19            1        RES_0402-1.0,1%,1/16W,CHIP,G21A
VR_PVCCIN_CPU0_PH4_BOOT  C4D9             1        CAP_0402-0.220UF,16V,10%,X7R,AA
VR_PVCCIN_CPU0_PH4_BOOT  RTI28            1        2D2R2F-GP_SMD-RG1-2D2R2F-GP,64A
VR_PVCCIN_CPU0_PH4_BOOT_R EU4D1            33       IR354XX_SM-IR35411,IC,H73688-0A
VR_PVCCIN_CPU0_PH4_BOOT_R RTI28            2        2D2R2F-GP_SMD-RG1-2D2R2F-GP,64A
VR_PVCCIN_CPU0_PH4_OCSET EU4D1            37       IR354XX_SM-IR35411,IC,H73688-0A
VR_PVCCIN_CPU0_PH4_OCSET R4D71            1        RES_0402-68.1K,1%,1/16W,EMPTY,A
VR_PVCCIN_CPU0_PH4_PHASE C4D9             2        CAP_0402-0.220UF,16V,10%,X7R,AA
VR_PVCCIN_CPU0_PH4_PHASE EU4D1            32       IR354XX_SM-IR35411,IC,H73688-0A
VR_PVCCIN_CPU0_PH4_VCIN  C4D7             1        CAP_0402-1.0UF,16V,10%,X6S,D97A
VR_PVCCIN_CPU0_PH4_VCIN  EU4D1            3        IR354XX_SM-IR35411,IC,H73688-0A
VR_PVCCIN_CPU0_PH4_VCIN  R6P10            1        RES_0402-1.0,1%,1/16W,CHIP,G21A
VR_PVCCIN_CPU0_PH5_BOOT  C4C17            1        CAP_0402-0.220UF,16V,10%,X7R,AA
VR_PVCCIN_CPU0_PH5_BOOT  RTI23            1        2D2R2F-GP_SMD-RG1-2D2R2F-GP,64A
VR_PVCCIN_CPU0_PH5_BOOT_R EU4C2            33       IR354XX_SM-IR35411,IC,H73688-0A
VR_PVCCIN_CPU0_PH5_BOOT_R RTI23            2        2D2R2F-GP_SMD-RG1-2D2R2F-GP,64A
VR_PVCCIN_CPU0_PH5_OCSET EU4C2            37       IR354XX_SM-IR35411,IC,H73688-0A
VR_PVCCIN_CPU0_PH5_OCSET R4D68            1        RES_0402-68.1K,1%,1/16W,EMPTY,A
VR_PVCCIN_CPU0_PH5_PHASE C4C17            2        CAP_0402-0.220UF,16V,10%,X7R,AA
VR_PVCCIN_CPU0_PH5_PHASE EU4C2            32       IR354XX_SM-IR35411,IC,H73688-0A
VR_PVCCIN_CPU0_PH5_VCIN  C4D46            1        CAP_0402-1.0UF,16V,10%,X6S,D97A
VR_PVCCIN_CPU0_PH5_VCIN  EU4C2            3        IR354XX_SM-IR35411,IC,H73688-0A
VR_PVCCIN_CPU0_PH5_VCIN  R6P47            1        RES_0402-1.0,1%,1/16W,CHIP,G21A
VR_PVCCIN_CPU0_PHASE1    CTI3             1        SC2K2P50V3KX-GP_SMD-BCG6-SC2K2A
VR_PVCCIN_CPU0_PHASE1    EU4E1            10       IR354XX_SM-IR35411,IC,H73688-0A
VR_PVCCIN_CPU0_PHASE1    L4E1             1        INDUCTOR_SM-0.12UH,IND,D92183-A
VR_PVCCIN_CPU0_PHASE2    CTI5             1        SC2K2P50V3KX-GP_SMD-BCG6-SC2K2A
VR_PVCCIN_CPU0_PHASE2    EU4D6            10       IR354XX_SM-IR35411,IC,H73688-0A
VR_PVCCIN_CPU0_PHASE2    L4D3             1        INDUCTOR_SM-0.12UH,IND,D92183-A
VR_PVCCIN_CPU0_PHASE3    CTI38            1        SC2K2P50V3KX-GP_SMD-BCG6-SC2K2A
VR_PVCCIN_CPU0_PHASE3    EU4D3            10       IR354XX_SM-IR35411,IC,H73688-0A
VR_PVCCIN_CPU0_PHASE3    L4D2             1        INDUCTOR_SM-0.12UH,IND,D92183-A
VR_PVCCIN_CPU0_PHASE4    CTI41            1        SC2K2P50V3KX-GP_SMD-BCG6-SC2K2A
VR_PVCCIN_CPU0_PHASE4    EU4D1            10       IR354XX_SM-IR35411,IC,H73688-0A
VR_PVCCIN_CPU0_PHASE4    L4D1             1        INDUCTOR_SM-0.12UH,IND,D92183-A
VR_PVCCIN_CPU0_PHASE5    CTI35            1        SC2K2P50V3KX-GP_SMD-BCG6-SC2K2A
VR_PVCCIN_CPU0_PHASE5    EU4C2            10       IR354XX_SM-IR35411,IC,H73688-0A
VR_PVCCIN_CPU0_PHASE5    L4C3             1        INDUCTOR_SM-0.12UH,IND,D92183-A
VR_PVCCIN_CPU0_PWM1      EU4D4            7        PXE1610B_QFN-IC,H79206-001
VR_PVCCIN_CPU0_PWM1      EU4E1            34       IR354XX_SM-IR35411,IC,H73688-0A
VR_PVCCIN_CPU0_PWM2      EU4D4            6        PXE1610B_QFN-IC,H79206-001
VR_PVCCIN_CPU0_PWM2      EU4D6            34       IR354XX_SM-IR35411,IC,H73688-0A
VR_PVCCIN_CPU0_PWM3      EU4D3            34       IR354XX_SM-IR35411,IC,H73688-0A
VR_PVCCIN_CPU0_PWM3      EU4D4            5        PXE1610B_QFN-IC,H79206-001
VR_PVCCIN_CPU0_PWM4      EU4D1            34       IR354XX_SM-IR35411,IC,H73688-0A
VR_PVCCIN_CPU0_PWM4      EU4D4            4        PXE1610B_QFN-IC,H79206-001
VR_PVCCIN_CPU0_PWM5      EU4C2            34       IR354XX_SM-IR35411,IC,H73688-0A
VR_PVCCIN_CPU0_PWM5      EU4D4            3        PXE1610B_QFN-IC,H79206-001
VR_PVCCIN_CPU0_VD12      C4D25            1        CAP_A_0402V-1.0UF,6.3V,10%,X6SA
VR_PVCCIN_CPU0_VD12      C4D26            1        CAP_A_0402V-0.1UF,16V,10%,X7R,A
VR_PVCCIN_CPU0_VD12      EU4D4            48       PXE1610B_QFN-IC,H79206-001
VR_PVCCIN_CPU0_VD12      R6P29            1        RES_0402-0.0,5%,1/16W,CHIP,G21A
VR_PVCCIN_CPU0_VD12      R6P30            1        RES_0402-0.0,5%,1/16W,CHIP,G21A
VR_PVCCIN_CPU0_VD12      R6P34            1        RES_0402-0.0,5%,1/16W,CHIP,G21A
VR_PVCCIN_CPU0_VD12      R6P38            1        RES_0402-0.0,5%,1/16W,CHIP,G21A
VR_PVCCIN_CPU0_VD12      R6P42            1        RES_0402-0.0,5%,1/16W,CHIP,G21A
VR_PVCCIN_CPU0_VD12      R6P43            1        RES_0402-0.0,5%,1/16W,CHIP,G21A
VR_PVCCIN_CPU0_VDD       C4D15            1        CAP_A_0402V-1.0UF,6.3V,10%,X6SA
VR_PVCCIN_CPU0_VDD       C4D19            1        CAP_A_0402V-0.1UF,16V,10%,X7R,A
VR_PVCCIN_CPU0_VDD       EU4D4            47       PXE1610B_QFN-IC,H79206-001
VR_PVCCIN_CPU0_VDD       R4D26            2        RES_0402-0.0,5%,1/16W,CHIP,G21A
VR_PVCCIN_CPU0_VREN      EU4D4            12       PXE1610B_QFN-IC,H79206-001
VR_PVCCIN_CPU0_VREN      R6P16            2        RES_0402-1.00K,1%,1/16W,CHIP,GA
VR_PVCCIN_CPU0_VREN      R6P18            2        RES_0402-0.0,5%,1/16W,CHIP,G21A
VR_PVCCIN_CPU0_XADDR1    EU4D4            44       PXE1610B_QFN-IC,H79206-001
VR_PVCCIN_CPU0_XADDR1    R6P28            1        RES_0402-4.02K,1%,1/16W,CHIP,GA
VR_PVCCIN_CPU0_XADDR2    EU4D4            41       PXE1610B_QFN-IC,H79206-001
VR_PVCCIN_CPU0_XADDR2    R6P27            1        RES_0402-4.02K,1%,1/16W,CHIP,GA
VR_PVCCIN_CPU1_AIREF1    CTI24            1        CAP_A_0402V-0.1UF,16V,10%,X7R,A
VR_PVCCIN_CPU1_AIREF1    EU1C2            23       PXE1610B_QFN-IC,H79206-001
VR_PVCCIN_CPU1_AIREF1    EU1E2            39       IR354XX_SM-IR35411,IC,H73688-0A
VR_PVCCIN_CPU1_AIREF1    R9N15            2        RES_0402-0.0,5%,1/16W,CHIP,G21A
VR_PVCCIN_CPU1_AIREF2    CTI25            1        CAP_A_0402V-0.1UF,16V,10%,X7R,A
VR_PVCCIN_CPU1_AIREF2    EU1C2            25       PXE1610B_QFN-IC,H79206-001
VR_PVCCIN_CPU1_AIREF2    EU1D4            39       IR354XX_SM-IR35411,IC,H73688-0A
VR_PVCCIN_CPU1_AIREF2    R9N17            2        RES_0402-0.0,5%,1/16W,CHIP,G21A
VR_PVCCIN_CPU1_AIREF3    CTI16            1        CAP_A_0402V-0.1UF,16V,10%,X7R,A
VR_PVCCIN_CPU1_AIREF3    EU1C2            27       PXE1610B_QFN-IC,H79206-001
VR_PVCCIN_CPU1_AIREF3    EU1D3            39       IR354XX_SM-IR35411,IC,H73688-0A
VR_PVCCIN_CPU1_AIREF3    R9N12            2        RES_0402-0.0,5%,1/16W,CHIP,G21A
VR_PVCCIN_CPU1_AIREF4    CTI21            1        CAP_A_0402V-0.1UF,16V,10%,X7R,A
VR_PVCCIN_CPU1_AIREF4    EU1C2            29       PXE1610B_QFN-IC,H79206-001
VR_PVCCIN_CPU1_AIREF4    EU1D1            39       IR354XX_SM-IR35411,IC,H73688-0A
VR_PVCCIN_CPU1_AIREF4    R9N10            2        RES_0402-0.0,5%,1/16W,CHIP,G21A
VR_PVCCIN_CPU1_AIREF5    CTI13            1        CAP_A_0402V-0.1UF,16V,10%,X7R,A
VR_PVCCIN_CPU1_AIREF5    EU1C2            31       PXE1610B_QFN-IC,H79206-001
VR_PVCCIN_CPU1_AIREF5    EU1C3            39       IR354XX_SM-IR35411,IC,H73688-0A
VR_PVCCIN_CPU1_AIREF5    R9N9             2        RES_0402-0.0,5%,1/16W,CHIP,G21A
VR_PVCCIN_CPU1_AVINSEN   C1C8             1        CAP_0402LF-1000PF,50V,10%,X7R,A
VR_PVCCIN_CPU1_AVINSEN   EU1C2            45       PXE1610B_QFN-IC,H79206-001
VR_PVCCIN_CPU1_AVINSEN   R1C13            2        RES_0402-100.0K,1%,1/16W,CHIP,B
VR_PVCCIN_CPU1_AVINSEN   R1C16            1        RES_0402-1.5K,1%,1/16W,CHIP,G2A
VR_PVCCIN_CPU1_PH1_BOOT  C1E11            1        CAP_0402-0.220UF,16V,10%,X7R,AA
VR_PVCCIN_CPU1_PH1_BOOT  RTI15            1        2D2R2F-GP_SMD-RG1-2D2R2F-GP,64A
VR_PVCCIN_CPU1_PH1_BOOT_R EU1E2            33       IR354XX_SM-IR35411,IC,H73688-0A
VR_PVCCIN_CPU1_PH1_BOOT_R RTI15            2        2D2R2F-GP_SMD-RG1-2D2R2F-GP,64A
VR_PVCCIN_CPU1_PH1_OCSET EU1E2            37       IR354XX_SM-IR35411,IC,H73688-0A
VR_PVCCIN_CPU1_PH1_OCSET R1E14            1        RES_0402-68.1K,1%,1/16W,EMPTY,A
VR_PVCCIN_CPU1_PH1_PHASE C1E11            2        CAP_0402-0.220UF,16V,10%,X7R,AA
VR_PVCCIN_CPU1_PH1_PHASE EU1E2            32       IR354XX_SM-IR35411,IC,H73688-0A
VR_PVCCIN_CPU1_PH1_VCIN  C1E8             1        CAP_0402-1.0UF,16V,10%,X6S,D97A
VR_PVCCIN_CPU1_PH1_VCIN  EU1E2            3        IR354XX_SM-IR35411,IC,H73688-0A
VR_PVCCIN_CPU1_PH1_VCIN  R9R2             1        RES_0402-1.0,1%,1/16W,CHIP,G21A
VR_PVCCIN_CPU1_PH2_BOOT  C1D36            1        CAP_0402-0.220UF,16V,10%,X7R,AA
VR_PVCCIN_CPU1_PH2_BOOT  RTI17            1        2D2R2F-GP_SMD-RG1-2D2R2F-GP,64A
VR_PVCCIN_CPU1_PH2_BOOT_R EU1D4            33       IR354XX_SM-IR35411,IC,H73688-0A
VR_PVCCIN_CPU1_PH2_BOOT_R RTI17            2        2D2R2F-GP_SMD-RG1-2D2R2F-GP,64A
VR_PVCCIN_CPU1_PH2_OCSET EU1D4            37       IR354XX_SM-IR35411,IC,H73688-0A
VR_PVCCIN_CPU1_PH2_OCSET R1E13            1        RES_0402-68.1K,1%,1/16W,EMPTY,A
VR_PVCCIN_CPU1_PH2_PHASE C1D36            2        CAP_0402-0.220UF,16V,10%,X7R,AA
VR_PVCCIN_CPU1_PH2_PHASE EU1D4            32       IR354XX_SM-IR35411,IC,H73688-0A
VR_PVCCIN_CPU1_PH2_VCIN  C1E24            1        CAP_0402-1.0UF,16V,10%,X6S,D97A
VR_PVCCIN_CPU1_PH2_VCIN  EU1D4            3        IR354XX_SM-IR35411,IC,H73688-0A
VR_PVCCIN_CPU1_PH2_VCIN  R9R11            1        RES_0402-1.0,1%,1/16W,CHIP,G21A
VR_PVCCIN_CPU1_PH3_BOOT  C1D20            1        CAP_0402-0.220UF,16V,10%,X7R,AA
VR_PVCCIN_CPU1_PH3_BOOT  RTI11            1        2D2R2F-GP_SMD-RG1-2D2R2F-GP,64A
VR_PVCCIN_CPU1_PH3_BOOT_R EU1D3            33       IR354XX_SM-IR35411,IC,H73688-0A
VR_PVCCIN_CPU1_PH3_BOOT_R RTI11            2        2D2R2F-GP_SMD-RG1-2D2R2F-GP,64A
VR_PVCCIN_CPU1_PH3_OCSET EU1D3            37       IR354XX_SM-IR35411,IC,H73688-0A
VR_PVCCIN_CPU1_PH3_OCSET R1D55            1        RES_0402-68.1K,1%,1/16W,EMPTY,A
VR_PVCCIN_CPU1_PH3_PHASE C1D20            2        CAP_0402-0.220UF,16V,10%,X7R,AA
VR_PVCCIN_CPU1_PH3_PHASE EU1D3            32       IR354XX_SM-IR35411,IC,H73688-0A
VR_PVCCIN_CPU1_PH3_VCIN  C1D17            1        CAP_0402-1.0UF,16V,10%,X6S,D97A
VR_PVCCIN_CPU1_PH3_VCIN  EU1D3            3        IR354XX_SM-IR35411,IC,H73688-0A
VR_PVCCIN_CPU1_PH3_VCIN  R9P22            1        RES_0402-1.0,1%,1/16W,CHIP,G21A
VR_PVCCIN_CPU1_PH4_BOOT  C1D10            1        CAP_0402-0.220UF,16V,10%,X7R,AA
VR_PVCCIN_CPU1_PH4_BOOT  RTI14            1        2D2R2F-GP_SMD-RG1-2D2R2F-GP,64A
VR_PVCCIN_CPU1_PH4_BOOT_R EU1D1            33       IR354XX_SM-IR35411,IC,H73688-0A
VR_PVCCIN_CPU1_PH4_BOOT_R RTI14            2        2D2R2F-GP_SMD-RG1-2D2R2F-GP,64A
VR_PVCCIN_CPU1_PH4_OCSET EU1D1            37       IR354XX_SM-IR35411,IC,H73688-0A
VR_PVCCIN_CPU1_PH4_OCSET R1D54            1        RES_0402-68.1K,1%,1/16W,EMPTY,A
VR_PVCCIN_CPU1_PH4_PHASE C1D10            2        CAP_0402-0.220UF,16V,10%,X7R,AA
VR_PVCCIN_CPU1_PH4_PHASE EU1D1            32       IR354XX_SM-IR35411,IC,H73688-0A
VR_PVCCIN_CPU1_PH4_VCIN  C1D7             1        CAP_0402-1.0UF,16V,10%,X6S,D97A
VR_PVCCIN_CPU1_PH4_VCIN  EU1D1            3        IR354XX_SM-IR35411,IC,H73688-0A
VR_PVCCIN_CPU1_PH4_VCIN  R9P8             1        RES_0402-1.0,1%,1/16W,CHIP,G21A
VR_PVCCIN_CPU1_PH5_BOOT  C1C24            1        CAP_0402-0.220UF,16V,10%,X7R,AA
VR_PVCCIN_CPU1_PH5_BOOT  RTI9             1        2D2R2F-GP_SMD-RG1-2D2R2F-GP,64A
VR_PVCCIN_CPU1_PH5_BOOT_R EU1C3            33       IR354XX_SM-IR35411,IC,H73688-0A
VR_PVCCIN_CPU1_PH5_BOOT_R RTI9             2        2D2R2F-GP_SMD-RG1-2D2R2F-GP,64A
VR_PVCCIN_CPU1_PH5_OCSET EU1C3            37       IR354XX_SM-IR35411,IC,H73688-0A
VR_PVCCIN_CPU1_PH5_OCSET R1D52            1        RES_0402-68.1K,1%,1/16W,EMPTY,A
VR_PVCCIN_CPU1_PH5_PHASE C1C24            2        CAP_0402-0.220UF,16V,10%,X7R,AA
VR_PVCCIN_CPU1_PH5_PHASE EU1C3            32       IR354XX_SM-IR35411,IC,H73688-0A
VR_PVCCIN_CPU1_PH5_VCIN  C1D32            1        CAP_0402-1.0UF,16V,10%,X6S,D97A
VR_PVCCIN_CPU1_PH5_VCIN  EU1C3            3        IR354XX_SM-IR35411,IC,H73688-0A
VR_PVCCIN_CPU1_PH5_VCIN  R9P32            1        RES_0402-1.0,1%,1/16W,CHIP,G21A
VR_PVCCIN_CPU1_PHASE1    CTI23            1        SC2K2P50V3KX-GP_SMD-BCG6-SC2K2A
VR_PVCCIN_CPU1_PHASE1    EU1E2            10       IR354XX_SM-IR35411,IC,H73688-0A
VR_PVCCIN_CPU1_PHASE1    L1E1             1        INDUCTOR_SM-0.12UH,IND,D92183-A
VR_PVCCIN_CPU1_PHASE2    CTI27            1        SC2K2P50V3KX-GP_SMD-BCG6-SC2K2A
VR_PVCCIN_CPU1_PHASE2    EU1D4            10       IR354XX_SM-IR35411,IC,H73688-0A
VR_PVCCIN_CPU1_PHASE2    L1D3             1        INDUCTOR_SM-0.12UH,IND,D92183-A
VR_PVCCIN_CPU1_PHASE3    CTI18            1        SC2K2P50V3KX-GP_SMD-BCG6-SC2K2A
VR_PVCCIN_CPU1_PHASE3    EU1D3            10       IR354XX_SM-IR35411,IC,H73688-0A
VR_PVCCIN_CPU1_PHASE3    L1D2             1        INDUCTOR_SM-0.12UH,IND,D92183-A
VR_PVCCIN_CPU1_PHASE4    CTI20            1        SC2K2P50V3KX-GP_SMD-BCG6-SC2K2A
VR_PVCCIN_CPU1_PHASE4    EU1D1            10       IR354XX_SM-IR35411,IC,H73688-0A
VR_PVCCIN_CPU1_PHASE4    L1D1             1        INDUCTOR_SM-0.12UH,IND,D92183-A
VR_PVCCIN_CPU1_PHASE5    CTI14            1        SC2K2P50V3KX-GP_SMD-BCG6-SC2K2A
VR_PVCCIN_CPU1_PHASE5    EU1C3            10       IR354XX_SM-IR35411,IC,H73688-0A
VR_PVCCIN_CPU1_PHASE5    L1C2             1        INDUCTOR_SM-0.12UH,IND,D92183-A
VR_PVCCIN_CPU1_PWM1      EU1C2            7        PXE1610B_QFN-IC,H79206-001
VR_PVCCIN_CPU1_PWM1      EU1E2            34       IR354XX_SM-IR35411,IC,H73688-0A
VR_PVCCIN_CPU1_PWM2      EU1C2            6        PXE1610B_QFN-IC,H79206-001
VR_PVCCIN_CPU1_PWM2      EU1D4            34       IR354XX_SM-IR35411,IC,H73688-0A
VR_PVCCIN_CPU1_PWM3      EU1C2            5        PXE1610B_QFN-IC,H79206-001
VR_PVCCIN_CPU1_PWM3      EU1D3            34       IR354XX_SM-IR35411,IC,H73688-0A
VR_PVCCIN_CPU1_PWM4      EU1C2            4        PXE1610B_QFN-IC,H79206-001
VR_PVCCIN_CPU1_PWM4      EU1D1            34       IR354XX_SM-IR35411,IC,H73688-0A
VR_PVCCIN_CPU1_PWM5      EU1C2            3        PXE1610B_QFN-IC,H79206-001
VR_PVCCIN_CPU1_PWM5      EU1C3            34       IR354XX_SM-IR35411,IC,H73688-0A
VR_PVCCIN_CPU1_VD12      C1C13            1        CAP_A_0402V-1.0UF,6.3V,10%,X6SA
VR_PVCCIN_CPU1_VD12      C1C14            1        CAP_A_0402V-0.1UF,16V,10%,X7R,A
VR_PVCCIN_CPU1_VD12      EU1C2            48       PXE1610B_QFN-IC,H79206-001
VR_PVCCIN_CPU1_VD12      R9N5             1        RES_0402-0.0,5%,1/16W,CHIP,G21A
VR_PVCCIN_CPU1_VD12      R9N9             1        RES_0402-0.0,5%,1/16W,CHIP,G21A
VR_PVCCIN_CPU1_VD12      R9N10            1        RES_0402-0.0,5%,1/16W,CHIP,G21A
VR_PVCCIN_CPU1_VD12      R9N12            1        RES_0402-0.0,5%,1/16W,CHIP,G21A
VR_PVCCIN_CPU1_VD12      R9N15            1        RES_0402-0.0,5%,1/16W,CHIP,G21A
VR_PVCCIN_CPU1_VD12      R9N17            1        RES_0402-0.0,5%,1/16W,CHIP,G21A
VR_PVCCIN_CPU1_VDD       C1C7             1        CAP_A_0402V-1.0UF,6.3V,10%,X6SA
VR_PVCCIN_CPU1_VDD       C1C9             1        CAP_A_0402V-0.1UF,16V,10%,X7R,A
VR_PVCCIN_CPU1_VDD       EU1C2            47       PXE1610B_QFN-IC,H79206-001
VR_PVCCIN_CPU1_VDD       R1C14            2        RES_0402-0.0,5%,1/16W,CHIP,G21A
VR_PVCCIN_CPU1_VREN      EU1C2            12       PXE1610B_QFN-IC,H79206-001
VR_PVCCIN_CPU1_VREN      R9N14            2        RES_0402-1.00K,1%,1/16W,CHIP,GA
VR_PVCCIN_CPU1_VREN      R9N16            2        RES_0402-0.0,5%,1/16W,CHIP,G21A
VR_PVCCIN_CPU1_XADDR1    EU1C2            44       PXE1610B_QFN-IC,H79206-001
VR_PVCCIN_CPU1_XADDR1    R9N8             1        RES_0402-4.02K,1%,1/16W,CHIP,GA
VR_PVCCIN_CPU1_XADDR2    EU1C2            41       PXE1610B_QFN-IC,H79206-001
VR_PVCCIN_CPU1_XADDR2    R9N7             1        RES_0402-3.16K,1%,1/16W,CHIP,GA
VR_PVCCIOMCP_CPU0_XADDR1 J6B1             E10      SCONN120_H61426002_SM-CONN,H61A
VR_PVCCIOMCP_CPU0_XADDR1 R3N29            1        RES_0402-16K,1.0%,1/16W,CHIP,GA
VR_PVCCIOMCP_CPU1_XADDR1 J4B2             E10      SCONN120_H61426002_SM-CONN,H61A
VR_PVCCIOMCP_CPU1_XADDR1 R4C12            1        RES_0402-8.06K,1%,1/16W,CHIP,GA
VR_PVCCIO_CPU0_AIREF1    CTI70            1        CAP_A_0402V-0.1UF,16V,10%,X7R,A
VR_PVCCIO_CPU0_AIREF1    EU3P1            21       PXE1110B_QFN-IC,H89187-001
VR_PVCCIO_CPU0_AIREF1    EU7C1            39       IR354XX_SM-IR35412,IC,H73684-0A
VR_PVCCIO_CPU0_AIREF1    R3P57            2        RES_0402-0.0,5%,1/16W,CHIP,G21A
VR_PVCCIO_CPU0_AVSP      C3N39            1        CAP_0402LF-220PF,50V,10%,X7R,AA
VR_PVCCIO_CPU0_AVSP      EU3P1            19       PXE1110B_QFN-IC,H89187-001
VR_PVCCIO_CPU0_AVSP      R3N19            2        RES_0402-10.0,1%,1/16W,CHIP,G2A
VR_PVCCIO_CPU0_EN        EU3P1            10       PXE1110B_QFN-IC,H89187-001
VR_PVCCIO_CPU0_EN        R3P21            2        RES_0402-100.0K,1%,1/16W,EMPTYA
VR_PVCCIO_CPU0_EN        R3P26            2        RES_0402-0.0,5%,1/16W,CHIP,G21A
VR_PVCCIO_CPU0_OCSET     EU7C1            37       IR354XX_SM-IR35412,IC,H73684-0A
VR_PVCCIO_CPU0_OCSET     R7C25            1        RES_0402-68.1K,1%,1/16W,EMPTY,A
VR_PVCCIO_CPU0_PH1_BOOT  C7C14            1        CAP_0402-0.220UF,16V,10%,X7R,AA
VR_PVCCIO_CPU0_PH1_BOOT  RTI47            1        2D2R2F-GP_SMD-RG1-2D2R2F-GP,64A
VR_PVCCIO_CPU0_PH1_BOOT_R EU7C1            33       IR354XX_SM-IR35412,IC,H73684-0A
VR_PVCCIO_CPU0_PH1_BOOT_R RTI47            2        2D2R2F-GP_SMD-RG1-2D2R2F-GP,64A
VR_PVCCIO_CPU0_PH1_PHASE C7C14            2        CAP_0402-0.220UF,16V,10%,X7R,AA
VR_PVCCIO_CPU0_PH1_PHASE EU7C1            32       IR354XX_SM-IR35412,IC,H73684-0A
VR_PVCCIO_CPU0_PH1_SW    CTI72            1        SC2K2P50V3KX-GP_SMD-BCG6-SC2K2A
VR_PVCCIO_CPU0_PH1_SW    EU7C1            10       IR354XX_SM-IR35412,IC,H73684-0A
VR_PVCCIO_CPU0_PH1_SW    L7C2             1        INDUCTOR_SM-150NH,IND,D92183-0A
VR_PVCCIO_CPU0_PH1_VCIN  C7C17            1        CAP_0402-1.0UF,16V,10%,X6S,D97A
VR_PVCCIO_CPU0_PH1_VCIN  EU7C1            3        IR354XX_SM-IR35412,IC,H73684-0A
VR_PVCCIO_CPU0_PH1_VCIN  R3N7             1        RES_0402-1.0,1%,1/16W,CHIP,G21A
VR_PVCCIO_CPU0_PWM1      EU3P1            5        PXE1110B_QFN-IC,H89187-001
VR_PVCCIO_CPU0_PWM1      EU7C1            34       IR354XX_SM-IR35412,IC,H73684-0A
VR_PVCCIO_CPU0_VD12      C3P4             1        CAP_A_0402V-1.0UF,6.3V,10%,X6SA
VR_PVCCIO_CPU0_VD12      C3P5             1        CAP_A_0402V-0.1UF,16V,10%,X7R,A
VR_PVCCIO_CPU0_VD12      EU3P1            40       PXE1110B_QFN-IC,H89187-001
VR_PVCCIO_CPU0_VD12      R3P57            1        RES_0402-0.0,5%,1/16W,CHIP,G21A
VR_PVCCIO_CPU0_VDD       C3P3             1        CAP_A_0402V-1.0UF,6.3V,10%,X6SA
VR_PVCCIO_CPU0_VDD       C3P7             1        CAP_A_0402V-0.1UF,16V,10%,X7R,A
VR_PVCCIO_CPU0_VDD       EU3P1            39       PXE1110B_QFN-IC,H89187-001
VR_PVCCIO_CPU0_VDD       R3P22            2        RES_0402-0.0,5%,1/16W,CHIP,G21A
VR_PVCCIO_CPU0_VINSEN    C3P2             1        CAP_0402LF-1000PF,50V,10%,X7R,A
VR_PVCCIO_CPU0_VINSEN    EU3P1            37       PXE1110B_QFN-IC,H89187-001
VR_PVCCIO_CPU0_VINSEN    R3P12            2        RES_0402-100.0K,1%,1/16W,CHIP,B
VR_PVCCIO_CPU0_VINSEN    R3P16            1        RES_0402-1.5K,1%,1/16W,CHIP,G2A
VR_PVCCIO_CPU0_XADDR1    EU3P1            36       PXE1110B_QFN-IC,H89187-001
VR_PVCCIO_CPU0_XADDR1    R3N31            1        RES_0402-3.16K,1%,1/16W,CHIP,GA
VR_PVCCIO_CPU0_XADDR2    EU3P1            33       PXE1110B_QFN-IC,H89187-001
VR_PVCCIO_CPU0_XADDR2    R3N22            1        RES_0402-4.02K,1%,1/16W,CHIP,GA
VR_PVCCIO_CPU1_AIREF1    CTI63            1        CAP_A_0402V-0.1UF,16V,10%,X7R,A
VR_PVCCIO_CPU1_AIREF1    EU4D5            21       PXE1110B_QFN-IC,H89187-001
VR_PVCCIO_CPU1_AIREF1    EU4E2            39       IR354XX_SM-IR35412,IC,H73684-0A
VR_PVCCIO_CPU1_AIREF1    R4D45            2        RES_0402-0.0,5%,1/16W,CHIP,G21A
VR_PVCCIO_CPU1_AVSP      C4D44            1        CAP_0402LF-220PF,50V,10%,X7R,AA
VR_PVCCIO_CPU1_AVSP      EU4D5            19       PXE1110B_QFN-IC,H89187-001
VR_PVCCIO_CPU1_AVSP      R4E7             2        RES_0402-10.0,1%,1/16W,CHIP,G2A
VR_PVCCIO_CPU1_EN        EU4D5            10       PXE1110B_QFN-IC,H89187-001
VR_PVCCIO_CPU1_EN        R6P40            2        RES_0402-100.0K,1%,1/16W,EMPTYA
VR_PVCCIO_CPU1_EN        R6P41            2        RES_0402-0.0,5%,1/16W,CHIP,G21A
VR_PVCCIO_CPU1_OCSET     EU4E2            37       IR354XX_SM-IR35412,IC,H73684-0A
VR_PVCCIO_CPU1_OCSET     R4E21            1        RES_0402-68.1K,1%,1/16W,EMPTY,A
VR_PVCCIO_CPU1_PH1_BOOT  C4E18            1        CAP_0402-0.220UF,16V,10%,X7R,AA
VR_PVCCIO_CPU1_PH1_BOOT  RTI41            1        2D2R2F-GP_SMD-RG1-2D2R2F-GP,64A
VR_PVCCIO_CPU1_PH1_BOOT_R EU4E2            33       IR354XX_SM-IR35412,IC,H73684-0A
VR_PVCCIO_CPU1_PH1_BOOT_R RTI41            2        2D2R2F-GP_SMD-RG1-2D2R2F-GP,64A
VR_PVCCIO_CPU1_PH1_PHASE C4E18            2        CAP_0402-0.220UF,16V,10%,X7R,AA
VR_PVCCIO_CPU1_PH1_PHASE EU4E2            32       IR354XX_SM-IR35412,IC,H73684-0A
VR_PVCCIO_CPU1_PH1_SW    CTI62            1        SC2K2P50V3KX-GP_SMD-BCG6-SC2K2A
VR_PVCCIO_CPU1_PH1_SW    EU4E2            10       IR354XX_SM-IR35412,IC,H73684-0A
VR_PVCCIO_CPU1_PH1_SW    L4E2             1        INDUCTOR_SM-150NH,IND,D92183-0A
VR_PVCCIO_CPU1_PH1_VCIN  C4E22            1        CAP_0402-1.0UF,16V,10%,X6S,D97A
VR_PVCCIO_CPU1_PH1_VCIN  EU4E2            3        IR354XX_SM-IR35412,IC,H73684-0A
VR_PVCCIO_CPU1_PH1_VCIN  R6R5             1        RES_0402-1.0,1%,1/16W,CHIP,G21A
VR_PVCCIO_CPU1_PWM1      EU4D5            5        PXE1110B_QFN-IC,H89187-001
VR_PVCCIO_CPU1_PWM1      EU4E2            34       IR354XX_SM-IR35412,IC,H73684-0A
VR_PVCCIO_CPU1_VD12      C4D31            1        CAP_A_0402V-1.0UF,6.3V,10%,X6SA
VR_PVCCIO_CPU1_VD12      C4D32            1        CAP_A_0402V-0.1UF,16V,10%,X7R,A
VR_PVCCIO_CPU1_VD12      EU4D5            40       PXE1110B_QFN-IC,H89187-001
VR_PVCCIO_CPU1_VD12      R4D45            1        RES_0402-0.0,5%,1/16W,CHIP,G21A
VR_PVCCIO_CPU1_VDD       C4D36            1        CAP_A_0402V-1.0UF,6.3V,10%,X6SA
VR_PVCCIO_CPU1_VDD       C4D38            1        CAP_A_0402V-0.1UF,16V,10%,X7R,A
VR_PVCCIO_CPU1_VDD       EU4D5            39       PXE1110B_QFN-IC,H89187-001
VR_PVCCIO_CPU1_VDD       R4D47            2        RES_0402-0.0,5%,1/16W,CHIP,G21A
VR_PVCCIO_CPU1_VINSEN    C4D40            1        CAP_0402LF-1000PF,50V,10%,X7R,A
VR_PVCCIO_CPU1_VINSEN    EU4D5            37       PXE1110B_QFN-IC,H89187-001
VR_PVCCIO_CPU1_VINSEN    R4D57            1        RES_0402-1.5K,1%,1/16W,CHIP,G2A
VR_PVCCIO_CPU1_VINSEN    R4D60            2        RES_0402-100.0K,1%,1/16W,CHIP,B
VR_PVCCIO_CPU1_XADDR1    EU4D5            36       PXE1110B_QFN-IC,H89187-001
VR_PVCCIO_CPU1_XADDR1    R4D64            1        RES_0402-3.16K,1%,1/16W,CHIP,GA
VR_PVCCIO_CPU1_XADDR2    EU4D5            33       PXE1110B_QFN-IC,H89187-001
VR_PVCCIO_CPU1_XADDR2    R4E2             1        RES_0402-3.16K,1%,1/16W,CHIP,GA
VR_PVCCMCP_CPU0_XADDR2   J6B1             F10      SCONN120_H61426002_SM-CONN,H61A
VR_PVCCMCP_CPU0_XADDR2   R7C24            1        RES_0402-4.02K,1%,1/16W,CHIP,GA
VR_PVCCMCP_CPU1_XADDR2   J4B2             F10      SCONN120_H61426002_SM-CONN,H61A
VR_PVCCMCP_CPU1_XADDR2   R4C11            1        RES_0402-3.16K,1%,1/16W,CHIP,GA
VR_PVDDQ_ABC_AIINSEN     C3U10            1        CAP_A_0402V-0.1UF,16V,10%,X7R,A
VR_PVDDQ_ABC_AIINSEN     EU7G1            38       PXM1310B_QFN-IC,H89186-001
VR_PVDDQ_ABC_AIINSEN     R4F1             2        RES_0402-0.0,5%,1/16W,CHIP,G21A
VR_PVDDQ_ABC_AIINSEN_R   R4F1             1        RES_0402-0.0,5%,1/16W,CHIP,G21A
VR_PVDDQ_ABC_AIINSEN_R   U4F1             3        MAX9634_SOT-IC,H35789-001
VR_PVDDQ_ABC_AIREF1      CTI51            1        CAP_A_0402V-0.1UF,16V,10%,X7R,A
VR_PVDDQ_ABC_AIREF1      EU7G1            21       PXM1310B_QFN-IC,H89186-001
VR_PVDDQ_ABC_AIREF1      EU7G2            39       IR354XX_SM-IR35411,IC,H73688-0A
VR_PVDDQ_ABC_AIREF1      R3U10            2        RES_0402-0.0,5%,1/16W,CHIP,G21A
VR_PVDDQ_ABC_AIREF2      CTI52            1        CAP_A_0402V-0.1UF,16V,10%,X7R,A
VR_PVDDQ_ABC_AIREF2      EU7G1            23       PXM1310B_QFN-IC,H89186-001
VR_PVDDQ_ABC_AIREF2      EU7G3            39       IR354XX_SM-IR35411,IC,H73688-0A
VR_PVDDQ_ABC_AIREF2      R3U3             2        RES_0402-0.0,5%,1/16W,CHIP,G21A
VR_PVDDQ_ABC_AVSP        C7G4             1        CAP_0402LF-220PF,50V,10%,X7R,AA
VR_PVDDQ_ABC_AVSP        EU7G1            19       PXM1310B_QFN-IC,H89186-001
VR_PVDDQ_ABC_AVSP        R7G9             2        RES_0402-10.0,1%,1/16W,CHIP,G2A
VR_PVDDQ_ABC_PH1_BOOT    C7G31            1        CAP_0402-0.220UF,16V,10%,X7R,AA
VR_PVDDQ_ABC_PH1_BOOT    RTI33            1        2D2R2F-GP_SMD-RG1-2D2R2F-GP,64A
VR_PVDDQ_ABC_PH1_BOOT_R  EU7G2            33       IR354XX_SM-IR35411,IC,H73688-0A
VR_PVDDQ_ABC_PH1_BOOT_R  RTI33            2        2D2R2F-GP_SMD-RG1-2D2R2F-GP,64A
VR_PVDDQ_ABC_PH1_OCSET   EU7G2            37       IR354XX_SM-IR35411,IC,H73688-0A
VR_PVDDQ_ABC_PH1_OCSET   R7G25            1        RES_0402-68.1K,1%,1/16W,EMPTY,A
VR_PVDDQ_ABC_PH1_PHASE   C7G31            2        CAP_0402-0.220UF,16V,10%,X7R,AA
VR_PVDDQ_ABC_PH1_PHASE   EU7G2            32       IR354XX_SM-IR35411,IC,H73688-0A
VR_PVDDQ_ABC_PH1_SW      CTI50            1        SC2K2P50V3KX-GP_SMD-BCG6-SC2K2A
VR_PVDDQ_ABC_PH1_SW      EU7G2            10       IR354XX_SM-IR35411,IC,H73688-0A
VR_PVDDQ_ABC_PH1_SW      L7G1             1        INDUCTOR_SM-0.12UH,IND,D92183-A
VR_PVDDQ_ABC_PH1_VCIN    C7G33            1        CAP_0402-1.0UF,16V,10%,X6S,D97A
VR_PVDDQ_ABC_PH1_VCIN    EU7G2            3        IR354XX_SM-IR35411,IC,H73688-0A
VR_PVDDQ_ABC_PH1_VCIN    R3U6             1        RES_0402-1.0,1%,1/16W,CHIP,G21A
VR_PVDDQ_ABC_PH2_BOOT    C7G38            1        CAP_0402-0.220UF,16V,10%,X7R,AA
VR_PVDDQ_ABC_PH2_BOOT    RTI36            1        2D2R2F-GP_SMD-RG1-2D2R2F-GP,64A
VR_PVDDQ_ABC_PH2_BOOT_R  EU7G3            33       IR354XX_SM-IR35411,IC,H73688-0A
VR_PVDDQ_ABC_PH2_BOOT_R  RTI36            2        2D2R2F-GP_SMD-RG1-2D2R2F-GP,64A
VR_PVDDQ_ABC_PH2_OCSET   EU7G3            37       IR354XX_SM-IR35411,IC,H73688-0A
VR_PVDDQ_ABC_PH2_OCSET   R7G30            1        RES_0402-68.1K,1%,1/16W,EMPTY,A
VR_PVDDQ_ABC_PH2_PHASE   C7G38            2        CAP_0402-0.220UF,16V,10%,X7R,AA
VR_PVDDQ_ABC_PH2_PHASE   EU7G3            32       IR354XX_SM-IR35411,IC,H73688-0A
VR_PVDDQ_ABC_PH2_SW      CTI53            1        SC2K2P50V3KX-GP_SMD-BCG6-SC2K2A
VR_PVDDQ_ABC_PH2_SW      EU7G3            10       IR354XX_SM-IR35411,IC,H73688-0A
VR_PVDDQ_ABC_PH2_SW      L7G2             1        INDUCTOR_SM-0.12UH,IND,D92183-A
VR_PVDDQ_ABC_PH2_VCIN    C7G40            1        CAP_0402-1.0UF,16V,10%,X6S,D97A
VR_PVDDQ_ABC_PH2_VCIN    EU7G3            3        IR354XX_SM-IR35411,IC,H73688-0A
VR_PVDDQ_ABC_PH2_VCIN    R3U9             1        RES_0402-1.0,1%,1/16W,CHIP,G21A
VR_PVDDQ_ABC_PWM1        EU7G1            5        PXM1310B_QFN-IC,H89186-001
VR_PVDDQ_ABC_PWM1        EU7G2            34       IR354XX_SM-IR35411,IC,H73688-0A
VR_PVDDQ_ABC_PWM2        EU7G1            4        PXM1310B_QFN-IC,H89186-001
VR_PVDDQ_ABC_PWM2        EU7G3            34       IR354XX_SM-IR35411,IC,H73688-0A
VR_PVDDQ_ABC_VD12        C7F15            1        CAP_A_0402V-0.1UF,16V,10%,X7R,A
VR_PVDDQ_ABC_VD12        C7F16            1        CAP_A_0402V-1.0UF,6.3V,10%,X6SA
VR_PVDDQ_ABC_VD12        EU7G1            40       PXM1310B_QFN-IC,H89186-001
VR_PVDDQ_ABC_VD12        R3U3             1        RES_0402-0.0,5%,1/16W,CHIP,G21A
VR_PVDDQ_ABC_VD12        R3U10            1        RES_0402-0.0,5%,1/16W,CHIP,G21A
VR_PVDDQ_ABC_VDD         C7F17            1        CAP_A_0402V-0.1UF,16V,10%,X7R,A
VR_PVDDQ_ABC_VDD         C7F18            1        CAP_A_0402V-1.0UF,6.3V,10%,X6SA
VR_PVDDQ_ABC_VDD         EU7G1            39       PXM1310B_QFN-IC,H89186-001
VR_PVDDQ_ABC_VDD         R3T13            2        RES_0402-0.0,5%,1/16W,CHIP,G21A
VR_PVDDQ_ABC_VINSEN      C7G1             1        CAP_0402LF-1000PF,50V,10%,X7R,A
VR_PVDDQ_ABC_VINSEN      EU7G1            37       PXM1310B_QFN-IC,H89186-001
VR_PVDDQ_ABC_VINSEN      R7F34            2        RES_0402-100.0K,1%,1/16W,CHIP,B
VR_PVDDQ_ABC_VINSEN      R7G3             1        RES_0402-1.5K,1%,1/16W,CHIP,G2A
VR_PVDDQ_ABC_VREN        EU7G1            10       PXM1310B_QFN-IC,H89186-001
VR_PVDDQ_ABC_VREN        R7F20            2        RES_0402-100.0K,1%,1/16W,EMPTYA
VR_PVDDQ_ABC_VREN        R7F21            2        RES_0402-0.0,5%,1/16W,CHIP,G21A
VR_PVDDQ_ABC_XADDR1      EU7G1            36       PXM1310B_QFN-IC,H89186-001
VR_PVDDQ_ABC_XADDR1      R7G8             1        RES_0402-4.02K,1%,1/16W,CHIP,GA
VR_PVDDQ_ABC_XADDR2      EU7G1            33       PXM1310B_QFN-IC,H89186-001
VR_PVDDQ_ABC_XADDR2      R7G10            1        RES_0402-8.06K,1%,1/16W,CHIP,GA
VR_PVDDQ_DEF_AIINSEN     C3L31            1        CAP_A_0402V-0.1UF,16V,10%,X7R,A
VR_PVDDQ_DEF_AIINSEN     EU7A5            38       PXM1310B_QFN-IC,H89186-001
VR_PVDDQ_DEF_AIINSEN     R4B11            2        RES_0402-0.0,5%,1/16W,CHIP,G21A
VR_PVDDQ_DEF_AIINSEN_R   R4B11            1        RES_0402-0.0,5%,1/16W,CHIP,G21A
VR_PVDDQ_DEF_AIINSEN_R   U4B1             3        MAX9634_SOT-IC,H35789-001
VR_PVDDQ_DEF_AIREF1      CTI45            1        CAP_A_0402V-0.1UF,16V,10%,X7R,A
VR_PVDDQ_DEF_AIREF1      EU7A1            39       IR354XX_SM-IR35411,IC,H73688-0A
VR_PVDDQ_DEF_AIREF1      EU7A5            21       PXM1310B_QFN-IC,H89186-001
VR_PVDDQ_DEF_AIREF1      R3L9             2        RES_0402-0.0,5%,1/16W,CHIP,G21A
VR_PVDDQ_DEF_AIREF2      CTI46            1        CAP_A_0402V-0.1UF,16V,10%,X7R,A
VR_PVDDQ_DEF_AIREF2      EU7A4            39       IR354XX_SM-IR35411,IC,H73688-0A
VR_PVDDQ_DEF_AIREF2      EU7A5            23       PXM1310B_QFN-IC,H89186-001
VR_PVDDQ_DEF_AIREF2      R3L10            2        RES_0402-0.0,5%,1/16W,CHIP,G21A
VR_PVDDQ_DEF_AVSP        C7A28            1        CAP_0402LF-220PF,50V,10%,X7R,AA
VR_PVDDQ_DEF_AVSP        EU7A5            19       PXM1310B_QFN-IC,H89186-001
VR_PVDDQ_DEF_AVSP        R7A7             2        RES_0402-10.0,1%,1/16W,CHIP,G2A
VR_PVDDQ_DEF_PH1_BOOT    C7A12            1        CAP_0402-0.220UF,16V,10%,X7R,AA
VR_PVDDQ_DEF_PH1_BOOT    RTI30            1        2D2R2F-GP_SMD-RG1-2D2R2F-GP,64A
VR_PVDDQ_DEF_PH1_BOOT_R  EU7A1            33       IR354XX_SM-IR35411,IC,H73688-0A
VR_PVDDQ_DEF_PH1_BOOT_R  RTI30            2        2D2R2F-GP_SMD-RG1-2D2R2F-GP,64A
VR_PVDDQ_DEF_PH1_OCSET   EU7A1            37       IR354XX_SM-IR35411,IC,H73688-0A
VR_PVDDQ_DEF_PH1_OCSET   R7A20            1        RES_0402-68.1K,1%,1/16W,EMPTY,A
VR_PVDDQ_DEF_PH1_PHASE   C7A12            2        CAP_0402-0.220UF,16V,10%,X7R,AA
VR_PVDDQ_DEF_PH1_PHASE   EU7A1            32       IR354XX_SM-IR35411,IC,H73688-0A
VR_PVDDQ_DEF_PH1_SW      CTI44            1        SC2K2P50V3KX-GP_SMD-BCG6-SC2K2A
VR_PVDDQ_DEF_PH1_SW      EU7A1            10       IR354XX_SM-IR35411,IC,H73688-0A
VR_PVDDQ_DEF_PH1_SW      L7A1             1        INDUCTOR_SM-0.12UH,IND,D92183-A
VR_PVDDQ_DEF_PH1_VCIN    C7A16            1        CAP_0402-1.0UF,16V,10%,X6S,D97A
VR_PVDDQ_DEF_PH1_VCIN    EU7A1            3        IR354XX_SM-IR35411,IC,H73688-0A
VR_PVDDQ_DEF_PH1_VCIN    R3L6             1        RES_0402-1.0,1%,1/16W,CHIP,G21A
VR_PVDDQ_DEF_PH2_BOOT    C7A22            1        CAP_0402-0.220UF,16V,10%,X7R,AA
VR_PVDDQ_DEF_PH2_BOOT    RTI31            1        2D2R2F-GP_SMD-RG1-2D2R2F-GP,64A
VR_PVDDQ_DEF_PH2_BOOT_R  EU7A4            33       IR354XX_SM-IR35411,IC,H73688-0A
VR_PVDDQ_DEF_PH2_BOOT_R  RTI31            2        2D2R2F-GP_SMD-RG1-2D2R2F-GP,64A
VR_PVDDQ_DEF_PH2_OCSET   EU7A4            37       IR354XX_SM-IR35411,IC,H73688-0A
VR_PVDDQ_DEF_PH2_OCSET   R7A21            1        RES_0402-68.1K,1%,1/16W,EMPTY,A
VR_PVDDQ_DEF_PH2_PHASE   C7A22            2        CAP_0402-0.220UF,16V,10%,X7R,AA
VR_PVDDQ_DEF_PH2_PHASE   EU7A4            32       IR354XX_SM-IR35411,IC,H73688-0A
VR_PVDDQ_DEF_PH2_SW      CTI47            1        SC2K2P50V3KX-GP_SMD-BCG6-SC2K2A
VR_PVDDQ_DEF_PH2_SW      EU7A4            10       IR354XX_SM-IR35411,IC,H73688-0A
VR_PVDDQ_DEF_PH2_SW      L7A3             1        INDUCTOR_SM-0.12UH,IND,D92183-A
VR_PVDDQ_DEF_PH2_VCIN    C7A24            1        CAP_0402-1.0UF,16V,10%,X6S,D97A
VR_PVDDQ_DEF_PH2_VCIN    EU7A4            3        IR354XX_SM-IR35411,IC,H73688-0A
VR_PVDDQ_DEF_PH2_VCIN    R3L8             1        RES_0402-1.0,1%,1/16W,CHIP,G21A
VR_PVDDQ_DEF_PWM1        EU7A1            34       IR354XX_SM-IR35411,IC,H73688-0A
VR_PVDDQ_DEF_PWM1        EU7A5            5        PXM1310B_QFN-IC,H89186-001
VR_PVDDQ_DEF_PWM2        EU7A4            34       IR354XX_SM-IR35411,IC,H73688-0A
VR_PVDDQ_DEF_PWM2        EU7A5            4        PXM1310B_QFN-IC,H89186-001
VR_PVDDQ_DEF_VD12        C7B1             1        CAP_A_0402V-1.0UF,6.3V,10%,X6SA
VR_PVDDQ_DEF_VD12        C7B2             1        CAP_A_0402V-0.1UF,16V,10%,X7R,A
VR_PVDDQ_DEF_VD12        EU7A5            40       PXM1310B_QFN-IC,H89186-001
VR_PVDDQ_DEF_VD12        R3L9             1        RES_0402-0.0,5%,1/16W,CHIP,G21A
VR_PVDDQ_DEF_VD12        R3L10            1        RES_0402-0.0,5%,1/16W,CHIP,G21A
VR_PVDDQ_DEF_VDD         C7A37            1        CAP_A_0402V-1.0UF,6.3V,10%,X6SA
VR_PVDDQ_DEF_VDD         C7A38            1        CAP_A_0402V-0.1UF,16V,10%,X7R,A
VR_PVDDQ_DEF_VDD         EU7A5            39       PXM1310B_QFN-IC,H89186-001
VR_PVDDQ_DEF_VDD         R3M1             2        RES_0402-0.0,5%,1/16W,CHIP,G21A
VR_PVDDQ_DEF_VINSEN      C7A35            1        CAP_0402LF-1000PF,50V,10%,X7R,A
VR_PVDDQ_DEF_VINSEN      EU7A5            37       PXM1310B_QFN-IC,H89186-001
VR_PVDDQ_DEF_VINSEN      R3L12            2        RES_0402-100.0K,1%,1/16W,CHIP,B
VR_PVDDQ_DEF_VINSEN      R7A16            1        RES_0402-1.5K,1%,1/16W,CHIP,G2A
VR_PVDDQ_DEF_VREN        EU7A5            10       PXM1310B_QFN-IC,H89186-001
VR_PVDDQ_DEF_VREN        R3M5             2        RES_0402-100.0K,1%,1/16W,EMPTYA
VR_PVDDQ_DEF_VREN        R3M6             2        RES_0402-0.0,5%,1/16W,CHIP,G21A
VR_PVDDQ_DEF_XADDR1      EU7A5            36       PXM1310B_QFN-IC,H89186-001
VR_PVDDQ_DEF_XADDR1      R7A10            1        RES_0402-3.16K,1%,1/16W,CHIP,GA
VR_PVDDQ_DEF_XADDR2      EU7A5            33       PXM1310B_QFN-IC,H89186-001
VR_PVDDQ_DEF_XADDR2      R7A8             1        RES_0402-8.06K,1%,1/16W,CHIP,GA
VR_PVDDQ_GHJ_AIINSEN     C9U12            1        CAP_A_0402V-0.1UF,16V,10%,X7R,A
VR_PVDDQ_GHJ_AIINSEN     EU1G2            38       PXM1310B_QFN-IC,H89186-001
VR_PVDDQ_GHJ_AIINSEN     R9T4             2        RES_0402-0.0,5%,1/16W,CHIP,G21A
VR_PVDDQ_GHJ_AIINSEN_R   R9T4             1        RES_0402-0.0,5%,1/16W,CHIP,G21A
VR_PVDDQ_GHJ_AIINSEN_R   U1F1             3        MAX9634_SOT-IC,H35789-001
VR_PVDDQ_GHJ_AIREF1      CTI30            1        CAP_A_0402V-0.1UF,16V,10%,X7R,A
VR_PVDDQ_GHJ_AIREF1      EU1G1            39       IR354XX_SM-IR35411,IC,H73688-0A
VR_PVDDQ_GHJ_AIREF1      EU1G2            21       PXM1310B_QFN-IC,H89186-001
VR_PVDDQ_GHJ_AIREF1      R1G28            2        RES_0402-0.0,5%,1/16W,CHIP,G21A
VR_PVDDQ_GHJ_AIREF2      CTI31            1        CAP_A_0402V-0.1UF,16V,10%,X7R,A
VR_PVDDQ_GHJ_AIREF2      EU1F1            39       IR354XX_SM-IR35411,IC,H73688-0A
VR_PVDDQ_GHJ_AIREF2      EU1G2            23       PXM1310B_QFN-IC,H89186-001
VR_PVDDQ_GHJ_AIREF2      R1G27            2        RES_0402-0.0,5%,1/16W,CHIP,G21A
VR_PVDDQ_GHJ_AVSP        C1G16            1        CAP_0402LF-220PF,50V,10%,X7R,AA
VR_PVDDQ_GHJ_AVSP        EU1G2            19       PXM1310B_QFN-IC,H89186-001
VR_PVDDQ_GHJ_AVSP        R1G5             2        RES_0402-10.0,1%,1/16W,CHIP,G2A
VR_PVDDQ_GHJ_PH1_BOOT    C1G11            1        CAP_0402-0.220UF,16V,10%,X7R,AA
VR_PVDDQ_GHJ_PH1_BOOT    RTI19            1        2D2R2F-GP_SMD-RG1-2D2R2F-GP,64A
VR_PVDDQ_GHJ_PH1_BOOT_R  EU1G1            33       IR354XX_SM-IR35411,IC,H73688-0A
VR_PVDDQ_GHJ_PH1_BOOT_R  RTI19            2        2D2R2F-GP_SMD-RG1-2D2R2F-GP,64A
VR_PVDDQ_GHJ_PH1_OCSET   EU1G1            37       IR354XX_SM-IR35411,IC,H73688-0A
VR_PVDDQ_GHJ_PH1_OCSET   R1G26            1        RES_0402-68.1K,1%,1/16W,EMPTY,A
VR_PVDDQ_GHJ_PH1_PHASE   C1G11            2        CAP_0402-0.220UF,16V,10%,X7R,AA
VR_PVDDQ_GHJ_PH1_PHASE   EU1G1            32       IR354XX_SM-IR35411,IC,H73688-0A
VR_PVDDQ_GHJ_PH1_SW      CTI29            1        SC2K2P50V3KX-GP_SMD-BCG6-SC2K2A
VR_PVDDQ_GHJ_PH1_SW      EU1G1            10       IR354XX_SM-IR35411,IC,H73688-0A
VR_PVDDQ_GHJ_PH1_SW      L1G1             1        INDUCTOR_SM-0.12UH,IND,D92183-A
VR_PVDDQ_GHJ_PH1_VCIN    C1G6             1        CAP_0402-1.0UF,16V,10%,X6S,D97A
VR_PVDDQ_GHJ_PH1_VCIN    EU1G1            3        IR354XX_SM-IR35411,IC,H73688-0A
VR_PVDDQ_GHJ_PH1_VCIN    R9U1             1        RES_0402-1.0,1%,1/16W,CHIP,G21A
VR_PVDDQ_GHJ_PH2_BOOT    C1F26            1        CAP_0402-0.220UF,16V,10%,X7R,AA
VR_PVDDQ_GHJ_PH2_BOOT    RTI21            1        2D2R2F-GP_SMD-RG1-2D2R2F-GP,64A
VR_PVDDQ_GHJ_PH2_BOOT_R  EU1F1            33       IR354XX_SM-IR35411,IC,H73688-0A
VR_PVDDQ_GHJ_PH2_BOOT_R  RTI21            2        2D2R2F-GP_SMD-RG1-2D2R2F-GP,64A
VR_PVDDQ_GHJ_PH2_OCSET   EU1F1            37       IR354XX_SM-IR35411,IC,H73688-0A
VR_PVDDQ_GHJ_PH2_OCSET   R1G25            1        RES_0402-68.1K,1%,1/16W,EMPTY,A
VR_PVDDQ_GHJ_PH2_PHASE   C1F26            2        CAP_0402-0.220UF,16V,10%,X7R,AA
VR_PVDDQ_GHJ_PH2_PHASE   EU1F1            32       IR354XX_SM-IR35411,IC,H73688-0A
VR_PVDDQ_GHJ_PH2_SW      CTI33            1        SC2K2P50V3KX-GP_SMD-BCG6-SC2K2A
VR_PVDDQ_GHJ_PH2_SW      EU1F1            10       IR354XX_SM-IR35411,IC,H73688-0A
VR_PVDDQ_GHJ_PH2_SW      L1F2             1        INDUCTOR_SM-0.12UH,IND,D92183-A
VR_PVDDQ_GHJ_PH2_VCIN    C1G28            1        CAP_0402-1.0UF,16V,10%,X6S,D97A
VR_PVDDQ_GHJ_PH2_VCIN    EU1F1            3        IR354XX_SM-IR35411,IC,H73688-0A
VR_PVDDQ_GHJ_PH2_VCIN    R9U12            1        RES_0402-1.0,1%,1/16W,CHIP,G21A
VR_PVDDQ_GHJ_PWM1        EU1G1            34       IR354XX_SM-IR35411,IC,H73688-0A
VR_PVDDQ_GHJ_PWM1        EU1G2            5        PXM1310B_QFN-IC,H89186-001
VR_PVDDQ_GHJ_PWM2        EU1F1            34       IR354XX_SM-IR35411,IC,H73688-0A
VR_PVDDQ_GHJ_PWM2        EU1G2            4        PXM1310B_QFN-IC,H89186-001
VR_PVDDQ_GHJ_VD12        C1G22            1        CAP_A_0402V-0.1UF,16V,10%,X7R,A
VR_PVDDQ_GHJ_VD12        C1G23            1        CAP_A_0402V-1.0UF,6.3V,10%,X6SA
VR_PVDDQ_GHJ_VD12        EU1G2            40       PXM1310B_QFN-IC,H89186-001
VR_PVDDQ_GHJ_VD12        R1G27            1        RES_0402-0.0,5%,1/16W,CHIP,G21A
VR_PVDDQ_GHJ_VD12        R1G28            1        RES_0402-0.0,5%,1/16W,CHIP,G21A
VR_PVDDQ_GHJ_VDD         C1G25            1        CAP_A_0402V-0.1UF,16V,10%,X7R,A
VR_PVDDQ_GHJ_VDD         C1G27            1        CAP_A_0402V-1.0UF,6.3V,10%,X6SA
VR_PVDDQ_GHJ_VDD         EU1G2            39       PXM1310B_QFN-IC,H89186-001
VR_PVDDQ_GHJ_VDD         R9U10            2        RES_0402-0.0,5%,1/16W,CHIP,G21A
VR_PVDDQ_GHJ_VINSEN      C1G26            1        CAP_0402LF-1000PF,50V,10%,X7R,A
VR_PVDDQ_GHJ_VINSEN      EU1G2            37       PXM1310B_QFN-IC,H89186-001
VR_PVDDQ_GHJ_VINSEN      R1G24            1        RES_0402-1.5K,1%,1/16W,CHIP,G2A
VR_PVDDQ_GHJ_VINSEN      R9U11            2        RES_0402-100.0K,1%,1/16W,CHIP,B
VR_PVDDQ_GHJ_VREN        EU1G2            10       PXM1310B_QFN-IC,H89186-001
VR_PVDDQ_GHJ_VREN        R9U7             2        RES_0402-0.0,5%,1/16W,CHIP,G21A
VR_PVDDQ_GHJ_VREN        R9U8             2        RES_0402-100.0K,1%,1/16W,EMPTYA
VR_PVDDQ_GHJ_XADDR1      EU1G2            36       PXM1310B_QFN-IC,H89186-001
VR_PVDDQ_GHJ_XADDR1      R1G23            1        RES_0402-4.02K,1%,1/16W,CHIP,GA
VR_PVDDQ_GHJ_XADDR2      EU1G2            33       PXM1310B_QFN-IC,H89186-001
VR_PVDDQ_GHJ_XADDR2      R1G22            1        RES_0402-5.36K,1.0%,1/16W,CHIPA
VR_PVDDQ_KLM_AIINSEN     C9M11            1        CAP_A_0402V-0.1UF,16V,10%,X7R,A
VR_PVDDQ_KLM_AIINSEN     EU1B1            38       PXM1310B_QFN-IC,H89186-001
VR_PVDDQ_KLM_AIINSEN     R1B14            2        RES_0402-0.0,5%,1/16W,CHIP,G21A
VR_PVDDQ_KLM_AIINSEN_R   R1B14            1        RES_0402-0.0,5%,1/16W,CHIP,G21A
VR_PVDDQ_KLM_AIINSEN_R   U1B1             3        MAX9634_SOT-IC,H35789-001
VR_PVDDQ_KLM_AIREF1      CTI7             1        CAP_A_0402V-0.1UF,16V,10%,X7R,A
VR_PVDDQ_KLM_AIREF1      EU1A2            39       IR354XX_SM-IR35411,IC,H73688-0A
VR_PVDDQ_KLM_AIREF1      EU1B1            21       PXM1310B_QFN-IC,H89186-001
VR_PVDDQ_KLM_AIREF1      R9M11            2        RES_0402-0.0,5%,1/16W,CHIP,G21A
VR_PVDDQ_KLM_AIREF2      CTI12            1        CAP_A_0402V-0.1UF,16V,10%,X7R,A
VR_PVDDQ_KLM_AIREF2      EU1A1            39       IR354XX_SM-IR35411,IC,H73688-0A
VR_PVDDQ_KLM_AIREF2      EU1B1            23       PXM1310B_QFN-IC,H89186-001
VR_PVDDQ_KLM_AIREF2      R9M10            2        RES_0402-0.0,5%,1/16W,CHIP,G21A
VR_PVDDQ_KLM_AVSP        C1B12            1        CAP_0402LF-220PF,50V,10%,X7R,AA
VR_PVDDQ_KLM_AVSP        EU1B1            19       PXM1310B_QFN-IC,H89186-001
VR_PVDDQ_KLM_AVSP        R1B16            2        RES_0402-10.0,1%,1/16W,CHIP,G2A
VR_PVDDQ_KLM_PH1_BOOT    C1A18            1        CAP_0402-0.220UF,16V,10%,X7R,AA
VR_PVDDQ_KLM_PH1_BOOT    RTI5             1        2D2R2F-GP_SMD-RG1-2D2R2F-GP,64A
VR_PVDDQ_KLM_PH1_BOOT_R  EU1A2            33       IR354XX_SM-IR35411,IC,H73688-0A
VR_PVDDQ_KLM_PH1_BOOT_R  RTI5             2        2D2R2F-GP_SMD-RG1-2D2R2F-GP,64A
VR_PVDDQ_KLM_PH1_OCSET   EU1A2            37       IR354XX_SM-IR35411,IC,H73688-0A
VR_PVDDQ_KLM_PH1_OCSET   R1A3             1        RES_0402-68.1K,1%,1/16W,EMPTY,A
VR_PVDDQ_KLM_PH1_PHASE   C1A18            2        CAP_0402-0.220UF,16V,10%,X7R,AA
VR_PVDDQ_KLM_PH1_PHASE   EU1A2            32       IR354XX_SM-IR35411,IC,H73688-0A
VR_PVDDQ_KLM_PH1_SW      CTI9             1        SC2K2P50V3KX-GP_SMD-BCG6-SC2K2A
VR_PVDDQ_KLM_PH1_SW      EU1A2            10       IR354XX_SM-IR35411,IC,H73688-0A
VR_PVDDQ_KLM_PH1_SW      L1A2             1        INDUCTOR_SM-0.12UH,IND,D92183-A
VR_PVDDQ_KLM_PH1_VCIN    C1B20            1        CAP_0402-1.0UF,16V,10%,X6S,D97A
VR_PVDDQ_KLM_PH1_VCIN    EU1A2            3        IR354XX_SM-IR35411,IC,H73688-0A
VR_PVDDQ_KLM_PH1_VCIN    R9L9             1        RES_0402-1.0,1%,1/16W,CHIP,G21A
VR_PVDDQ_KLM_PH2_BOOT    C1A8             1        CAP_0402-0.220UF,16V,10%,X7R,AA
VR_PVDDQ_KLM_PH2_BOOT    RTI8             1        2D2R2F-GP_SMD-RG1-2D2R2F-GP,64A
VR_PVDDQ_KLM_PH2_BOOT_R  EU1A1            33       IR354XX_SM-IR35411,IC,H73688-0A
VR_PVDDQ_KLM_PH2_BOOT_R  RTI8             2        2D2R2F-GP_SMD-RG1-2D2R2F-GP,64A
VR_PVDDQ_KLM_PH2_OCSET   EU1A1            37       IR354XX_SM-IR35411,IC,H73688-0A
VR_PVDDQ_KLM_PH2_OCSET   R1A2             1        RES_0402-68.1K,1%,1/16W,EMPTY,A
VR_PVDDQ_KLM_PH2_PHASE   C1A8             2        CAP_0402-0.220UF,16V,10%,X7R,AA
VR_PVDDQ_KLM_PH2_PHASE   EU1A1            32       IR354XX_SM-IR35411,IC,H73688-0A
VR_PVDDQ_KLM_PH2_SW      CTI11            1        SC2K2P50V3KX-GP_SMD-BCG6-SC2K2A
VR_PVDDQ_KLM_PH2_SW      EU1A1            10       IR354XX_SM-IR35411,IC,H73688-0A
VR_PVDDQ_KLM_PH2_SW      L1A1             1        INDUCTOR_SM-0.12UH,IND,D92183-A
VR_PVDDQ_KLM_PH2_VCIN    C1A6             1        CAP_0402-1.0UF,16V,10%,X6S,D97A
VR_PVDDQ_KLM_PH2_VCIN    EU1A1            3        IR354XX_SM-IR35411,IC,H73688-0A
VR_PVDDQ_KLM_PH2_VCIN    R9L4             1        RES_0402-1.0,1%,1/16W,CHIP,G21A
VR_PVDDQ_KLM_PWM1        EU1A2            34       IR354XX_SM-IR35411,IC,H73688-0A
VR_PVDDQ_KLM_PWM1        EU1B1            5        PXM1310B_QFN-IC,H89186-001
VR_PVDDQ_KLM_PWM2        EU1A1            34       IR354XX_SM-IR35411,IC,H73688-0A
VR_PVDDQ_KLM_PWM2        EU1B1            4        PXM1310B_QFN-IC,H89186-001
VR_PVDDQ_KLM_VD12        C1B2             1        CAP_A_0402V-0.1UF,16V,10%,X7R,A
VR_PVDDQ_KLM_VD12        C1B3             1        CAP_A_0402V-1.0UF,6.3V,10%,X6SA
VR_PVDDQ_KLM_VD12        EU1B1            40       PXM1310B_QFN-IC,H89186-001
VR_PVDDQ_KLM_VD12        R9M10            1        RES_0402-0.0,5%,1/16W,CHIP,G21A
VR_PVDDQ_KLM_VD12        R9M11            1        RES_0402-0.0,5%,1/16W,CHIP,G21A
VR_PVDDQ_KLM_VDD         C1B5             1        CAP_A_0402V-0.1UF,16V,10%,X7R,A
VR_PVDDQ_KLM_VDD         C1B6             1        CAP_A_0402V-1.0UF,6.3V,10%,X6SA
VR_PVDDQ_KLM_VDD         EU1B1            39       PXM1310B_QFN-IC,H89186-001
VR_PVDDQ_KLM_VDD         R9M3             2        RES_0402-0.0,5%,1/16W,CHIP,G21A
VR_PVDDQ_KLM_VINSEN      C1B8             1        CAP_0402LF-1000PF,50V,10%,X7R,A
VR_PVDDQ_KLM_VINSEN      EU1B1            37       PXM1310B_QFN-IC,H89186-001
VR_PVDDQ_KLM_VINSEN      R1B9             1        RES_0402-1.5K,1%,1/16W,CHIP,G2A
VR_PVDDQ_KLM_VINSEN      R9M8             2        RES_0402-100.0K,1%,1/16W,CHIP,B
VR_PVDDQ_KLM_VREN        EU1B1            10       PXM1310B_QFN-IC,H89186-001
VR_PVDDQ_KLM_VREN        R9M5             2        RES_0402-100.0K,1%,1/16W,EMPTYA
VR_PVDDQ_KLM_VREN        R9M9             2        RES_0402-0.0,5%,1/16W,CHIP,G21A
VR_PVDDQ_KLM_XADDR1      EU1B1            36       PXM1310B_QFN-IC,H89186-001
VR_PVDDQ_KLM_XADDR1      R1B12            1        RES_0402-3.16K,1%,1/16W,CHIP,GA
VR_PVDDQ_KLM_XADDR2      EU1B1            33       PXM1310B_QFN-IC,H89186-001
VR_PVDDQ_KLM_XADDR2      R1B15            1        RES_0402-5.36K,1.0%,1/16W,CHIPA
VR_PVNN_P1V05_PCH_VD12   C8A7             1        CAP_A_0402V-1.0UF,6.3V,10%,X6SA
VR_PVNN_P1V05_PCH_VD12   C8A8             1        CAP_A_0402V-0.1UF,16V,10%,X7R,A
VR_PVNN_P1V05_PCH_VD12   EU8A1            40       PXE1110B_QFN-IC,H89187-001
VR_PVNN_P1V05_PCH_VD12   R2L1             1        RES_0402-0.0,5%,1/16W,CHIP,G21A
VR_PVNN_P1V05_PCH_VD12   R2L7             1        RES_0402-0.0,5%,1/16W,CHIP,G21A
VR_PVNN_PCH_AIREF1       CTI66            1        CAP_A_0402V-0.1UF,16V,10%,X7R,A
VR_PVNN_PCH_AIREF1       EU7A3            39       IR354XX_SM-IR35412,IC,H73684-0A
VR_PVNN_PCH_AIREF1       EU8A1            21       PXE1110B_QFN-IC,H89187-001
VR_PVNN_PCH_AIREF1       R2L1             2        RES_0402-0.0,5%,1/16W,CHIP,G21A
VR_PVNN_PCH_AVSP         C8A2             1        CAP_0402LF-220PF,50V,10%,X7R,AA
VR_PVNN_PCH_AVSP         EU8A1            19       PXE1110B_QFN-IC,H89187-001
VR_PVNN_PCH_AVSP         R8A1             2        RES_0402-10.0,1%,1/16W,CHIP,G2A
VR_PVNN_PCH_PH1_BOOT     C7A43            1        CAP_0402-0.220UF,16V,10%,X7R,AA
VR_PVNN_PCH_PH1_BOOT     RTI44            1        2D2R2F-GP_SMD-RG1-2D2R2F-GP,64A
VR_PVNN_PCH_PH1_BOOT_R   EU7A3            33       IR354XX_SM-IR35412,IC,H73684-0A
VR_PVNN_PCH_PH1_BOOT_R   RTI44            2        2D2R2F-GP_SMD-RG1-2D2R2F-GP,64A
VR_PVNN_PCH_PH1_PHASE    C7A43            2        CAP_0402-0.220UF,16V,10%,X7R,AA
VR_PVNN_PCH_PH1_PHASE    EU7A3            32       IR354XX_SM-IR35412,IC,H73684-0A
VR_PVNN_PCH_PH1_PHASE_SW CTI65            1        SC2K2P50V3KX-GP_SMD-BCG6-SC2K2A
VR_PVNN_PCH_PH1_PHASE_SW EU7A3            10       IR354XX_SM-IR35412,IC,H73684-0A
VR_PVNN_PCH_PH1_PHASE_SW L7A2             1        INDUCTOR_SM-0.3UH,IND,D92183-0A
VR_PVNN_PCH_PH1_VCIN     C7A6             1        CAP_0402-1.0UF,16V,10%,X6S,D97A
VR_PVNN_PCH_PH1_VCIN     EU7A3            3        IR354XX_SM-IR35412,IC,H73684-0A
VR_PVNN_PCH_PH1_VCIN     R3L1             1        RES_0402-1.0,1%,1/16W,CHIP,G21A
VR_PVNN_PCH_PWM1         EU7A3            34       IR354XX_SM-IR35412,IC,H73684-0A
VR_PVNN_PCH_PWM1         EU8A1            5        PXE1110B_QFN-IC,H89187-001
VR_PVNN_PCH_STBY_OCSET   EU7A3            37       IR354XX_SM-IR35412,IC,H73684-0A
VR_PVNN_PCH_STBY_OCSET   R3L15            1        RES_0402-68.1K,1%,1/16W,EMPTY,A
VR_PVNN_PCH_VDD          C2L8             1        CAP_A_0402V-1.0UF,6.3V,10%,X6SA
VR_PVNN_PCH_VDD          C2L11            1        CAP_A_0402V-0.1UF,16V,10%,X7R,A
VR_PVNN_PCH_VDD          EU8A1            39       PXE1110B_QFN-IC,H89187-001
VR_PVNN_PCH_VDD          R2L14            2        RES_0402-0.0,5%,1/16W,CHIP,G21A
VR_PVNN_PCH_VINSEN       C8A3             1        CAP_0402LF-1000PF,50V,10%,X7R,A
VR_PVNN_PCH_VINSEN       EU8A1            37       PXE1110B_QFN-IC,H89187-001
VR_PVNN_PCH_VINSEN       R2L10            1        RES_0402-1.5K,1%,1/16W,CHIP,G2A
VR_PVNN_PCH_VINSEN       R8A4             2        RES_0402-100.0K,1%,1/16W,CHIP,B
VR_PVNN_PCH_VREN         EU8A1            10       PXE1110B_QFN-IC,H89187-001
VR_PVNN_PCH_VREN         R2L17            2        RES_0402-0.0,5%,1/16W,CHIP,G21A
VR_PVNN_PCH_VREN         R8A7             2        RES_0402-100.0K,1%,1/16W,EMPTYA
VR_PVNN_PCH_XADDR1       EU8A1            36       PXE1110B_QFN-IC,H89187-001
VR_PVNN_PCH_XADDR1       R2L9             1        RES_0402-4.02K,1%,1/16W,CHIP,GA
VR_PVNN_PCH_XADDR2       EU8A1            33       PXE1110B_QFN-IC,H89187-001
VR_PVNN_PCH_XADDR2       R8A2             1        RES_0402-2.67K,1%,1/16W,CHIP,GA
VR_PVPP_ABC_BOOT         EU7F1            36       NCP3232L_SM-IC,H86355-001
VR_PVPP_ABC_BOOT         R7F8             1        RES_0402-0.0,5%,1/16W,CHIP,G21A
VR_PVPP_ABC_BOOT_R       C7F4             2        CAP_0603LF-0.1UF,25V,10%,X7R,6A
VR_PVPP_ABC_BOOT_R       R7F8             2        RES_0402-0.0,5%,1/16W,CHIP,G21A
VR_PVPP_ABC_ISET         EU7F1            4        NCP3232L_SM-IC,H86355-001
VR_PVPP_ABC_ISET         R7F15            1        RES_0402-7.87K,1.0%,1/16W,CHIPA
VR_PVPP_ABC_PHASE        C7F3             1        CAP_0402LF-3300PF,50V,10%,EMPTA
VR_PVPP_ABC_PHASE        C7F4             1        CAP_0603LF-0.1UF,25V,10%,X7R,6A
VR_PVPP_ABC_PHASE        EU7F1            15       NCP3232L_SM-IC,H86355-001
VR_PVPP_ABC_PHASE        EU7F1            29       NCP3232L_SM-IC,H86355-001
VR_PVPP_ABC_PHASE        EU7F1            30       NCP3232L_SM-IC,H86355-001
VR_PVPP_ABC_PHASE        EU7F1            31       NCP3232L_SM-IC,H86355-001
VR_PVPP_ABC_PHASE        EU7F1            32       NCP3232L_SM-IC,H86355-001
VR_PVPP_ABC_PHASE        EU7F1            33       NCP3232L_SM-IC,H86355-001
VR_PVPP_ABC_PHASE        EU7F1            34       NCP3232L_SM-IC,H86355-001
VR_PVPP_ABC_PHASE        EU7F1            35       NCP3232L_SM-IC,H86355-001
VR_PVPP_ABC_PHASE        EU7F1            43       NCP3232L_SM-IC,H86355-001
VR_PVPP_ABC_PHASE        L7F1             1        INDUCTOR_SM-0.47UH,IND,E13358-A
VR_PVPP_ABC_SNUB         C7F3             2        CAP_0402LF-3300PF,50V,10%,EMPTA
VR_PVPP_ABC_SNUB         R7F7             1        RES_0402-2.2,5%,1/16W,EMPTY,G2A
VR_PVPP_ABC_SS           C7F10            1        CAP_0402-0.027UF,16V,10%,X7R,AA
VR_PVPP_ABC_SS           EU7F1            1        NCP3232L_SM-IC,H86355-001
VR_PVPP_DEF_BOOT         EU7B1            36       NCP3232L_SM-IC,H86355-001
VR_PVPP_DEF_BOOT         R7B19            1        RES_0402-0.0,5%,1/16W,CHIP,G21A
VR_PVPP_DEF_BOOT_R       C7B30            2        CAP_0603LF-0.1UF,25V,10%,X7R,6A
VR_PVPP_DEF_BOOT_R       R7B19            2        RES_0402-0.0,5%,1/16W,CHIP,G21A
VR_PVPP_DEF_ISET         EU7B1            4        NCP3232L_SM-IC,H86355-001
VR_PVPP_DEF_ISET         R7B14            1        RES_0402-7.87K,1.0%,1/16W,CHIPA
VR_PVPP_DEF_PHASE        C7A34            1        CAP_0402LF-3300PF,50V,10%,EMPTA
VR_PVPP_DEF_PHASE        C7B30            1        CAP_0603LF-0.1UF,25V,10%,X7R,6A
VR_PVPP_DEF_PHASE        EU7B1            15       NCP3232L_SM-IC,H86355-001
VR_PVPP_DEF_PHASE        EU7B1            29       NCP3232L_SM-IC,H86355-001
VR_PVPP_DEF_PHASE        EU7B1            30       NCP3232L_SM-IC,H86355-001
VR_PVPP_DEF_PHASE        EU7B1            31       NCP3232L_SM-IC,H86355-001
VR_PVPP_DEF_PHASE        EU7B1            32       NCP3232L_SM-IC,H86355-001
VR_PVPP_DEF_PHASE        EU7B1            33       NCP3232L_SM-IC,H86355-001
VR_PVPP_DEF_PHASE        EU7B1            34       NCP3232L_SM-IC,H86355-001
VR_PVPP_DEF_PHASE        EU7B1            35       NCP3232L_SM-IC,H86355-001
VR_PVPP_DEF_PHASE        EU7B1            43       NCP3232L_SM-IC,H86355-001
VR_PVPP_DEF_PHASE        L7B1             1        INDUCTOR_SM-0.47UH,IND,E13358-A
VR_PVPP_DEF_SNUB         C7A34            2        CAP_0402LF-3300PF,50V,10%,EMPTA
VR_PVPP_DEF_SNUB         R7A15            1        RES_0402-2.2,5%,1/16W,EMPTY,G2A
VR_PVPP_DEF_SS           C7B11            1        CAP_0402-0.027UF,16V,10%,X7R,AA
VR_PVPP_DEF_SS           EU7B1            1        NCP3232L_SM-IC,H86355-001
VR_PVPP_GHJ_BOOT         EU4G1            36       NCP3232L_SM-IC,H86355-001
VR_PVPP_GHJ_BOOT         R4G24            1        RES_0402-0.0,5%,1/16W,CHIP,G21A
VR_PVPP_GHJ_BOOT_R       C4G26            2        CAP_0603LF-0.1UF,25V,10%,X7R,6A
VR_PVPP_GHJ_BOOT_R       R4G24            2        RES_0402-0.0,5%,1/16W,CHIP,G21A
VR_PVPP_GHJ_ISET         EU4G1            4        NCP3232L_SM-IC,H86355-001
VR_PVPP_GHJ_ISET         R4G11            1        RES_0402-7.87K,1.0%,1/16W,CHIPA
VR_PVPP_GHJ_PHASE        C4F12            1        CAP_0402LF-3300PF,50V,10%,EMPTA
VR_PVPP_GHJ_PHASE        C4G26            1        CAP_0603LF-0.1UF,25V,10%,X7R,6A
VR_PVPP_GHJ_PHASE        EU4G1            15       NCP3232L_SM-IC,H86355-001
VR_PVPP_GHJ_PHASE        EU4G1            29       NCP3232L_SM-IC,H86355-001
VR_PVPP_GHJ_PHASE        EU4G1            30       NCP3232L_SM-IC,H86355-001
VR_PVPP_GHJ_PHASE        EU4G1            31       NCP3232L_SM-IC,H86355-001
VR_PVPP_GHJ_PHASE        EU4G1            32       NCP3232L_SM-IC,H86355-001
VR_PVPP_GHJ_PHASE        EU4G1            33       NCP3232L_SM-IC,H86355-001
VR_PVPP_GHJ_PHASE        EU4G1            34       NCP3232L_SM-IC,H86355-001
VR_PVPP_GHJ_PHASE        EU4G1            35       NCP3232L_SM-IC,H86355-001
VR_PVPP_GHJ_PHASE        EU4G1            43       NCP3232L_SM-IC,H86355-001
VR_PVPP_GHJ_PHASE        L4G1             1        INDUCTOR_SM-0.47UH,IND,E13358-A
VR_PVPP_GHJ_SNUB         C4F12            2        CAP_0402LF-3300PF,50V,10%,EMPTA
VR_PVPP_GHJ_SNUB         R4F6             1        RES_0402-2.2,5%,1/16W,EMPTY,G2A
VR_PVPP_GHJ_SS           C4G8             1        CAP_0402-0.027UF,16V,10%,X7R,AA
VR_PVPP_GHJ_SS           EU4G1            1        NCP3232L_SM-IC,H86355-001
VR_PVPP_KLM_BOOT         EU4A3            36       NCP3232L_SM-IC,H86355-001
VR_PVPP_KLM_BOOT         R4B13            1        RES_0402-0.0,5%,1/16W,CHIP,G21A
VR_PVPP_KLM_BOOT_R       C4B15            2        CAP_0603LF-0.1UF,25V,10%,X7R,6A
VR_PVPP_KLM_BOOT_R       R4B13            2        RES_0402-0.0,5%,1/16W,CHIP,G21A
VR_PVPP_KLM_ISET         EU4A3            4        NCP3232L_SM-IC,H86355-001
VR_PVPP_KLM_ISET         R4B6             1        RES_0402-7.87K,1.0%,1/16W,CHIPA
VR_PVPP_KLM_PHASE        C4A16            1        CAP_0402LF-3300PF,50V,10%,EMPTA
VR_PVPP_KLM_PHASE        C4B15            1        CAP_0603LF-0.1UF,25V,10%,X7R,6A
VR_PVPP_KLM_PHASE        EU4A3            15       NCP3232L_SM-IC,H86355-001
VR_PVPP_KLM_PHASE        EU4A3            29       NCP3232L_SM-IC,H86355-001
VR_PVPP_KLM_PHASE        EU4A3            30       NCP3232L_SM-IC,H86355-001
VR_PVPP_KLM_PHASE        EU4A3            31       NCP3232L_SM-IC,H86355-001
VR_PVPP_KLM_PHASE        EU4A3            32       NCP3232L_SM-IC,H86355-001
VR_PVPP_KLM_PHASE        EU4A3            33       NCP3232L_SM-IC,H86355-001
VR_PVPP_KLM_PHASE        EU4A3            34       NCP3232L_SM-IC,H86355-001
VR_PVPP_KLM_PHASE        EU4A3            35       NCP3232L_SM-IC,H86355-001
VR_PVPP_KLM_PHASE        EU4A3            43       NCP3232L_SM-IC,H86355-001
VR_PVPP_KLM_PHASE        L4A1             1        INDUCTOR_SM-0.47UH,IND,E13358-A
VR_PVPP_KLM_SNUB         C4A16            2        CAP_0402LF-3300PF,50V,10%,EMPTA
VR_PVPP_KLM_SNUB         R4A7             1        RES_0402-2.2,5%,1/16W,EMPTY,G2A
VR_PVPP_KLM_SS           C4B6             1        CAP_0402-0.027UF,16V,10%,X7R,AA
VR_PVPP_KLM_SS           EU4A3            1        NCP3232L_SM-IC,H86355-001
VR_PVSA_CPU0_BIREF1      CTI60            1        CAP_A_0402V-0.1UF,16V,10%,X7R,A
VR_PVSA_CPU0_BIREF1      EU4C1            39       IR354XX_SM-IR35412,IC,H73684-0A
VR_PVSA_CPU0_BIREF1      EU4D4            37       PXE1610B_QFN-IC,H79206-001
VR_PVSA_CPU0_BIREF1      R6P29            2        RES_0402-0.0,5%,1/16W,CHIP,G21A
VR_PVSA_CPU0_BOOT        C4C8             1        CAP_0402-0.220UF,16V,10%,X7R,AA
VR_PVSA_CPU0_BOOT        RTI40            1        2D2R2F-GP_SMD-RG1-2D2R2F-GP,64A
VR_PVSA_CPU0_BOOT_R      EU4C1            33       IR354XX_SM-IR35412,IC,H73684-0A
VR_PVSA_CPU0_BOOT_R      RTI40            2        2D2R2F-GP_SMD-RG1-2D2R2F-GP,64A
VR_PVSA_CPU0_OCSET       EU4C1            37       IR354XX_SM-IR35412,IC,H73684-0A
VR_PVSA_CPU0_OCSET       R4C13            1        RES_0402-68.1K,1%,1/16W,EMPTY,A
VR_PVSA_CPU0_PHASE       C4C8             2        CAP_0402-0.220UF,16V,10%,X7R,AA
VR_PVSA_CPU0_PHASE       EU4C1            32       IR354XX_SM-IR35412,IC,H73684-0A
VR_PVSA_CPU0_PHASE_SW    CTI59            1        SC2K2P50V3KX-GP_SMD-BCG6-SC2K2A
VR_PVSA_CPU0_PHASE_SW    EU4C1            10       IR354XX_SM-IR35412,IC,H73684-0A
VR_PVSA_CPU0_PHASE_SW    L4C2             1        INDUCTOR_SM-0.3UH,IND,D92183-0A
VR_PVSA_CPU0_PWM         EU4C1            34       IR354XX_SM-IR35412,IC,H73684-0A
VR_PVSA_CPU0_PWM         EU4D4            1        PXE1610B_QFN-IC,H79206-001
VR_PVSA_CPU0_VCIN        C4C6             1        CAP_0402-1.0UF,16V,10%,X6S,D97A
VR_PVSA_CPU0_VCIN        EU4C1            3        IR354XX_SM-IR35412,IC,H73684-0A
VR_PVSA_CPU0_VCIN        R6N3             1        RES_0402-1.0,1%,1/16W,CHIP,G21A
VR_PVSA_CPU1_BIREF1      CTI57            1        CAP_A_0402V-0.1UF,16V,10%,X7R,A
VR_PVSA_CPU1_BIREF1      EU1C1            39       IR354XX_SM-IR35412,IC,H73684-0A
VR_PVSA_CPU1_BIREF1      EU1C2            37       PXE1610B_QFN-IC,H79206-001
VR_PVSA_CPU1_BIREF1      R9N5             2        RES_0402-0.0,5%,1/16W,CHIP,G21A
VR_PVSA_CPU1_BOOT        C1C12            1        CAP_0402-0.220UF,16V,10%,X7R,AA
VR_PVSA_CPU1_BOOT        RTI37            1        2D2R2F-GP_SMD-RG1-2D2R2F-GP,64A
VR_PVSA_CPU1_BOOT_R      EU1C1            33       IR354XX_SM-IR35412,IC,H73684-0A
VR_PVSA_CPU1_BOOT_R      RTI37            2        2D2R2F-GP_SMD-RG1-2D2R2F-GP,64A
VR_PVSA_CPU1_OCSET       EU1C1            37       IR354XX_SM-IR35412,IC,H73684-0A
VR_PVSA_CPU1_OCSET       R1C37            1        RES_0402-68.1K,1%,1/16W,EMPTY,A
VR_PVSA_CPU1_PHASE       C1C12            2        CAP_0402-0.220UF,16V,10%,X7R,AA
VR_PVSA_CPU1_PHASE       EU1C1            32       IR354XX_SM-IR35412,IC,H73684-0A
VR_PVSA_CPU1_PHASE_SW    CTI56            1        SC2K2P50V3KX-GP_SMD-BCG6-SC2K2A
VR_PVSA_CPU1_PHASE_SW    EU1C1            10       IR354XX_SM-IR35412,IC,H73684-0A
VR_PVSA_CPU1_PHASE_SW    L1C1             1        INDUCTOR_SM-0.3UH,IND,D92183-0A
VR_PVSA_CPU1_PWM         EU1C1            34       IR354XX_SM-IR35412,IC,H73684-0A
VR_PVSA_CPU1_PWM         EU1C2            1        PXE1610B_QFN-IC,H79206-001
VR_PVSA_CPU1_VCIN        C1C5             1        CAP_0402-1.0UF,16V,10%,X6S,D97A
VR_PVSA_CPU1_VCIN        EU1C1            3        IR354XX_SM-IR35412,IC,H73684-0A
VR_PVSA_CPU1_VCIN        R9N3             1        RES_0402-1.0,1%,1/16W,CHIP,G21A
VR_PVTT_ABC_BIAS         C4G15            1        CAP_0402-1.0UF,16V,10%,X6S,D97A
VR_PVTT_ABC_BIAS         EU4G3            2        MIC5166_DFN-IC,H55101-001
VR_PVTT_ABC_BIAS         R6U4             2        RES_0402-0.0,5%,1/16W,CHIP,G21A
VR_PVTT_ABC_SNS          EU4G3            6        MIC5166_DFN-IC,H55101-001
VR_PVTT_ABC_SNS          SH5U1            1        SHUNT_SH0201-EMPTY,N_A
VR_PVTT_ABC_VREF         C4G16            1        CAP_0402-1.0UF,16V,10%,X6S,D97A
VR_PVTT_ABC_VREF         EU4G3            1        MIC5166_DFN-IC,H55101-001
VR_PVTT_DEF_BIAS         C4A10            1        CAP_0402-1.0UF,16V,10%,X6S,D97A
VR_PVTT_DEF_BIAS         EU4A1            2        MIC5166_DFN-IC,H55101-001
VR_PVTT_DEF_BIAS         R6L11            2        RES_0402-0.0,5%,1/16W,CHIP,G21A
VR_PVTT_DEF_SNS          EU4A1            6        MIC5166_DFN-IC,H55101-001
VR_PVTT_DEF_SNS          SH5L1            1        SHUNT_SH0201-EMPTY,N_A
VR_PVTT_DEF_VREF         C4A9             1        CAP_0402-1.0UF,16V,10%,X6S,D97A
VR_PVTT_DEF_VREF         EU4A1            1        MIC5166_DFN-IC,H55101-001
VR_PVTT_GHJ_BIAS         C4G18            1        CAP_0402-1.0UF,16V,10%,X6S,D97A
VR_PVTT_GHJ_BIAS         EU4G2            2        MIC5166_DFN-IC,H55101-001
VR_PVTT_GHJ_BIAS         R6U7             2        RES_0402-0.0,5%,1/16W,CHIP,G21A
VR_PVTT_GHJ_SNS          EU4G2            6        MIC5166_DFN-IC,H55101-001
VR_PVTT_GHJ_SNS          SH8U1            1        SHUNT_SH0201-EMPTY,N_A
VR_PVTT_GHJ_VREF         C4G21            1        CAP_0402-1.0UF,16V,10%,X6S,D97A
VR_PVTT_GHJ_VREF         EU4G2            1        MIC5166_DFN-IC,H55101-001
VR_PVTT_KLM_BIAS         C4A8             1        CAP_0402-1.0UF,16V,10%,X6S,D97A
VR_PVTT_KLM_BIAS         EU4A2            2        MIC5166_DFN-IC,H55101-001
VR_PVTT_KLM_BIAS         R6L8             2        RES_0402-0.0,5%,1/16W,CHIP,G21A
VR_PVTT_KLM_SNS          EU4A2            6        MIC5166_DFN-IC,H55101-001
VR_PVTT_KLM_SNS          SH8L1            1        SHUNT_SH0201-EMPTY,N_A
VR_PVTT_KLM_VREF         C4A14            1        CAP_0402-1.0UF,16V,10%,X6S,D97A
VR_PVTT_KLM_VREF         EU4A2            1        MIC5166_DFN-IC,H55101-001
VR_VB_PVPP_ABC           C3T11            1        CAP_0603-4.7UF,6.3V,10%,X6S,E1A
VR_VB_PVPP_ABC           EU7F1            38       NCP3232L_SM-IC,H86355-001
VR_VB_PVPP_DEF           C3M10            1        CAP_0603-4.7UF,6.3V,10%,X6S,E1A
VR_VB_PVPP_DEF           EU7B1            38       NCP3232L_SM-IC,H86355-001
VR_VB_PVPP_GHJ           C6U6             1        CAP_0603-4.7UF,6.3V,10%,X6S,E1A
VR_VB_PVPP_GHJ           EU4G1            38       NCP3232L_SM-IC,H86355-001
VR_VB_PVPP_KLM           C6L12            1        CAP_0603-4.7UF,6.3V,10%,X6S,E1A
VR_VB_PVPP_KLM           EU4A3            38       NCP3232L_SM-IC,H86355-001
VR_VRRDY_PVCCIN_CPU0     C4D42            1        CAP_0402LF-1000PF,50V,10%,X7R,A
VR_VRRDY_PVCCIN_CPU0     EU4D4            11       PXE1610B_QFN-IC,H79206-001
VR_VRRDY_PVCCIN_CPU0     R4D58            2        RES_0402-1.00K,1%,1/16W,CHIP,GA
VR_VRRDY_PVCCIN_CPU0     R4D63            1        RES_0402-22.1,1.0%,1/16W,CHIP,A
VR_VRRDY_PVCCIN_CPU1     C1C23            1        CAP_0402LF-1000PF,50V,10%,X7R,A
VR_VRRDY_PVCCIN_CPU1     EU1C2            11       PXE1610B_QFN-IC,H79206-001
VR_VRRDY_PVCCIN_CPU1     R1C28            2        RES_0402-1.00K,1%,1/16W,CHIP,GA
VR_VRRDY_PVCCIN_CPU1     R1C30            1        RES_0402-22.1,1.0%,1/16W,CHIP,A
VSENSE_P12V_ADM1085      R3P48            2        RES_0402-90.9K,1%,1/16W,CHIP,GA
VSENSE_P12V_ADM1085      R3P51            1        RES_0402-6.34K,1%,1/16W,CHIP,GA
VSENSE_P12V_ADM1085      U7D3             3        ADM1085_SMT-IC,H46130-001
VSENSE_P1V05_PCH_STBY_AVSN C2L2             2        CAP_0402LF-220PF,50V,10%,X7R,AA
VSENSE_P1V05_PCH_STBY_AVSN EU8A1            30       PXE1110B_QFN-IC,H89187-001
VSENSE_P1V05_PCH_STBY_AVSN R8B12            1        RES_0402-0.0,5%,1/16W,CHIP,G21A
VSENSE_P1V05_PCH_STBY_AVSN R8B15            2        RES_0402-100.0,1%,1/16W,EMPTY,A
VSENSE_P1V05_PCH_STBY_AVSP R2L8             1        RES_0603-10.0,1%,1/10W,CHIP,G2A
VSENSE_P1V05_PCH_STBY_AVSP R8B14            1        RES_0402-0.0,5%,1/16W,CHIP,G21A
VSENSE_P1V05_PCH_STBY_AVSP R8B15            1        RES_0402-100.0,1%,1/16W,EMPTY,A
VSENSE_P1V8MCP_CPU0_SKT_VRTN J6E1             D2       SCONN120_H61426002_SM-CONN,H61A
VSENSE_P1V8MCP_CPU0_SKT_VRTN U5D1             AL20     SKX_EXT_B_BGA1-IC,TBD
VSENSE_P1V8MCP_CPU0_SKT_VSEN J6E1             D1       SCONN120_H61426002_SM-CONN,H61A
VSENSE_P1V8MCP_CPU0_SKT_VSEN U5D1             AK21     SKX_EXT_B_BGA1-IC,TBD
VSENSE_P1V8MCP_CPU1_SKT_VRTN J4E1             D2       SCONN120_H61426002_SM-CONN,H61A
VSENSE_P1V8MCP_CPU1_SKT_VRTN U2D1             AL20     SKX_EXT_B_BGA1-IC,TBD
VSENSE_P1V8MCP_CPU1_SKT_VSEN J4E1             D1       SCONN120_H61426002_SM-CONN,H61A
VSENSE_P1V8MCP_CPU1_SKT_VSEN U2D1             AK21     SKX_EXT_B_BGA1-IC,TBD
VSENSE_P3V3_STBY         R8E25            2        RES_0402-0.0,5%,1/16W,CHIP,G21A
VSENSE_P3V3_STBY         R8E31            1        RES_0402-23.2K,1%,1/16W,CHIP,GA
VSENSE_PMAX_CPU0         R5D5             1        RES_0402-249,0.1%,1/16W,CHIP,GA
VSENSE_PMAX_CPU0         R5D6             2        RES_0402-10.0,1%,1/16W,EMPTY,GA
VSENSE_PMAX_CPU0         U5D1             AD41     SKX_EXT_B_BGA1-IC,TBD
VSENSE_PMAX_CPU1         R3D27            1        RES_0402-249,0.1%,1/16W,CHIP,GA
VSENSE_PMAX_CPU1         R3D32            2        RES_0402-10.0,1%,1/16W,EMPTY,GA
VSENSE_PMAX_CPU1         U2D1             AD41     SKX_EXT_B_BGA1-IC,TBD
VSENSE_PVCCIN_CPU0_AVSP  C4D45            1        CAP_0402LF-220PF,50V,10%,X7R,AA
VSENSE_PVCCIN_CPU0_AVSP  EU4D4            21       PXE1610B_QFN-IC,H79206-001
VSENSE_PVCCIN_CPU0_AVSP  R4E8             2        RES_0402-10.0,1%,1/16W,CHIP,G2A
VSENSE_PVCCIN_CPU0_N     C4D45            2        CAP_0402LF-220PF,50V,10%,X7R,AA
VSENSE_PVCCIN_CPU0_N     EU4D4            22       PXE1610B_QFN-IC,H79206-001
VSENSE_PVCCIN_CPU0_N     R4E15            2        RES_0402-1.00K,1%,1/16W,EMPTY,A
VSENSE_PVCCIN_CPU0_N     R4E17            1        RES_0402-0.0,5%,1/16W,CHIP,G21A
VSENSE_PVCCIN_CPU0_N     R4E18            1        RES_0402-100.0,1%,1/16W,CHIP,GA
VSENSE_PVCCIN_CPU0_P     R4E8             1        RES_0402-10.0,1%,1/16W,CHIP,G2A
VSENSE_PVCCIN_CPU0_P     R4E14            1        RES_0402-100.0,1%,1/16W,CHIP,GA
VSENSE_PVCCIN_CPU0_P     R4E15            1        RES_0402-1.00K,1%,1/16W,EMPTY,A
VSENSE_PVCCIN_CPU0_P     R4E16            1        RES_0402-0.0,5%,1/16W,CHIP,G21A
VSENSE_PVCCIN_CPU0_SKT_VRTN R4E17            2        RES_0402-0.0,5%,1/16W,CHIP,G21A
VSENSE_PVCCIN_CPU0_SKT_VRTN U5D1             AY85     SKX_EXT_B_BGA1-IC,TBD
VSENSE_PVCCIN_CPU0_SKT_VSEN R4E16            2        RES_0402-0.0,5%,1/16W,CHIP,G21A
VSENSE_PVCCIN_CPU0_SKT_VSEN U5D1             BA86     SKX_EXT_B_BGA1-IC,TBD
VSENSE_PVCCIN_CPU1_AVSP  C1D1             1        CAP_0402LF-220PF,50V,10%,X7R,AA
VSENSE_PVCCIN_CPU1_AVSP  EU1C2            21       PXE1610B_QFN-IC,H79206-001
VSENSE_PVCCIN_CPU1_AVSP  R1D4             2        RES_0402-10.0,1%,1/16W,CHIP,G2A
VSENSE_PVCCIN_CPU1_N     C1D1             2        CAP_0402LF-220PF,50V,10%,X7R,AA
VSENSE_PVCCIN_CPU1_N     EU1C2            22       PXE1610B_QFN-IC,H79206-001
VSENSE_PVCCIN_CPU1_N     R1E5             2        RES_0402-1.00K,1%,1/16W,EMPTY,A
VSENSE_PVCCIN_CPU1_N     R1E7             1        RES_0402-0.0,5%,1/16W,CHIP,G21A
VSENSE_PVCCIN_CPU1_N     R1E8             1        RES_0402-100.0,1%,1/16W,CHIP,GA
VSENSE_PVCCIN_CPU1_P     R1D4             1        RES_0402-10.0,1%,1/16W,CHIP,G2A
VSENSE_PVCCIN_CPU1_P     R1E4             1        RES_0402-100.0,1%,1/16W,CHIP,GA
VSENSE_PVCCIN_CPU1_P     R1E5             1        RES_0402-1.00K,1%,1/16W,EMPTY,A
VSENSE_PVCCIN_CPU1_P     R1E6             1        RES_0402-0.0,5%,1/16W,CHIP,G21A
VSENSE_PVCCIN_CPU1_SKT_VRTN R1E7             2        RES_0402-0.0,5%,1/16W,CHIP,G21A
VSENSE_PVCCIN_CPU1_SKT_VRTN U2D1             AY85     SKX_EXT_B_BGA1-IC,TBD
VSENSE_PVCCIN_CPU1_SKT_VSEN R1E6             2        RES_0402-0.0,5%,1/16W,CHIP,G21A
VSENSE_PVCCIN_CPU1_SKT_VSEN U2D1             BA86     SKX_EXT_B_BGA1-IC,TBD
VSENSE_PVCCIOMCP_CPU0_SKT_VRTN J6B1             F8       SCONN120_H61426002_SM-CONN,H61A
VSENSE_PVCCIOMCP_CPU0_SKT_VRTN U5D1             BU16     SKX_EXT_B_BGA1-IC,TBD
VSENSE_PVCCIOMCP_CPU0_SKT_VSEN J6B1             E8       SCONN120_H61426002_SM-CONN,H61A
VSENSE_PVCCIOMCP_CPU0_SKT_VSEN U5D1             BT17     SKX_EXT_B_BGA1-IC,TBD
VSENSE_PVCCIOMCP_CPU1_SKT_VRTN J4B2             F8       SCONN120_H61426002_SM-CONN,H61A
VSENSE_PVCCIOMCP_CPU1_SKT_VRTN U2D1             BU16     SKX_EXT_B_BGA1-IC,TBD
VSENSE_PVCCIOMCP_CPU1_SKT_VSEN J4B2             E8       SCONN120_H61426002_SM-CONN,H61A
VSENSE_PVCCIOMCP_CPU1_SKT_VSEN U2D1             BT17     SKX_EXT_B_BGA1-IC,TBD
VSENSE_PVCCIO_CPU0_AVSN  C3N39            2        CAP_0402LF-220PF,50V,10%,X7R,AA
VSENSE_PVCCIO_CPU0_AVSN  EU3P1            20       PXE1110B_QFN-IC,H89187-001
VSENSE_PVCCIO_CPU0_AVSN  R3N20            1        RES_0402-100.0,1%,1/16W,CHIP,GA
VSENSE_PVCCIO_CPU0_AVSN  SH3P2            2        SHUNT_SH0201-EMPTY,N_A
VSENSE_PVCCIO_CPU0_AVSP  R3N19            1        RES_0402-10.0,1%,1/16W,CHIP,G2A
VSENSE_PVCCIO_CPU0_AVSP  R3N21            1        RES_0402-100.0,1%,1/16W,CHIP,GA
VSENSE_PVCCIO_CPU0_AVSP  SH3P1            2        SHUNT_SH0201-EMPTY,N_A
VSENSE_PVCCIO_CPU0_SKT_VRTN C3P1             2        CAP_A_0402V-0.1UF,16V,10%,EMPTA
VSENSE_PVCCIO_CPU0_SKT_VRTN SH3P2            1        SHUNT_SH0201-EMPTY,N_A
VSENSE_PVCCIO_CPU0_SKT_VRTN U5D1             BF5      SKX_EXT_B_BGA1-IC,TBD
VSENSE_PVCCIO_CPU0_SKT_VSEN C3P1             1        CAP_A_0402V-0.1UF,16V,10%,EMPTA
VSENSE_PVCCIO_CPU0_SKT_VSEN SH3P1            1        SHUNT_SH0201-EMPTY,N_A
VSENSE_PVCCIO_CPU0_SKT_VSEN U5D1             BH5      SKX_EXT_B_BGA1-IC,TBD
VSENSE_PVCCIO_CPU1_AVSN  C4D44            2        CAP_0402LF-220PF,50V,10%,X7R,AA
VSENSE_PVCCIO_CPU1_AVSN  EU4D5            20       PXE1110B_QFN-IC,H89187-001
VSENSE_PVCCIO_CPU1_AVSN  R3D28            1        RES_0402-100.0,1%,1/16W,CHIP,GA
VSENSE_PVCCIO_CPU1_AVSN  SH3D1            2        SHUNT_SH0201-EMPTY,N_A
VSENSE_PVCCIO_CPU1_AVSP  R3E1             1        RES_0402-100.0,1%,1/16W,CHIP,GA
VSENSE_PVCCIO_CPU1_AVSP  R4E7             1        RES_0402-10.0,1%,1/16W,CHIP,G2A
VSENSE_PVCCIO_CPU1_AVSP  SH3D2            2        SHUNT_SH0201-EMPTY,N_A
VSENSE_PVCCIO_CPU1_SKT_VRTN C3D27            2        CAP_A_0402V-0.1UF,16V,10%,EMPTA
VSENSE_PVCCIO_CPU1_SKT_VRTN SH3D1            1        SHUNT_SH0201-EMPTY,N_A
VSENSE_PVCCIO_CPU1_SKT_VRTN U2D1             BF5      SKX_EXT_B_BGA1-IC,TBD
VSENSE_PVCCIO_CPU1_SKT_VSEN C3D27            1        CAP_A_0402V-0.1UF,16V,10%,EMPTA
VSENSE_PVCCIO_CPU1_SKT_VSEN SH3D2            1        SHUNT_SH0201-EMPTY,N_A
VSENSE_PVCCIO_CPU1_SKT_VSEN U2D1             BH5      SKX_EXT_B_BGA1-IC,TBD
VSENSE_PVCCMCP_CPU0_SKT_VRTN J6E1             B4       SCONN120_H61426002_SM-CONN,H61A
VSENSE_PVCCMCP_CPU0_SKT_VRTN U5D1             BL16     SKX_EXT_B_BGA1-IC,TBD
VSENSE_PVCCMCP_CPU0_SKT_VSEN J6E1             A4       SCONN120_H61426002_SM-CONN,H61A
VSENSE_PVCCMCP_CPU0_SKT_VSEN U5D1             BN16     SKX_EXT_B_BGA1-IC,TBD
VSENSE_PVCCMCP_CPU1_SKT_VRTN J4E1             B4       SCONN120_H61426002_SM-CONN,H61A
VSENSE_PVCCMCP_CPU1_SKT_VRTN U2D1             BL16     SKX_EXT_B_BGA1-IC,TBD
VSENSE_PVCCMCP_CPU1_SKT_VSEN J4E1             A4       SCONN120_H61426002_SM-CONN,H61A
VSENSE_PVCCMCP_CPU1_SKT_VSEN U2D1             BN16     SKX_EXT_B_BGA1-IC,TBD
VSENSE_PVDDQ_ABC_N       C7G4             2        CAP_0402LF-220PF,50V,10%,X7R,AA
VSENSE_PVDDQ_ABC_N       EU7G1            20       PXM1310B_QFN-IC,H89186-001
VSENSE_PVDDQ_ABC_N       R4U6             2        RES_0402-100.0,1%,1/16W,EMPTY,A
VSENSE_PVDDQ_ABC_N       SH4U1            1        SHUNT_SH0201-EMPTY,N_A
VSENSE_PVDDQ_ABC_P       R4U6             1        RES_0402-100.0,1%,1/16W,EMPTY,A
VSENSE_PVDDQ_ABC_P       R7G9             1        RES_0402-10.0,1%,1/16W,CHIP,G2A
VSENSE_PVDDQ_ABC_P       SH4U2            1        SHUNT_SH0201-EMPTY,N_A
VSENSE_PVDDQ_ABC_VTT     C6U12            1        CAP_0603-4.7UF,6.3V,10%,X6S,E1A
VSENSE_PVDDQ_ABC_VTT     EU4G3            4        MIC5166_DFN-IC,H55101-001
VSENSE_PVDDQ_ABC_VTT     R6U5             2        RES_0402-0.0,5%,1/16W,CHIP,G21A
VSENSE_PVDDQ_DEF_N       C7A28            2        CAP_0402LF-220PF,50V,10%,X7R,AA
VSENSE_PVDDQ_DEF_N       EU7A5            20       PXM1310B_QFN-IC,H89186-001
VSENSE_PVDDQ_DEF_N       R4L2             2        RES_0402-100.0,1%,1/16W,EMPTY,A
VSENSE_PVDDQ_DEF_N       SH4L1            1        SHUNT_SH0201-EMPTY,N_A
VSENSE_PVDDQ_DEF_P       R4L2             1        RES_0402-100.0,1%,1/16W,EMPTY,A
VSENSE_PVDDQ_DEF_P       R7A7             1        RES_0402-10.0,1%,1/16W,CHIP,G2A
VSENSE_PVDDQ_DEF_P       SH4L2            1        SHUNT_SH0201-EMPTY,N_A
VSENSE_PVDDQ_DEF_VTT     C4A11            1        CAP_0603-4.7UF,6.3V,10%,X6S,E1A
VSENSE_PVDDQ_DEF_VTT     EU4A1            4        MIC5166_DFN-IC,H55101-001
VSENSE_PVDDQ_DEF_VTT     R6L10            2        RES_0402-0.0,5%,1/16W,CHIP,G21A
VSENSE_PVDDQ_GHJ_N       C1G16            2        CAP_0402LF-220PF,50V,10%,X7R,AA
VSENSE_PVDDQ_GHJ_N       EU1G2            20       PXM1310B_QFN-IC,H89186-001
VSENSE_PVDDQ_GHJ_N       R7U2             2        RES_0402-100.0,1%,1/16W,EMPTY,A
VSENSE_PVDDQ_GHJ_N       SH7U2            1        SHUNT_SH0201-EMPTY,N_A
VSENSE_PVDDQ_GHJ_P       R1G5             1        RES_0402-10.0,1%,1/16W,CHIP,G2A
VSENSE_PVDDQ_GHJ_P       R7U2             1        RES_0402-100.0,1%,1/16W,EMPTY,A
VSENSE_PVDDQ_GHJ_P       SH7U1            1        SHUNT_SH0201-EMPTY,N_A
VSENSE_PVDDQ_GHJ_VTT     C6U11            1        CAP_0603-4.7UF,6.3V,10%,X6S,E1A
VSENSE_PVDDQ_GHJ_VTT     EU4G2            4        MIC5166_DFN-IC,H55101-001
VSENSE_PVDDQ_GHJ_VTT     R6U6             2        RES_0402-0.0,5%,1/16W,CHIP,G21A
VSENSE_PVDDQ_KLM_N       C1B12            2        CAP_0402LF-220PF,50V,10%,X7R,AA
VSENSE_PVDDQ_KLM_N       EU1B1            20       PXM1310B_QFN-IC,H89186-001
VSENSE_PVDDQ_KLM_N       R7L2             2        RES_0402-100.0,1%,1/16W,EMPTY,A
VSENSE_PVDDQ_KLM_N       SH7L1            1        SHUNT_SH0201-EMPTY,N_A
VSENSE_PVDDQ_KLM_P       R1B16            1        RES_0402-10.0,1%,1/16W,CHIP,G2A
VSENSE_PVDDQ_KLM_P       R7L2             1        RES_0402-100.0,1%,1/16W,EMPTY,A
VSENSE_PVDDQ_KLM_P       SH7L2            1        SHUNT_SH0201-EMPTY,N_A
VSENSE_PVDDQ_KLM_VTT     C4A7             1        CAP_0603-4.7UF,6.3V,10%,X6S,E1A
VSENSE_PVDDQ_KLM_VTT     EU4A2            4        MIC5166_DFN-IC,H55101-001
VSENSE_PVDDQ_KLM_VTT     R6L6             2        RES_0402-0.0,5%,1/16W,CHIP,G21A
VSENSE_PVNN_PCH_STBY_AVSN C8A2             2        CAP_0402LF-220PF,50V,10%,X7R,AA
VSENSE_PVNN_PCH_STBY_AVSN EU8A1            20       PXE1110B_QFN-IC,H89187-001
VSENSE_PVNN_PCH_STBY_AVSN R7A18            2        RES_0402-0.0,5%,1/16W,CHIP,G21A
VSENSE_PVNN_PCH_STBY_AVSP R7A13            1        RES_0402-100.0,1%,1/16W,CHIP,GA
VSENSE_PVNN_PCH_STBY_AVSP R7A14            2        RES_0402-10.0,1%,1/16W,CHIP,G2A
VSENSE_PVNN_PCH_STBY_AVSP R7A19            2        RES_0402-10.0,1%,1/16W,CHIP,G2A
VSENSE_PVNN_PCH_STBY_AVSP R8A1             1        RES_0402-10.0,1%,1/16W,CHIP,G2A
VSENSE_PVNN_PCH_STBY_FPK R7A14            1        RES_0402-10.0,1%,1/16W,CHIP,G2A
VSENSE_PVNN_PCH_STBY_FPK U7C1             AK36     LBG_CORE_QAT_EXT_D_BGA1-IC,H91A
VSENSE_PVNN_PCH_STBY_QAT R7A19            1        RES_0402-10.0,1%,1/16W,CHIP,G2A
VSENSE_PVNN_PCH_STBY_QAT U7C1             V37      LBG_CORE_QAT_EXT_D_BGA1-IC,H91A
VSENSE_PVPP_ABC          R7F12            2        RES_0402-0.0,5%,1/16W,CHIP,G21A
VSENSE_PVPP_ABC          R7F13            1        RES_0402-20.0K,1%,1/16W,CHIP,GA
VSENSE_PVPP_ABC          R7F17            1        RES_0402-1.0K,0.1%,1/16W,CHIP,A
VSENSE_PVPP_DEF          R7B11            2        RES_0402-0.0,5%,1/16W,CHIP,G21A
VSENSE_PVPP_DEF          R7B15            1        RES_0402-20.0K,1%,1/16W,CHIP,GA
VSENSE_PVPP_DEF          R7B18            1        RES_0402-1.0K,0.1%,1/16W,CHIP,A
VSENSE_PVPP_GHJ          R4G7             1        RES_0402-20.0K,1%,1/16W,CHIP,GA
VSENSE_PVPP_GHJ          R4G8             2        RES_0402-0.0,5%,1/16W,CHIP,G21A
VSENSE_PVPP_GHJ          R4G10            1        RES_0402-1.0K,0.1%,1/16W,CHIP,A
VSENSE_PVPP_KLM          R4B3             2        RES_0402-0.0,5%,1/16W,CHIP,G21A
VSENSE_PVPP_KLM          R4B5             1        RES_0402-20.0K,1%,1/16W,CHIP,GA
VSENSE_PVPP_KLM          R4B9             1        RES_0402-1.0K,0.1%,1/16W,CHIP,A
VSENSE_PVSA_CPU0_BVSP    C4D29            1        CAP_0402LF-220PF,50V,10%,X7R,AA
VSENSE_PVSA_CPU0_BVSP    EU4D4            35       PXE1610B_QFN-IC,H79206-001
VSENSE_PVSA_CPU0_BVSP    R4D39            2        RES_0402-10.0,1%,1/16W,CHIP,G2A
VSENSE_PVSA_CPU0_N       C4D29            2        CAP_0402LF-220PF,50V,10%,X7R,AA
VSENSE_PVSA_CPU0_N       EU4D4            36       PXE1610B_QFN-IC,H79206-001
VSENSE_PVSA_CPU0_N       R4C1             1        RES_0402-100.0,1%,1/16W,CHIP,GA
VSENSE_PVSA_CPU0_N       R4C2             1        RES_0402-0.0,5%,1/16W,CHIP,G21A
VSENSE_PVSA_CPU0_N       R4C3             2        RES_0402-1.00K,1%,1/16W,EMPTY,A
VSENSE_PVSA_CPU0_P       R4C3             1        RES_0402-1.00K,1%,1/16W,EMPTY,A
VSENSE_PVSA_CPU0_P       R4C4             1        RES_0402-0.0,5%,1/16W,CHIP,G21A
VSENSE_PVSA_CPU0_P       R4C5             1        RES_0402-100.0,1%,1/16W,CHIP,GA
VSENSE_PVSA_CPU0_P       R4D39            1        RES_0402-10.0,1%,1/16W,CHIP,G2A
VSENSE_PVSA_CPU0_SKT_VRTN R4C2             2        RES_0402-0.0,5%,1/16W,CHIP,G21A
VSENSE_PVSA_CPU0_SKT_VRTN U5D1             CG76     SKX_EXT_B_BGA1-IC,TBD
VSENSE_PVSA_CPU0_SKT_VSEN R4C4             2        RES_0402-0.0,5%,1/16W,CHIP,G21A
VSENSE_PVSA_CPU0_SKT_VSEN U5D1             CE76     SKX_EXT_B_BGA1-IC,TBD
VSENSE_PVSA_CPU1_BVSP    C1C16            1        CAP_0402LF-220PF,50V,10%,X7R,AA
VSENSE_PVSA_CPU1_BVSP    EU1C2            35       PXE1610B_QFN-IC,H79206-001
VSENSE_PVSA_CPU1_BVSP    R1C21            2        RES_0402-10.0,1%,1/16W,CHIP,G2A
VSENSE_PVSA_CPU1_N       C1C16            2        CAP_0402LF-220PF,50V,10%,X7R,AA
VSENSE_PVSA_CPU1_N       EU1C2            36       PXE1610B_QFN-IC,H79206-001
VSENSE_PVSA_CPU1_N       R1C4             1        RES_0402-100.0,1%,1/16W,CHIP,GA
VSENSE_PVSA_CPU1_N       R1C5             1        RES_0402-0.0,5%,1/16W,CHIP,G21A
VSENSE_PVSA_CPU1_N       R1C6             2        RES_0402-1.00K,1%,1/16W,EMPTY,A
VSENSE_PVSA_CPU1_P       R1C6             1        RES_0402-1.00K,1%,1/16W,EMPTY,A
VSENSE_PVSA_CPU1_P       R1C7             1        RES_0402-0.0,5%,1/16W,CHIP,G21A
VSENSE_PVSA_CPU1_P       R1C12            1        RES_0402-100.0,1%,1/16W,CHIP,GA
VSENSE_PVSA_CPU1_P       R1C21            1        RES_0402-10.0,1%,1/16W,CHIP,G2A
VSENSE_PVSA_CPU1_SKT_VRTN R1C5             2        RES_0402-0.0,5%,1/16W,CHIP,G21A
VSENSE_PVSA_CPU1_SKT_VRTN U2D1             CG76     SKX_EXT_B_BGA1-IC,TBD
VSENSE_PVSA_CPU1_SKT_VSEN R1C7             2        RES_0402-0.0,5%,1/16W,CHIP,G21A
VSENSE_PVSA_CPU1_SKT_VSEN U2D1             CE76     SKX_EXT_B_BGA1-IC,TBD
VSENSE_RGND_P3V3_STBY    EU8F1            7        RT8240_QFN-IC,H66262-001
VSENSE_RGND_P3V3_STBY    R8E38            1        RES_0402-0.0,5%,1/16W,CHIP,G21A
VSENSE_VCCINR2PMAX_CPU0  R5P1             2        RES_0603-100.0K,1%,1/10W,CHIP,A
VSENSE_VCCINR2PMAX_CPU0  U5D1             AV85     SKX_EXT_B_BGA1-IC,TBD
VSENSE_VCCINR2PMAX_CPU0  U5D1             AW86     SKX_EXT_B_BGA1-IC,TBD
VSENSE_VCCINR2PMAX_CPU1  RT8P1            2        RES_0603-100.0K,1%,1/10W,CHIP,A
VSENSE_VCCINR2PMAX_CPU1  U2D1             AV85     SKX_EXT_B_BGA1-IC,TBD
VSENSE_VCCINR2PMAX_CPU1  U2D1             AW86     SKX_EXT_B_BGA1-IC,TBD
VSENSE_VOUT_P3V3_STBY    EU8F1            6        RT8240_QFN-IC,H66262-001
VSENSE_VOUT_P3V3_STBY    R8E31            2        RES_0402-23.2K,1%,1/16W,CHIP,GA
VSENSE_VOUT_P3V3_STBY    R8E34            1        RES_0402-10.0K,1%,1/16W,CHIP,GA
XDP_CPU0_TDO             R4P23            2        RES_0402-150.0,1%,1/16W,CHIP,GA
XDP_CPU0_TDO             U1M4             2        74CBTLV1G125_SMLF-IC,C88177-00A
XDP_CPU0_TDO             U1M7             1        NC7SB3157_SMLF-IC,C99406-001
XDP_CPU0_TDO             U5D1             AE14     SKX_EXT_B_BGA1-IC,TBD
XDP_CPU1_TDI             R6T6             2        RES_0402-150.0,1%,1/16W,CHIP,GA
XDP_CPU1_TDI             U1M4             4        74CBTLV1G125_SMLF-IC,C88177-00A
XDP_CPU1_TDI             U2D1             AC14     SKX_EXT_B_BGA1-IC,TBD
XDP_CPU1_TDO             R6T7             2        RES_0402-150.0,1%,1/16W,CHIP,GA
XDP_CPU1_TDO             U1M7             3        NC7SB3157_SMLF-IC,C99406-001
XDP_CPU1_TDO             U2D1             AE14     SKX_EXT_B_BGA1-IC,TBD
XDP_CPU_GTL_TCK_R2       Q9A1             1        NPN_DUAL_SSOPLF-MBT3904,EMPTY,A
XDP_CPU_GTL_TCK_R2       R9A2             2        RES_0402-33.2,1%,1/16W,EMPTY,GA
XDP_CPU_MBP0_N           R4P12            2        RES_0402-100.0,1%,1/16W,CHIP,GA
XDP_CPU_MBP0_N           R7P30            2        RES_0402-100.0,1%,1/16W,CHIP,GA
XDP_CPU_MBP0_N           U2D1             AJ10     SKX_EXT_B_BGA1-IC,TBD
XDP_CPU_MBP0_N           U5D1             AJ10     SKX_EXT_B_BGA1-IC,TBD
XDP_CPU_MBP1_N           R4P15            2        RES_0402-100.0,1%,1/16W,CHIP,GA
XDP_CPU_MBP1_N           R6P46            2        RES_0402-100.0,1%,1/16W,CHIP,GA
XDP_CPU_MBP1_N           U2D1             AH11     SKX_EXT_B_BGA1-IC,TBD
XDP_CPU_MBP1_N           U5D1             AH11     SKX_EXT_B_BGA1-IC,TBD
XDP_CPU_OBSFN_B0_MBP6_N  R6T8             2        RES_0402-100.0,1%,1/16W,CHIP,GA
XDP_CPU_OBSFN_B0_MBP6_N  U1L5             6        TTL3126_QFNLF-74CBTLV3126,IC,DB
XDP_CPU_OBSFN_B0_MBP6_N  U2D1             AE12     SKX_EXT_B_BGA1-IC,TBD
XDP_CPU_OBSFN_B0_MBP6_N  U5D1             AE12     SKX_EXT_B_BGA1-IC,TBD
XDP_CPU_OBSFN_B1_MBP7_N  R6T9             2        RES_0402-100.0,1%,1/16W,CHIP,GA
XDP_CPU_OBSFN_B1_MBP7_N  U1L5             3        TTL3126_QFNLF-74CBTLV3126,IC,DB
XDP_CPU_OBSFN_B1_MBP7_N  U2D1             AC12     SKX_EXT_B_BGA1-IC,TBD
XDP_CPU_OBSFN_B1_MBP7_N  U5D1             AC12     SKX_EXT_B_BGA1-IC,TBD
XDP_CPU_PRDY_N           R1M3             2        RES_0402-100.0,1%,1/16W,CHIP,GA
XDP_CPU_PRDY_N           U1L5             8        TTL3126_QFNLF-74CBTLV3126,IC,DB
XDP_CPU_PRDY_N           U2D1             AG16     SKX_EXT_B_BGA1-IC,TBD
XDP_CPU_PRDY_N           U5D1             AG16     SKX_EXT_B_BGA1-IC,TBD
XDP_CPU_PREQ_N           R1M4             2        RES_0402-100.0,1%,1/16W,CHIP,GA
XDP_CPU_PREQ_N           U1L5             11       TTL3126_QFNLF-74CBTLV3126,IC,DB
XDP_CPU_PREQ_N           U2D1             AR12     SKX_EXT_B_BGA1-IC,TBD
XDP_CPU_PREQ_N           U5D1             AR12     SKX_EXT_B_BGA1-IC,TBD
XDP_CPU_PWR_DEBUG_N      C9A4             1        CAP_A_0402V-0.1UF,16V,10%,X7R,A
XDP_CPU_PWR_DEBUG_N      J9A3             45       SCONN60_C21100002_SMLF-CONN,C2A
XDP_CPU_PWR_DEBUG_N      R1L17            1        RES_0402-150.0,1%,1/16W,CHIP,GA
XDP_CPU_PWR_DEBUG_N      U2D1             AP17     SKX_EXT_B_BGA1-IC,TBD
XDP_CPU_PWR_DEBUG_N      U5D1             AP17     SKX_EXT_B_BGA1-IC,TBD
XDP_CPU_PWR_DEBUG_N      U7D1             4        74CBTLV1G125_SMLF-IC,C88177-00A
XDP_CPU_TCK0             J9A3             57       SCONN60_C21100002_SMLF-CONN,C2A
XDP_CPU_TCK0             Q9A1             4        NPN_DUAL_SSOPLF-MBT3904,EMPTY,A
XDP_CPU_TCK0             R7P29            1        RES_0402-51.1,1.0%,1/16W,CHIP,A
XDP_CPU_TCK0             R9A3             2        RES_0402-0.0,5%,1/16W,CHIP,G21A
XDP_CPU_TCK0             U2D1             AA14     SKX_EXT_B_BGA1-IC,TBD
XDP_CPU_TCK0             U5D1             AA14     SKX_EXT_B_BGA1-IC,TBD
XDP_CPU_TCK_BUF          Q9A1             2        NPN_DUAL_SSOPLF-MBT3904,EMPTY,A
XDP_CPU_TCK_BUF          Q9A1             5        NPN_DUAL_SSOPLF-MBT3904,EMPTY,A
XDP_CPU_TCK_BUF          Q9A1             6        NPN_DUAL_SSOPLF-MBT3904,EMPTY,A
XDP_CPU_TCK_BUF          R9A1             2        RES_0402-1.00K,1%,1/16W,EMPTY,A
XDP_CPU_TDI              R4P24            2        RES_0402-150.0,1%,1/16W,CHIP,GA
XDP_CPU_TDI              U1L1             11       TTL3126_QFNLF-74CBTLV3126,IC,DB
XDP_CPU_TDI              U5D1             AC14     SKX_EXT_B_BGA1-IC,TBD
XDP_CPU_TDO              U1L1             8        TTL3126_QFNLF-74CBTLV3126,IC,DB
XDP_CPU_TDO              U1M7             4        NC7SB3157_SMLF-IC,C99406-001
XDP_CPU_TMS              R1L15            2        RES_0402-150.0,1%,1/16W,CHIP,GA
XDP_CPU_TMS              U1L1             6        TTL3126_QFNLF-74CBTLV3126,IC,DB
XDP_CPU_TMS              U2D1             W14      SKX_EXT_B_BGA1-IC,TBD
XDP_CPU_TMS              U5D1             W14      SKX_EXT_B_BGA1-IC,TBD
XDP_CPU_TRST_N           R6T5             1        RES_0402-1.00K,1%,1/16W,CHIP,GA
XDP_CPU_TRST_N           U1L1             3        TTL3126_QFNLF-74CBTLV3126,IC,DB
XDP_CPU_TRST_N           U2D1             Y13      SKX_EXT_B_BGA1-IC,TBD
XDP_CPU_TRST_N           U5D1             Y13      SKX_EXT_B_BGA1-IC,TBD
XDP_DEBUG_CONSENT_N      J9A3             1        SCONN60_C21100002_SMLF-CONN,C2A
XDP_DEBUG_CONSENT_N      R2P2             2        RES_0402-1.00K,1%,1/16W,CHIP,GA
XDP_ITP_PMODE            J9A3             46       SCONN60_C21100002_SMLF-CONN,C2A
XDP_ITP_PMODE            R9A17            1        RES_0402-1.00K,1%,1/16W,CHIP,GA
XDP_ITP_PMODE            U7C1             AR54     LBG_CORE_QAT_EXT_D_BGA1-IC,H91A
XDP_OBSFN_B0_MBP6_N      J9A3             22       SCONN60_C21100002_SMLF-CONN,C2A
XDP_OBSFN_B0_MBP6_N      U1L5             5        TTL3126_QFNLF-74CBTLV3126,IC,DB
XDP_OBSFN_B1_MBP7_N      J9A3             24       SCONN60_C21100002_SMLF-CONN,C2A
XDP_OBSFN_B1_MBP7_N      U1L5             2        TTL3126_QFNLF-74CBTLV3126,IC,DB
XDP_PCH_CPU_TCK0         R3M10            1        RES_0402-1.00K,1%,1/16W,CHIP,GA
XDP_PCH_CPU_TCK0         R9A2             1        RES_0402-33.2,1%,1/16W,EMPTY,GA
XDP_PCH_CPU_TCK0         R9A3             1        RES_0402-0.0,5%,1/16W,CHIP,G21A
XDP_PCH_CPU_TCK0         U7C1             AF54     LBG_CORE_QAT_EXT_D_BGA1-IC,H91A
XDP_PCH_PWR_DEBUG_N      R7C23            2        RES_0402-10.0K,1%,1/16W,CHIP,GA
XDP_PCH_PWR_DEBUG_N      U7C1             G15      LBG_CORE_QAT_EXT_D_BGA1-IC,H91A
XDP_PCH_PWR_DEBUG_N      U7D1             2        74CBTLV1G125_SMLF-IC,C88177-00A
XDP_PCH_TCK1             J9A3             55       SCONN60_C21100002_SMLF-CONN,C2A
XDP_PCH_TCK1             R8B1             1        RES_0402-51.1,1.0%,1/16W,CHIP,A
XDP_PCH_TCK1             U7C1             AL56     LBG_CORE_QAT_EXT_D_BGA1-IC,H91A
XDP_PRDY_N               J9A3             5        SCONN60_C21100002_SMLF-CONN,C2A
XDP_PRDY_N               R1L39            2        RES_0402-100.0,1%,1/16W,CHIP,GA
XDP_PRDY_N               U1L5             9        TTL3126_QFNLF-74CBTLV3126,IC,DB
XDP_PRDY_N               U7C1             AD54     LBG_CORE_QAT_EXT_D_BGA1-IC,H91A
XDP_PREQ_N               J9A3             3        SCONN60_C21100002_SMLF-CONN,C2A
XDP_PREQ_N               R1L41            2        RES_0402-100.0,1%,1/16W,CHIP,GA
XDP_PREQ_N               U1L5             12       TTL3126_QFNLF-74CBTLV3126,IC,DB
XDP_PREQ_N               U7C1             U54      LBG_CORE_QAT_EXT_D_BGA1-IC,H91A
XDP_PRESENT_N            J9A3             60       SCONN60_C21100002_SMLF-CONN,C2A
XDP_PRESENT_N            R9A4             1        RES_0402-475.0,1%,1/16W,CHIP,GA
XDP_PRESENT_N            U2D1             AV21     SKX_EXT_B_BGA1-IC,TBD
XDP_PRESENT_N            U5D1             AV21     SKX_EXT_B_BGA1-IC,TBD
XDP_PWRGD_RST_N          C1L8             1        CAP_A_0402V-0.1UF,16V,10%,X7R,A
XDP_PWRGD_RST_N          J9A3             41       SCONN60_C21100002_SMLF-CONN,C2A
XDP_PWRGD_RST_N          R1L23            1        RES_0402-1.00K,1%,1/16W,CHIP,GA
XDP_PWRGD_RST_N          U8D7             M11      LCMXO2_A_256BGA-IC,H63395-001
XDP_RSMRST_N             J9A3             39       SCONN60_C21100002_SMLF-CONN,C2A
XDP_RSMRST_N             R9A15            2        RES_0402-1.00K,1%,1/16W,CHIP,GA
XDP_RST_CO_N             C9A5             1        CAP_A_0402V-0.1UF,16V,10%,X7R,A
XDP_RST_CO_N             J9A3             48       SCONN60_C21100002_SMLF-CONN,C2A
XDP_RST_CO_N             R9A14            1        RES_0402-1.00K,1%,1/16W,CHIP,GA
XDP_RST_CO_N             U1L4             2        TTL1G07_A_SOP-74LVC1G07,IC,C88B
XDP_SPI_PCH_MOSI_BOOT_HALT_N J9A3             6        SCONN60_C21100002_SMLF-CONN,C2A
XDP_SPI_PCH_MOSI_BOOT_HALT_N R8E2             1        RES_0402-1.00K,1%,1/16W,CHIP,GA
XDP_SYSPWROK             C9A2             1        CAP_A_0402V-0.1UF,16V,10%,X7R,A
XDP_SYSPWROK             J9A3             47       SCONN60_C21100002_SMLF-CONN,C2A
XDP_SYSPWROK             R1L13            1        RES_0402-1.00K,1%,1/16W,CHIP,GA
XDP_SYSPWROK             U8D7             N11      LCMXO2_A_256BGA-IC,H63395-001
XDP_TDI                  J9A3             56       SCONN60_C21100002_SMLF-CONN,C2A
XDP_TDI                  R8A13            2        RES_0402-150.0,1%,1/16W,CHIP,GA
XDP_TDI                  U1L1             12       TTL3126_QFNLF-74CBTLV3126,IC,DB
XDP_TDI                  U7C1             AN54     LBG_CORE_QAT_EXT_D_BGA1-IC,H91A
XDP_TDO                  J9A3             52       SCONN60_C21100002_SMLF-CONN,C2A
XDP_TDO                  R9A11            2        RES_0402-150.0,1%,1/16W,CHIP,GA
XDP_TDO                  U1L1             9        TTL3126_QFNLF-74CBTLV3126,IC,DB
XDP_TDO                  U7C1             AP56     LBG_CORE_QAT_EXT_D_BGA1-IC,H91A
XDP_TMS                  J9A3             58       SCONN60_C21100002_SMLF-CONN,C2A
XDP_TMS                  R8A14            2        RES_0402-150.0,1%,1/16W,CHIP,GA
XDP_TMS                  U1L1             5        TTL3126_QFNLF-74CBTLV3126,IC,DB
XDP_TMS                  U7C1             AH54     LBG_CORE_QAT_EXT_D_BGA1-IC,H91A
XDP_TRST_N               J9A3             54       SCONN60_C21100002_SMLF-CONN,C2A
XDP_TRST_N               R8B2             1        RES_0402-1.00K,1%,1/16W,CHIP,GA
XDP_TRST_N               U1L1             2        TTL3126_QFNLF-74CBTLV3126,IC,DB
XDP_TRST_N               U7C1             AT56     LBG_CORE_QAT_EXT_D_BGA1-IC,H91A
XTAL_24MHZ_IN_R          EU9F3            9        PI7C9X1172_QFN-IC,H66899-001
XTAL_24MHZ_IN_R          R9F58            2        RES_0402-0.0,5%,1/16W,CHIP,G21A
XTAL_24MHZ_OUT_R         EU9F3            10       PI7C9X1172_QFN-IC,H66899-001
XTAL_24MHZ_OUT_R         R9F59            2        RES_0402-0.0,5%,1/16W,CHIP,G21A
XTAL_24MHZ_PI7C9X1172_IN C9F20            1        CAP_0402LF-12.0PF,50V,5%,COG,AA
XTAL_24MHZ_PI7C9X1172_IN R9F58            1        RES_0402-0.0,5%,1/16W,CHIP,G21A
XTAL_24MHZ_PI7C9X1172_IN Y9F1             1        CRYSTAL_SM-24.000MHZ,IC,D95126A
XTAL_24MHZ_PI7C9X1172_OUT C9F21            1        CAP_0402LF-12.0PF,50V,5%,COG,AA
XTAL_24MHZ_PI7C9X1172_OUT R9F59            1        RES_0402-0.0,5%,1/16W,CHIP,G21A
XTAL_24MHZ_PI7C9X1172_OUT Y9F1             2        CRYSTAL_SM-24.000MHZ,IC,D95126A
XTAL_25MHZ_IN            C9E9             1        CAP_0402LF-22.0PF,50V,5%,COG,AA
XTAL_25MHZ_IN            R9E20            1        RES_0402-0.0,5%,1/16W,CHIP,G21A
XTAL_25MHZ_IN            Y9E1             1        CRYSTAL_2013-25.000MHZ,IC,D717A
XTAL_25MHZ_IN_R          EU9E1            46       SPRINGVILLE_SM1-IC,G47144-004
XTAL_25MHZ_IN_R          R9E20            2        RES_0402-0.0,5%,1/16W,CHIP,G21A
XTAL_25MHZ_OUT           EU9E1            45       SPRINGVILLE_SM1-IC,G47144-004
XTAL_25MHZ_OUT           R9E18            2        RES_0402-0.0,5%,1/16W,CHIP,G21A
XTAL_25MHZ_OUT_R         C9E8             1        CAP_0402LF-22.0PF,50V,5%,COG,AA
XTAL_25MHZ_OUT_R         R9E18            1        RES_0402-0.0,5%,1/16W,CHIP,G21A
XTAL_25MHZ_OUT_R         Y9E1             3        CRYSTAL_2013-25.000MHZ,IC,D717A
XTAL_33K_RTC1            C7C13            1        CAP_0402LF-18PF,50V,5%,C0G,A36A
XTAL_33K_RTC1            R7C6             1        RES_0603-10M,1.0%,1/10W,CHIP,GA
XTAL_33K_RTC1            U7C1             K17      LBG_CORE_QAT_EXT_D_BGA1-IC,H91A
XTAL_33K_RTC1            Y7C2             1        CRYSTAL_SM-32.768KHZ,IC,C13544A
XTAL_33K_RTC2            C7C15            1        CAP_0402LF-18PF,50V,5%,C0G,A36A
XTAL_33K_RTC2            R7C6             2        RES_0603-10M,1.0%,1/10W,CHIP,GA
XTAL_33K_RTC2            U7C1             H17      LBG_CORE_QAT_EXT_D_BGA1-IC,H91A
XTAL_33K_RTC2            Y7C2             2        CRYSTAL_SM-32.768KHZ,IC,C13544A
XTAL_CK_MNG_IN           C8F18            1        CAP_0402LF-27.0PF,50V,5%,COG,AA
XTAL_CK_MNG_IN           EU8F2            19       ICS9FGP204_MLFP-IC,E95226-001
XTAL_CK_MNG_IN           Y8F1             1        CRYSTAL_2013LF-25.000MHZ,IC,D7B
XTAL_CK_MNG_OUT          C8F19            1        CAP_0402LF-27.0PF,50V,5%,COG,AA
XTAL_CK_MNG_OUT          EU8F2            20       ICS9FGP204_MLFP-IC,E95226-001
XTAL_CK_MNG_OUT          Y8F1             3        CRYSTAL_2013LF-25.000MHZ,IC,D7B
XTAL_KR_25M_IN           C8C1             1        CAP_0402LF-33.0PF,50V,5%,COG,AA
XTAL_KR_25M_IN           U7C1             BV16     LBG_CORE_QAT_EXT_D_BGA1-IC,H91A
XTAL_KR_25M_IN           Y8C1             1        CRYSTAL_2013-25.000MHZ,IC,H196A
XTAL_KR_25M_OUT          C8C2             1        CAP_0402LF-33.0PF,50V,5%,COG,AA
XTAL_KR_25M_OUT          U7C1             BY16     LBG_CORE_QAT_EXT_D_BGA1-IC,H91A
XTAL_KR_25M_OUT          Y8C1             3        CRYSTAL_2013-25.000MHZ,IC,H196A
XTAL_PCH_48M_IN          C7C4             1        CAP_0402LF-15.0PF,50V,5%,COG,AA
XTAL_PCH_48M_IN          R7C1             1        RES_0603-200K,0.1%,1/10W,CHIP,A
XTAL_PCH_48M_IN          U7C1             B35      LBG_CORE_QAT_EXT_D_BGA1-IC,H91A
XTAL_PCH_48M_IN          Y7C1             1        CRYSTAL_2013-48.000MHZ,IC,D717A
XTAL_PCH_48M_OUT         C7C5             1        CAP_0402LF-15.0PF,50V,5%,COG,AA
XTAL_PCH_48M_OUT         R7C1             2        RES_0603-200K,0.1%,1/10W,CHIP,A
XTAL_PCH_48M_OUT         U7C1             D35      LBG_CORE_QAT_EXT_D_BGA1-IC,H91A
XTAL_PCH_48M_OUT         Y7C1             3        CRYSTAL_2013-48.000MHZ,IC,D717A
END CONCISE NET LIST
